G04 ================== begin FILE IDENTIFICATION RECORD ==================*
G04 Layout Name:  E:/<user>/9332_F0TG_MB_C/brd/0417/9332_F0TG_MB_C_V02_0417_0820.brd*
G04 Film Name:    gnd6*
G04 File Format:  Gerber RS274X*
G04 File Origin:  Cadence Allegro 17.2-S081*
G04 Origin Date:  Wed Apr 19 14:50:10 2023*
G04 *
G04 Layer:  DRAWING FORMAT/TITLE_BLOCK_A*
G04 Layer:  PIN/SPECIAL_DRILL*
G04 Layer:  VIA CLASS/GND6*
G04 Layer:  PIN/GND6*
G04 Layer:  MANUFACTURING/PHOTOPLOT_OUTLINE*
G04 Layer:  ETCH/GND6*
G04 Layer:  DRAWING FORMAT/TITLE_BLOCK*
G04 Layer:  DRAWING FORMAT/TITLE_DATA_GND6*
G04 *
G04 Offset:    (0.00 0.00)*
G04 Mirror:    No*
G04 Mode:      Negative*
G04 Rotation:  0*
G04 FullContactRelief:  No*
G04 UndefLineWidth:     6.00*
G04 ================== end FILE IDENTIFICATION RECORD ====================*
%FSLAX25Y25*MOIN*%
%IR0*IPPOS*OFA0.00000B0.00000*MIA0B0*SFA1.00000B1.00000*%
%ADD14C,.03*%
%ADD41C,.06*%
%ADD30C,.024*%
%ADD68C,.052*%
%ADD25C,.061*%
%AMMACRO54*
4,1,36,0.0,.01,
-.001736,.009848,
-.00342,.009397,
-.005,.00866,
-.006428,.00766,
-.00766,.006428,
-.00866,.005,
-.009397,.00342,
-.009848,.001736,
-.01,0.0,
-.009848,-.001736,
-.009397,-.00342,
-.00866,-.005,
-.00766,-.006428,
-.006428,-.00766,
-.005,-.00866,
-.00342,-.009397,
-.001736,-.009848,
0.0,-.01,
.001736,-.009848,
.00342,-.009397,
.005,-.00866,
.006428,-.00766,
.00766,-.006428,
.00866,-.005,
.009397,-.00342,
.009848,-.001736,
.01,0.0,
.009848,.001736,
.009397,.00342,
.00866,.005,
.00766,.006428,
.006428,.00766,
.005,.00866,
.00342,.009397,
.001736,.009848,
0.0,.01,
0.0*
%
%ADD54MACRO54*%
%ADD43C,.071*%
%ADD23C,.026*%
%ADD64C,.064*%
%AMMACRO28*
4,1,36,.0025,0.0,
.002462,.000434,
.002349,.000855,
.002165,.00125,
.001915,.001607,
.001607,.001915,
.00125,.002165,
.000855,.002349,
.000434,.002462,
0.0,.0025,
-.000434,.002462,
-.000855,.002349,
-.00125,.002165,
-.001607,.001915,
-.001915,.001607,
-.002165,.00125,
-.002349,.000855,
-.002462,.000434,
-.0025,0.0,
-.002462,-.000434,
-.002349,-.000855,
-.002165,-.00125,
-.001915,-.001607,
-.001607,-.001915,
-.00125,-.002165,
-.000855,-.002349,
-.000434,-.002462,
0.0,-.0025,
.000434,-.002462,
.000855,-.002349,
.00125,-.002165,
.001607,-.001915,
.001915,-.001607,
.002165,-.00125,
.002349,-.000855,
.002462,-.000434,
.0025,0.0,
135.*
%
%ADD28MACRO28*%
%ADD24C,.028*%
%AMMACRO19*
4,1,36,.0025,0.0,
.002462,.000434,
.002349,.000855,
.002165,.00125,
.001915,.001607,
.001607,.001915,
.00125,.002165,
.000855,.002349,
.000434,.002462,
0.0,.0025,
-.000434,.002462,
-.000855,.002349,
-.00125,.002165,
-.001607,.001915,
-.001915,.001607,
-.002165,.00125,
-.002349,.000855,
-.002462,.000434,
-.0025,0.0,
-.002462,-.000434,
-.002349,-.000855,
-.002165,-.00125,
-.001915,-.001607,
-.001607,-.001915,
-.00125,-.002165,
-.000855,-.002349,
-.000434,-.002462,
0.0,-.0025,
.000434,-.002462,
.000855,-.002349,
.00125,-.002165,
.001607,-.001915,
.001915,-.001607,
.002165,-.00125,
.002349,-.000855,
.002462,-.000434,
.0025,0.0,
180.*
%
%ADD19MACRO19*%
%AMMACRO17*
4,1,36,.0025,0.0,
.002462,.000434,
.002349,.000855,
.002165,.00125,
.001915,.001607,
.001607,.001915,
.00125,.002165,
.000855,.002349,
.000434,.002462,
0.0,.0025,
-.000434,.002462,
-.000855,.002349,
-.00125,.002165,
-.001607,.001915,
-.001915,.001607,
-.002165,.00125,
-.002349,.000855,
-.002462,.000434,
-.0025,0.0,
-.002462,-.000434,
-.002349,-.000855,
-.002165,-.00125,
-.001915,-.001607,
-.001607,-.001915,
-.00125,-.002165,
-.000855,-.002349,
-.000434,-.002462,
0.0,-.0025,
.000434,-.002462,
.000855,-.002349,
.00125,-.002165,
.001607,-.001915,
.001915,-.001607,
.002165,-.00125,
.002349,-.000855,
.002462,-.000434,
.0025,0.0,
225.*
%
%ADD17MACRO17*%
%AMMACRO10*
4,1,36,.0025,0.0,
.002462,.000434,
.002349,.000855,
.002165,.00125,
.001915,.001607,
.001607,.001915,
.00125,.002165,
.000855,.002349,
.000434,.002462,
0.0,.0025,
-.000434,.002462,
-.000855,.002349,
-.00125,.002165,
-.001607,.001915,
-.001915,.001607,
-.002165,.00125,
-.002349,.000855,
-.002462,.000434,
-.0025,0.0,
-.002462,-.000434,
-.002349,-.000855,
-.002165,-.00125,
-.001915,-.001607,
-.001607,-.001915,
-.00125,-.002165,
-.000855,-.002349,
-.000434,-.002462,
0.0,-.0025,
.000434,-.002462,
.000855,-.002349,
.00125,-.002165,
.001607,-.001915,
.001915,-.001607,
.002165,-.00125,
.002349,-.000855,
.002462,-.000434,
.0025,0.0,
270.*
%
%ADD10MACRO10*%
%AMMACRO82*
4,1,36,.003,0.0,
.002954,.000521,
.002819,.001026,
.002598,.0015,
.002298,.001928,
.001928,.002298,
.0015,.002598,
.001026,.002819,
.000521,.002954,
0.0,.003,
-.000521,.002954,
-.001026,.002819,
-.0015,.002598,
-.001928,.002298,
-.002298,.001928,
-.002598,.0015,
-.002819,.001026,
-.002954,.000521,
-.003,0.0,
-.002954,-.000521,
-.002819,-.001026,
-.002598,-.0015,
-.002298,-.001928,
-.001928,-.002298,
-.0015,-.002598,
-.001026,-.002819,
-.000521,-.002954,
0.0,-.003,
.000521,-.002954,
.001026,-.002819,
.0015,-.002598,
.001928,-.002298,
.002298,-.001928,
.002598,-.0015,
.002819,-.001026,
.002954,-.000521,
.003,0.0,
270.*
%
%ADD82MACRO82*%
%AMMACRO44*
4,1,36,-.0025,0.0,
-.002462,.000434,
-.002349,.000855,
-.002165,.00125,
-.001915,.001607,
-.001607,.001915,
-.00125,.002165,
-.000855,.002349,
-.000434,.002462,
0.0,.0025,
.000434,.002462,
.000855,.002349,
.00125,.002165,
.001607,.001915,
.001915,.001607,
.002165,.00125,
.002349,.000855,
.002462,.000434,
.0025,0.0,
.002462,-.000434,
.002349,-.000855,
.002165,-.00125,
.001915,-.001607,
.001607,-.001915,
.00125,-.002165,
.000855,-.002349,
.000434,-.002462,
0.0,-.0025,
-.000434,-.002462,
-.000855,-.002349,
-.00125,-.002165,
-.001607,-.001915,
-.001915,-.001607,
-.002165,-.00125,
-.002349,-.000855,
-.002462,-.000434,
-.0025,0.0,
180.*
%
%ADD44MACRO44*%
%AMMACRO32*
4,1,36,.003,0.0,
.002954,.000521,
.002819,.001026,
.002598,.0015,
.002298,.001928,
.001928,.002298,
.0015,.002598,
.001026,.002819,
.000521,.002954,
0.0,.003,
-.000521,.002954,
-.001026,.002819,
-.0015,.002598,
-.001928,.002298,
-.002298,.001928,
-.002598,.0015,
-.002819,.001026,
-.002954,.000521,
-.003,0.0,
-.002954,-.000521,
-.002819,-.001026,
-.002598,-.0015,
-.002298,-.001928,
-.001928,-.002298,
-.0015,-.002598,
-.001026,-.002819,
-.000521,-.002954,
0.0,-.003,
.000521,-.002954,
.001026,-.002819,
.0015,-.002598,
.001928,-.002298,
.002298,-.001928,
.002598,-.0015,
.002819,-.001026,
.002954,-.000521,
.003,0.0,
180.*
%
%ADD32MACRO32*%
%ADD22C,.074*%
%ADD20C,.0263*%
%AMMACRO81*
4,1,36,-.003,0.0,
-.002954,.000521,
-.002819,.001026,
-.002598,.0015,
-.002298,.001928,
-.001928,.002298,
-.0015,.002598,
-.001026,.002819,
-.000521,.002954,
0.0,.003,
.000521,.002954,
.001026,.002819,
.0015,.002598,
.001928,.002298,
.002298,.001928,
.002598,.0015,
.002819,.001026,
.002954,.000521,
.003,0.0,
.002954,-.000521,
.002819,-.001026,
.002598,-.0015,
.002298,-.001928,
.001928,-.002298,
.0015,-.002598,
.001026,-.002819,
.000521,-.002954,
0.0,-.003,
-.000521,-.002954,
-.001026,-.002819,
-.0015,-.002598,
-.001928,-.002298,
-.002298,-.001928,
-.002598,-.0015,
-.002819,-.001026,
-.002954,-.000521,
-.003,0.0,
270.*
%
%ADD81MACRO81*%
%ADD80C,.0435*%
%ADD67C,.075*%
%ADD62C,.06015*%
%ADD48C,.066*%
%ADD51C,.076*%
%ADD50C,.095*%
%ADD34C,.03047*%
%ADD31C,.0248*%
%ADD74C,.087*%
%ADD35C,.03417*%
%AMMACRO13*
4,1,18,.09673,.06845,
.107147,.050613,
.114308,.031238,
.117996,.010914,
.118098,-.009741,
.114613,-.030101,
.107644,-.049546,
.097406,-.067485,
.09673,-.06845,
.10175,-.07347,
.112962,-.054685,
.120742,-.034239,
.124853,-.012752,
.125171,.009122,
.121685,.030719,
.114502,.051383,
.10384,.070486,
.10175,.07347,
.09673,.06845,
0.0*
4,1,18,.06845,-.09673,
.050613,-.107147,
.031238,-.114308,
.010914,-.117996,
-.009741,-.118098,
-.030101,-.114613,
-.049546,-.107644,
-.067485,-.097406,
-.06845,-.09673,
-.07347,-.10175,
-.054685,-.112962,
-.034239,-.120742,
-.012752,-.124853,
.009122,-.125171,
.030719,-.121685,
.051383,-.114502,
.070486,-.10384,
.07347,-.10175,
.06845,-.09673,
0.0*
4,1,18,-.09673,-.06845,
-.107147,-.050613,
-.114308,-.031238,
-.117996,-.010914,
-.118098,.009741,
-.114613,.030101,
-.107644,.049546,
-.097406,.067485,
-.09673,.06845,
-.10175,.07347,
-.112962,.054685,
-.120742,.034239,
-.124853,.012752,
-.125171,-.009122,
-.121685,-.030719,
-.114502,-.051383,
-.10384,-.070486,
-.10175,-.07347,
-.09673,-.06845,
0.0*
4,1,18,-.06845,.09673,
-.050613,.107147,
-.031238,.114308,
-.010914,.117996,
.009741,.118098,
.030101,.114613,
.049546,.107644,
.067485,.097406,
.06845,.09673,
.07347,.10175,
.054685,.112962,
.034239,.120742,
.012752,.124853,
-.009122,.125171,
-.030719,.121685,
-.051383,.114502,
-.070486,.10384,
-.07347,.10175,
-.06845,.09673,
0.0*
%
%ADD13MACRO13*%
%AMMACRO37*
4,1,16,.0711,.04282,
.077455,.029823,
.081457,.01592,
.082984,.001533,
.08199,-.0129,
.078504,-.026942,
.072633,-.040164,
.0711,-.04282,
.07619,-.04791,
.083352,-.033952,
.087981,-.018962,
.089937,-.003396,
.089161,.012273,
.085675,.027569,
.079586,.042027,
.07619,.04791,
.0711,.04282,
0.0*
4,1,16,.04282,-.0711,
.029823,-.077455,
.01592,-.081457,
.001533,-.082984,
-.0129,-.08199,
-.026942,-.078504,
-.040164,-.072633,
-.04282,-.0711,
-.04791,-.07619,
-.033952,-.083352,
-.018962,-.087981,
-.003396,-.089937,
.012273,-.089161,
.027569,-.085675,
.042027,-.079586,
.04791,-.07619,
.04282,-.0711,
0.0*
4,1,16,-.0711,-.04282,
-.077455,-.029823,
-.081457,-.01592,
-.082984,-.001533,
-.08199,.0129,
-.078504,.026942,
-.072633,.040164,
-.0711,.04282,
-.07619,.04791,
-.083352,.033952,
-.087981,.018962,
-.089937,.003396,
-.089161,-.012273,
-.085675,-.027569,
-.079586,-.042027,
-.07619,-.04791,
-.0711,-.04282,
0.0*
4,1,16,-.04282,.0711,
-.029823,.077455,
-.01592,.081457,
-.001533,.082984,
.0129,.08199,
.026942,.078504,
.040164,.072633,
.04282,.0711,
.04791,.07619,
.033952,.083352,
.018962,.087981,
.003396,.089937,
-.012273,.089161,
-.027569,.085675,
-.042027,.079586,
-.04791,.07619,
-.04282,.0711,
0.0*
%
%ADD37MACRO37*%
%AMMACRO65*
4,1,16,.02584,.01524,
.028094,.010521,
.029494,.005483,
.029998,.000278,
.029591,-.004935,
.028284,-.009999,
.026118,-.014758,
.02584,-.01524,
.03092,-.02032,
.033979,-.014642,
.036005,-.008519,
.036938,-.002138,
.036748,.004309,
.035441,.010625,
.033058,.016618,
.03092,.02032,
.02584,.01524,
90.*
4,1,16,.01524,-.02584,
.010521,-.028094,
.005483,-.029494,
.000278,-.029998,
-.004935,-.029591,
-.009999,-.028284,
-.014758,-.026118,
-.01524,-.02584,
-.02032,-.03092,
-.014642,-.033979,
-.008519,-.036005,
-.002138,-.036938,
.004309,-.036748,
.010625,-.035441,
.016618,-.033058,
.02032,-.03092,
.01524,-.02584,
90.*
4,1,16,-.02584,-.01524,
-.028094,-.010521,
-.029494,-.005483,
-.029998,-.000278,
-.029591,.004935,
-.028284,.009999,
-.026118,.014758,
-.02584,.01524,
-.03092,.02032,
-.033979,.014642,
-.036005,.008519,
-.036938,.002138,
-.036748,-.004309,
-.035441,-.010625,
-.033058,-.016618,
-.03092,-.02032,
-.02584,-.01524,
90.*
4,1,16,-.01524,.02584,
-.010521,.028094,
-.005483,.029494,
-.000278,.029998,
.004935,.029591,
.009999,.028284,
.014758,.026118,
.01524,.02584,
.02032,.03092,
.014642,.033979,
.008519,.036005,
.002138,.036938,
-.004309,.036748,
-.010625,.035441,
-.016618,.033058,
-.02032,.03092,
-.01524,.02584,
90.*
%
%ADD65MACRO65*%
%AMMACRO47*
4,1,15,.02438,.01377,
.026401,.009327,
.027619,.004601,
.027999,-.000265,
.027527,-.005123,
.02622,-.009825,
.02438,-.01377,
.02948,-.01887,
.032309,-.013464,
.034156,-.007649,
.034965,-.001602,
.034712,.004494,
.033405,.010454,
.031082,.016095,
.02948,.01887,
.02438,.01377,
90.*
4,1,15,.01377,-.02438,
.009327,-.026401,
.004601,-.027619,
-.000265,-.027999,
-.005123,-.027527,
-.009825,-.02622,
-.01377,-.02438,
-.01887,-.02948,
-.013464,-.032309,
-.007649,-.034156,
-.001602,-.034965,
.004494,-.034712,
.010454,-.033405,
.016095,-.031082,
.01887,-.02948,
.01377,-.02438,
90.*
4,1,15,-.02438,-.01377,
-.026401,-.009327,
-.027619,-.004601,
-.027999,.000265,
-.027527,.005123,
-.02622,.009825,
-.02438,.01377,
-.02948,.01887,
-.032309,.013464,
-.034156,.007649,
-.034965,.001602,
-.034712,-.004494,
-.033405,-.010454,
-.031082,-.016095,
-.02948,-.01887,
-.02438,-.01377,
90.*
4,1,15,-.01377,.02438,
-.009327,.026401,
-.004601,.027619,
.000265,.027999,
.005123,.027527,
.009825,.02622,
.01377,.02438,
.01887,.02948,
.013464,.032309,
.007649,.034156,
.001602,.034965,
-.004494,.034712,
-.010454,.033405,
-.016095,.031082,
-.01887,.02948,
-.01377,.02438,
90.*
%
%ADD47MACRO47*%
%AMMACRO16*
4,1,16,.07001,.04172,
.076191,.028929,
.080057,.015259,
.08149,.001126,
.080448,-.013042,
.076961,-.026814,
.071136,-.03977,
.07001,-.04172,
.0751,-.04682,
.082089,-.033068,
.086584,-.018311,
.088449,-.002997,
.087625,.012407,
.08414,.027435,
.078097,.041629,
.0751,.04682,
.07001,.04172,
0.0*
4,1,16,.04172,-.07001,
.028929,-.076191,
.015259,-.080057,
.001126,-.08149,
-.013042,-.080448,
-.026814,-.076961,
-.03977,-.071136,
-.04172,-.07001,
-.04682,-.0751,
-.033068,-.082089,
-.018311,-.086584,
-.002997,-.088449,
.012407,-.087625,
.027435,-.08414,
.041629,-.078097,
.04682,-.0751,
.04172,-.07001,
0.0*
4,1,16,-.07001,-.04172,
-.076191,-.028929,
-.080057,-.015259,
-.08149,-.001126,
-.080448,.013042,
-.076961,.026814,
-.071136,.03977,
-.07001,.04172,
-.0751,.04682,
-.082089,.033068,
-.086584,.018311,
-.088449,.002997,
-.087625,-.012407,
-.08414,-.027435,
-.078097,-.041629,
-.0751,-.04682,
-.07001,-.04172,
0.0*
4,1,16,-.04172,.07001,
-.028929,.076191,
-.015259,.080057,
-.001126,.08149,
.013042,.080448,
.026814,.076961,
.03977,.071136,
.04172,.07001,
.04682,.0751,
.033068,.082089,
.018311,.086584,
.002997,.088449,
-.012407,.087625,
-.027435,.08414,
-.041629,.078097,
-.04682,.0751,
-.04172,.07001,
0.0*
%
%ADD16MACRO16*%
%AMMACRO66*
4,1,15,.02142,.01082,
.022973,.006936,
.023829,.002841,
.02396,-.00134,
.023364,-.00548,
.022057,-.009454,
.02142,-.01082,
.02657,-.01597,
.02894,-.011114,
.03043,-.005919,
.030995,-.000545,
.030619,.004845,
.029313,.010088,
.027115,.015025,
.02657,.01597,
.02142,.01082,
0.0*
4,1,15,.01082,-.02142,
.006936,-.022973,
.002841,-.023829,
-.00134,-.02396,
-.00548,-.023364,
-.009454,-.022057,
-.01082,-.02142,
-.01597,-.02657,
-.011114,-.02894,
-.005919,-.03043,
-.000545,-.030995,
.004845,-.030619,
.010088,-.029313,
.015025,-.027115,
.01597,-.02657,
.01082,-.02142,
0.0*
4,1,15,-.02142,-.01082,
-.022973,-.006936,
-.023829,-.002841,
-.02396,.00134,
-.023364,.00548,
-.022057,.009454,
-.02142,.01082,
-.02657,.01597,
-.02894,.011114,
-.03043,.005919,
-.030995,.000545,
-.030619,-.004845,
-.029313,-.010088,
-.027115,-.015025,
-.02657,-.01597,
-.02142,-.01082,
0.0*
4,1,15,-.01082,.02142,
-.006936,.022973,
-.002841,.023829,
.00134,.02396,
.00548,.023364,
.009454,.022057,
.01082,.02142,
.01597,.02657,
.011114,.02894,
.005919,.03043,
.000545,.030995,
-.004845,.030619,
-.010088,.029313,
-.015025,.027115,
-.01597,.02657,
-.01082,.02142,
0.0*
%
%ADD66MACRO66*%
%AMMACRO52*
4,1,15,.02475,.01414,
.026829,.009627,
.028094,.004822,
.028504,-.000129,
.028049,-.005077,
.026741,-.009871,
.02475,-.01414,
.02984,-.01923,
.032726,-.013756,
.034617,-.007864,
.035457,-.001734,
.03522,.00445,
.033912,.010498,
.031574,.016227,
.02984,.01923,
.02475,.01414,
0.0*
4,1,15,.01414,-.02475,
.009627,-.026829,
.004822,-.028094,
-.000129,-.028504,
-.005077,-.028049,
-.009871,-.026741,
-.01414,-.02475,
-.01923,-.02984,
-.013756,-.032726,
-.007864,-.034617,
-.001734,-.035457,
.00445,-.03522,
.010498,-.033912,
.016227,-.031574,
.01923,-.02984,
.01414,-.02475,
0.0*
4,1,15,-.02475,-.01414,
-.026829,-.009627,
-.028094,-.004822,
-.028504,.000129,
-.028049,.005077,
-.026741,.009871,
-.02475,.01414,
-.02984,.01923,
-.032726,.013756,
-.034617,.007864,
-.035457,.001734,
-.03522,-.00445,
-.033912,-.010498,
-.031574,-.016227,
-.02984,-.01923,
-.02475,-.01414,
0.0*
4,1,15,-.01414,.02475,
-.009627,.026829,
-.004822,.028094,
.000129,.028504,
.005077,.028049,
.009871,.026741,
.01414,.02475,
.01923,.02984,
.013756,.032726,
.007864,.034617,
.001734,.035457,
-.00445,.03522,
-.010498,.033912,
-.016227,.031574,
-.01923,.02984,
-.01414,.02475,
0.0*
%
%ADD52MACRO52*%
%AMMACRO77*
4,1,15,.03682,.01914,
.039584,.012455,
.041146,.005393,
.041457,-.001834,
.040509,-.009005,
.03833,-.015903,
.03682,-.01914,
.04197,-.0243,
.045552,-.016643,
.04775,-.00848,
.048497,-.000059,
.047771,.008363,
.045593,.016531,
.042029,.024197,
.04197,.0243,
.03682,.01914,
0.0*
4,1,15,.01914,-.03682,
.012455,-.039584,
.005393,-.041146,
-.001834,-.041457,
-.009005,-.040509,
-.015903,-.03833,
-.01914,-.03682,
-.0243,-.04197,
-.016643,-.045552,
-.00848,-.04775,
-.000059,-.048497,
.008363,-.047771,
.016531,-.045593,
.024197,-.042029,
.0243,-.04197,
.01914,-.03682,
0.0*
4,1,15,-.03682,-.01914,
-.039584,-.012455,
-.041146,-.005393,
-.041457,.001834,
-.040509,.009005,
-.03833,.015903,
-.03682,.01914,
-.04197,.0243,
-.045552,.016643,
-.04775,.00848,
-.048497,.000059,
-.047771,-.008363,
-.045593,-.016531,
-.042029,-.024197,
-.04197,-.0243,
-.03682,-.01914,
0.0*
4,1,15,-.01914,.03682,
-.012455,.039584,
-.005393,.041146,
.001834,.041457,
.009005,.040509,
.015903,.03833,
.01914,.03682,
.0243,.04197,
.016643,.045552,
.00848,.04775,
.000059,.048497,
-.008363,.047771,
-.016531,.045593,
-.024197,.042029,
-.0243,.04197,
-.01914,.03682,
0.0*
%
%ADD77MACRO77*%
%AMMACRO73*
4,1,36,.0025,0.0,
.002462,.000434,
.002349,.000855,
.002165,.00125,
.001915,.001607,
.001607,.001915,
.00125,.002165,
.000855,.002349,
.000434,.002462,
0.0,.0025,
-.000434,.002462,
-.000855,.002349,
-.00125,.002165,
-.001607,.001915,
-.001915,.001607,
-.002165,.00125,
-.002349,.000855,
-.002462,.000434,
-.0025,0.0,
-.002462,-.000434,
-.002349,-.000855,
-.002165,-.00125,
-.001915,-.001607,
-.001607,-.001915,
-.00125,-.002165,
-.000855,-.002349,
-.000434,-.002462,
0.0,-.0025,
.000434,-.002462,
.000855,-.002349,
.00125,-.002165,
.001607,-.001915,
.001915,-.001607,
.002165,-.00125,
.002349,-.000855,
.002462,-.000434,
.0025,0.0,
134.996*
%
%ADD73MACRO73*%
%AMMACRO75*
4,1,15,-.03682,.01914,
-.039584,.012455,
-.041146,.005393,
-.041457,-.001834,
-.040509,-.009005,
-.03833,-.015903,
-.03682,-.01914,
-.04197,-.0243,
-.045552,-.016643,
-.04775,-.00848,
-.048497,-.000059,
-.047771,.008363,
-.045593,.016531,
-.042029,.024197,
-.04197,.0243,
-.03682,.01914,
0.0*
4,1,15,-.01914,-.03682,
-.012455,-.039584,
-.005393,-.041146,
.001834,-.041457,
.009005,-.040509,
.015903,-.03833,
.01914,-.03682,
.0243,-.04197,
.016643,-.045552,
.00848,-.04775,
.000059,-.048497,
-.008363,-.047771,
-.016531,-.045593,
-.024197,-.042029,
-.0243,-.04197,
-.01914,-.03682,
0.0*
4,1,15,.03682,-.01914,
.039584,-.012455,
.041146,-.005393,
.041457,.001834,
.040509,.009005,
.03833,.015903,
.03682,.01914,
.04197,.0243,
.045552,.016643,
.04775,.00848,
.048497,.000059,
.047771,-.008363,
.045593,-.016531,
.042029,-.024197,
.04197,-.0243,
.03682,-.01914,
0.0*
4,1,15,.01914,.03682,
.012455,.039584,
.005393,.041146,
-.001834,.041457,
-.009005,.040509,
-.015903,.03833,
-.01914,.03682,
-.0243,.04197,
-.016643,.045552,
-.00848,.04775,
-.000059,.048497,
.008363,.047771,
.016531,.045593,
.024197,.042029,
.0243,.04197,
.01914,.03682,
0.0*
%
%ADD75MACRO75*%
%AMMACRO39*
4,1,36,.003,0.0,
.002954,.000521,
.002819,.001026,
.002598,.0015,
.002298,.001928,
.001928,.002298,
.0015,.002598,
.001026,.002819,
.000521,.002954,
0.0,.003,
-.000521,.002954,
-.001026,.002819,
-.0015,.002598,
-.001928,.002298,
-.002298,.001928,
-.002598,.0015,
-.002819,.001026,
-.002954,.000521,
-.003,0.0,
-.002954,-.000521,
-.002819,-.001026,
-.002598,-.0015,
-.002298,-.001928,
-.001928,-.002298,
-.0015,-.002598,
-.001026,-.002819,
-.000521,-.002954,
0.0,-.003,
.000521,-.002954,
.001026,-.002819,
.0015,-.002598,
.001928,-.002298,
.002298,-.001928,
.002598,-.0015,
.002819,-.001026,
.002954,-.000521,
.003,0.0,
179.996*
%
%ADD39MACRO39*%
%ADD60O,.285X.23*%
%ADD72C,.142*%
%AMMACRO61*
4,1,36,0.0,.01,
-.001736,.009848,
-.00342,.009397,
-.005,.00866,
-.006428,.00766,
-.00766,.006428,
-.00866,.005,
-.009397,.00342,
-.009848,.001736,
-.01,0.0,
-.009848,-.001736,
-.009397,-.00342,
-.00866,-.005,
-.00766,-.006428,
-.006428,-.00766,
-.005,-.00866,
-.00342,-.009397,
-.001736,-.009848,
0.0,-.01,
.001736,-.009848,
.00342,-.009397,
.005,-.00866,
.006428,-.00766,
.00766,-.006428,
.00866,-.005,
.009397,-.00342,
.009848,-.001736,
.01,0.0,
.009848,.001736,
.009397,.00342,
.00866,.005,
.00766,.006428,
.006428,.00766,
.005,.00866,
.00342,.009397,
.001736,.009848,
0.0,.01,
180.*
%
%ADD61MACRO61*%
%ADD36O,.219X.156*%
%ADD11C,.125*%
%ADD27C,.424*%
%ADD18C,.155*%
%ADD53C,.291*%
%ADD55C,.247*%
%ADD46C,.256*%
%AMMACRO33*
4,1,36,0.0,.0085,
.001476,.008371,
.002907,.007987,
.00425,.007361,
.005464,.006511,
.006511,.005464,
.007361,.00425,
.007987,.002907,
.008371,.001476,
.0085,0.0,
.008371,-.001476,
.007987,-.002907,
.007361,-.00425,
.006511,-.005464,
.005464,-.006511,
.00425,-.007361,
.002907,-.007987,
.001476,-.008371,
0.0,-.0085,
-.001476,-.008371,
-.002907,-.007987,
-.00425,-.007361,
-.005464,-.006511,
-.006511,-.005464,
-.007361,-.00425,
-.007987,-.002907,
-.008371,-.001476,
-.0085,0.0,
-.008371,.001476,
-.007987,.002907,
-.007361,.00425,
-.006511,.005464,
-.005464,.006511,
-.00425,.007361,
-.002907,.007987,
-.001476,.008371,
0.0,.0085,
180.*
%
%ADD33MACRO33*%
%AMMACRO59*
4,1,20,-.0075,-.05555,
-.0075,-.06273,
-.013677,-.060878,
-.019439,-.057981,
-.024611,-.054127,
-.029034,-.049434,
-.032576,-.044045,
-.035127,-.038122,
-.036612,-.031846,
-.037,-.0265,
-.037,-.0075,
-.03,-.0075,
-.03,-.0265,
-.029544,-.03171,
-.028191,-.036762,
-.02598,-.041502,
-.022981,-.045786,
-.019282,-.049484,
-.014998,-.052484,
-.010258,-.054694,
-.0075,-.05555,
90.*
4,1,20,.0075,-.06273,
.0075,-.05555,
.01243,-.053806,
.016983,-.051232,
.02102,-.047906,
.024418,-.043931,
.027073,-.039425,
.028906,-.034527,
.029861,-.029385,
.03,-.0265,
.03,-.0075,
.037,-.0075,
.037,-.0265,
.036438,-.032925,
.034769,-.039154,
.032043,-.044999,
.028344,-.050282,
.023784,-.054842,
.018501,-.058541,
.012656,-.061266,
.0075,-.06273,
90.*
4,1,20,-.0075,.06273,
-.0075,.05555,
-.01243,.053806,
-.016983,.051232,
-.02102,.047906,
-.024418,.043931,
-.027073,.039425,
-.028906,.034527,
-.029861,.029385,
-.03,.0265,
-.03,.0075,
-.037,.0075,
-.037,.0265,
-.036438,.032925,
-.034769,.039154,
-.032043,.044999,
-.028344,.050282,
-.023784,.054842,
-.018501,.058541,
-.012656,.061266,
-.0075,.06273,
90.*
4,1,20,.0075,.05555,
.0075,.06273,
.013677,.060878,
.019439,.057981,
.024611,.054127,
.029034,.049434,
.032576,.044045,
.035127,.038122,
.036612,.031846,
.037,.0265,
.037,.0075,
.03,.0075,
.03,.0265,
.029544,.03171,
.028191,.036762,
.02598,.041502,
.022981,.045786,
.019282,.049484,
.014998,.052484,
.010258,.054694,
.0075,.05555,
90.*
%
%ADD59MACRO59*%
%AMMACRO15*
4,1,36,.0025,0.0,
.002462,.000434,
.002349,.000855,
.002165,.00125,
.001915,.001607,
.001607,.001915,
.00125,.002165,
.000855,.002349,
.000434,.002462,
0.0,.0025,
-.000434,.002462,
-.000855,.002349,
-.00125,.002165,
-.001607,.001915,
-.001915,.001607,
-.002165,.00125,
-.002349,.000855,
-.002462,.000434,
-.0025,0.0,
-.002462,-.000434,
-.002349,-.000855,
-.002165,-.00125,
-.001915,-.001607,
-.001607,-.001915,
-.00125,-.002165,
-.000855,-.002349,
-.000434,-.002462,
0.0,-.0025,
.000434,-.002462,
.000855,-.002349,
.00125,-.002165,
.001607,-.001915,
.001915,-.001607,
.002165,-.00125,
.002349,-.000855,
.002462,-.000434,
.0025,0.0,
90.*
%
%ADD15MACRO15*%
%AMMACRO56*
4,1,36,0.0,.019,
-.003299,.018711,
-.006498,.017854,
-.0095,.016454,
-.012213,.014555,
-.014555,.012213,
-.016454,.0095,
-.017854,.006498,
-.018711,.003299,
-.019,0.0,
-.018711,-.003299,
-.017854,-.006498,
-.016454,-.0095,
-.014555,-.012213,
-.012213,-.014555,
-.0095,-.016454,
-.006498,-.017854,
-.003299,-.018711,
0.0,-.019,
.003299,-.018711,
.006498,-.017854,
.0095,-.016454,
.012213,-.014555,
.014555,-.012213,
.016454,-.0095,
.017854,-.006498,
.018711,-.003299,
.019,0.0,
.018711,.003299,
.017854,.006498,
.016454,.0095,
.014555,.012213,
.012213,.014555,
.0095,.016454,
.006498,.017854,
.003299,.018711,
0.0,.019,
270.*
%
%ADD56MACRO56*%
%AMMACRO40*
4,1,36,.003,0.0,
.002954,.000521,
.002819,.001026,
.002598,.0015,
.002298,.001928,
.001928,.002298,
.0015,.002598,
.001026,.002819,
.000521,.002954,
0.0,.003,
-.000521,.002954,
-.001026,.002819,
-.0015,.002598,
-.001928,.002298,
-.002298,.001928,
-.002598,.0015,
-.002819,.001026,
-.002954,.000521,
-.003,0.0,
-.002954,-.000521,
-.002819,-.001026,
-.002598,-.0015,
-.002298,-.001928,
-.001928,-.002298,
-.0015,-.002598,
-.001026,-.002819,
-.000521,-.002954,
0.0,-.003,
.000521,-.002954,
.001026,-.002819,
.0015,-.002598,
.001928,-.002298,
.002298,-.001928,
.002598,-.0015,
.002819,-.001026,
.002954,-.000521,
.003,0.0,
90.*
%
%ADD40MACRO40*%
%AMMACRO12*
4,1,36,.0025,0.0,
.002462,.000434,
.002349,.000855,
.002165,.00125,
.001915,.001607,
.001607,.001915,
.00125,.002165,
.000855,.002349,
.000434,.002462,
0.0,.0025,
-.000434,.002462,
-.000855,.002349,
-.00125,.002165,
-.001607,.001915,
-.001915,.001607,
-.002165,.00125,
-.002349,.000855,
-.002462,.000434,
-.0025,0.0,
-.002462,-.000434,
-.002349,-.000855,
-.002165,-.00125,
-.001915,-.001607,
-.001607,-.001915,
-.00125,-.002165,
-.000855,-.002349,
-.000434,-.002462,
0.0,-.0025,
.000434,-.002462,
.000855,-.002349,
.00125,-.002165,
.001607,-.001915,
.001915,-.001607,
.002165,-.00125,
.002349,-.000855,
.002462,-.000434,
.0025,0.0,
0.0*
%
%ADD12MACRO12*%
%AMMACRO79*
4,1,36,-.003,0.0,
-.002954,.000521,
-.002819,.001026,
-.002598,.0015,
-.002298,.001928,
-.001928,.002298,
-.0015,.002598,
-.001026,.002819,
-.000521,.002954,
0.0,.003,
.000521,.002954,
.001026,.002819,
.0015,.002598,
.001928,.002298,
.002298,.001928,
.002598,.0015,
.002819,.001026,
.002954,.000521,
.003,0.0,
.002954,-.000521,
.002819,-.001026,
.002598,-.0015,
.002298,-.001928,
.001928,-.002298,
.0015,-.002598,
.001026,-.002819,
.000521,-.002954,
0.0,-.003,
-.000521,-.002954,
-.001026,-.002819,
-.0015,-.002598,
-.001928,-.002298,
-.002298,-.001928,
-.002598,-.0015,
-.002819,-.001026,
-.002954,-.000521,
-.003,0.0,
90.*
%
%ADD79MACRO79*%
%AMMACRO45*
4,1,36,-.0025,0.0,
-.002462,.000434,
-.002349,.000855,
-.002165,.00125,
-.001915,.001607,
-.001607,.001915,
-.00125,.002165,
-.000855,.002349,
-.000434,.002462,
0.0,.0025,
.000434,.002462,
.000855,.002349,
.00125,.002165,
.001607,.001915,
.001915,.001607,
.002165,.00125,
.002349,.000855,
.002462,.000434,
.0025,0.0,
.002462,-.000434,
.002349,-.000855,
.002165,-.00125,
.001915,-.001607,
.001607,-.001915,
.00125,-.002165,
.000855,-.002349,
.000434,-.002462,
0.0,-.0025,
-.000434,-.002462,
-.000855,-.002349,
-.00125,-.002165,
-.001607,-.001915,
-.001915,-.001607,
-.002165,-.00125,
-.002349,-.000855,
-.002462,-.000434,
-.0025,0.0,
0.0*
%
%ADD45MACRO45*%
%ADD38C,.188*%
%AMMACRO29*
4,1,36,.003,0.0,
.002954,.000521,
.002819,.001026,
.002598,.0015,
.002298,.001928,
.001928,.002298,
.0015,.002598,
.001026,.002819,
.000521,.002954,
0.0,.003,
-.000521,.002954,
-.001026,.002819,
-.0015,.002598,
-.001928,.002298,
-.002298,.001928,
-.002598,.0015,
-.002819,.001026,
-.002954,.000521,
-.003,0.0,
-.002954,-.000521,
-.002819,-.001026,
-.002598,-.0015,
-.002298,-.001928,
-.001928,-.002298,
-.0015,-.002598,
-.001026,-.002819,
-.000521,-.002954,
0.0,-.003,
.000521,-.002954,
.001026,-.002819,
.0015,-.002598,
.001928,-.002298,
.002298,-.001928,
.002598,-.0015,
.002819,-.001026,
.002954,-.000521,
.003,0.0,
0.0*
%
%ADD29MACRO29*%
%AMMACRO21*
4,1,16,.02584,.01524,
.028094,.010521,
.029494,.005483,
.029998,.000278,
.029591,-.004935,
.028284,-.009999,
.026118,-.014758,
.02584,-.01524,
.03092,-.02032,
.033979,-.014642,
.036005,-.008519,
.036938,-.002138,
.036748,.004309,
.035441,.010625,
.033058,.016618,
.03092,.02032,
.02584,.01524,
180.*
4,1,16,.01524,-.02584,
.010521,-.028094,
.005483,-.029494,
.000278,-.029998,
-.004935,-.029591,
-.009999,-.028284,
-.014758,-.026118,
-.01524,-.02584,
-.02032,-.03092,
-.014642,-.033979,
-.008519,-.036005,
-.002138,-.036938,
.004309,-.036748,
.010625,-.035441,
.016618,-.033058,
.02032,-.03092,
.01524,-.02584,
180.*
4,1,16,-.02584,-.01524,
-.028094,-.010521,
-.029494,-.005483,
-.029998,-.000278,
-.029591,.004935,
-.028284,.009999,
-.026118,.014758,
-.02584,.01524,
-.03092,.02032,
-.033979,.014642,
-.036005,.008519,
-.036938,.002138,
-.036748,-.004309,
-.035441,-.010625,
-.033058,-.016618,
-.03092,-.02032,
-.02584,-.01524,
180.*
4,1,16,-.01524,.02584,
-.010521,.028094,
-.005483,.029494,
-.000278,.029998,
.004935,.029591,
.009999,.028284,
.014758,.026118,
.01524,.02584,
.02032,.03092,
.014642,.033979,
.008519,.036005,
.002138,.036938,
-.004309,.036748,
-.010625,.035441,
-.016618,.033058,
-.02032,.03092,
-.01524,.02584,
180.*
%
%ADD21MACRO21*%
%AMMACRO63*
4,1,15,.02438,.01377,
.026401,.009327,
.027619,.004601,
.027999,-.000265,
.027527,-.005123,
.02622,-.009825,
.02438,-.01377,
.02948,-.01887,
.032309,-.013464,
.034156,-.007649,
.034965,-.001602,
.034712,.004494,
.033405,.010454,
.031082,.016095,
.02948,.01887,
.02438,.01377,
270.*
4,1,15,.01377,-.02438,
.009327,-.026401,
.004601,-.027619,
-.000265,-.027999,
-.005123,-.027527,
-.009825,-.02622,
-.01377,-.02438,
-.01887,-.02948,
-.013464,-.032309,
-.007649,-.034156,
-.001602,-.034965,
.004494,-.034712,
.010454,-.033405,
.016095,-.031082,
.01887,-.02948,
.01377,-.02438,
270.*
4,1,15,-.02438,-.01377,
-.026401,-.009327,
-.027619,-.004601,
-.027999,.000265,
-.027527,.005123,
-.02622,.009825,
-.02438,.01377,
-.02948,.01887,
-.032309,.013464,
-.034156,.007649,
-.034965,.001602,
-.034712,-.004494,
-.033405,-.010454,
-.031082,-.016095,
-.02948,-.01887,
-.02438,-.01377,
270.*
4,1,15,-.01377,.02438,
-.009327,.026401,
-.004601,.027619,
.000265,.027999,
.005123,.027527,
.009825,.02622,
.01377,.02438,
.01887,.02948,
.013464,.032309,
.007649,.034156,
.001602,.034965,
-.004494,.034712,
-.010454,.033405,
-.016095,.031082,
-.01887,.02948,
-.01377,.02438,
270.*
%
%ADD63MACRO63*%
%AMMACRO42*
4,1,15,.02438,.01377,
.026401,.009327,
.027619,.004601,
.027999,-.000265,
.027527,-.005123,
.02622,-.009825,
.02438,-.01377,
.02948,-.01887,
.032309,-.013464,
.034156,-.007649,
.034965,-.001602,
.034712,.004494,
.033405,.010454,
.031082,.016095,
.02948,.01887,
.02438,.01377,
180.*
4,1,15,.01377,-.02438,
.009327,-.026401,
.004601,-.027619,
-.000265,-.027999,
-.005123,-.027527,
-.009825,-.02622,
-.01377,-.02438,
-.01887,-.02948,
-.013464,-.032309,
-.007649,-.034156,
-.001602,-.034965,
.004494,-.034712,
.010454,-.033405,
.016095,-.031082,
.01887,-.02948,
.01377,-.02438,
180.*
4,1,15,-.02438,-.01377,
-.026401,-.009327,
-.027619,-.004601,
-.027999,.000265,
-.027527,.005123,
-.02622,.009825,
-.02438,.01377,
-.02948,.01887,
-.032309,.013464,
-.034156,.007649,
-.034965,.001602,
-.034712,-.004494,
-.033405,-.010454,
-.031082,-.016095,
-.02948,-.01887,
-.02438,-.01377,
180.*
4,1,15,-.01377,.02438,
-.009327,.026401,
-.004601,.027619,
.000265,.027999,
.005123,.027527,
.009825,.02622,
.01377,.02438,
.01887,.02948,
.013464,.032309,
.007649,.034156,
.001602,.034965,
-.004494,.034712,
-.010454,.033405,
-.016095,.031082,
-.01887,.02948,
-.01377,.02438,
180.*
%
%ADD42MACRO42*%
%AMMACRO26*
4,1,20,-.039,.0245,
-.038408,.031272,
-.036648,.037838,
-.033775,.043999,
-.029876,.049567,
-.02507,.054374,
-.019501,.058273,
-.01334,.061146,
-.0075,.06277,
-.0075,.05561,
-.012788,.053835,
-.017688,.051168,
-.02205,.047691,
-.025742,.04351,
-.028652,.038751,
-.030691,.033558,
-.031798,.028091,
-.032,.0245,
-.032,.0075,
-.039,.0075,
-.039,.0245,
90.*
4,1,20,-.039,-.0075,
-.032,-.0075,
-.032,-.0245,
-.031514,-.030057,
-.03007,-.035445,
-.027713,-.040501,
-.024513,-.04507,
-.020569,-.049015,
-.015999,-.052214,
-.010944,-.054572,
-.0075,-.05561,
-.0075,-.06277,
-.014032,-.060887,
-.020137,-.057898,
-.025631,-.053894,
-.030345,-.048997,
-.034138,-.043356,
-.036894,-.037142,
-.038529,-.030544,
-.039,-.0245,
-.039,-.0075,
90.*
4,1,20,.0075,.06277,
.014032,.060887,
.020137,.057898,
.025631,.053894,
.030345,.048997,
.034138,.043356,
.036894,.037142,
.038529,.030544,
.039,.0245,
.039,.0075,
.032,.0075,
.032,.0245,
.031514,.030057,
.03007,.035445,
.027713,.040501,
.024513,.04507,
.020569,.049015,
.015999,.052214,
.010944,.054572,
.0075,.05561,
.0075,.06277,
90.*
4,1,20,.0075,-.05561,
.012788,-.053835,
.017688,-.051168,
.02205,-.047691,
.025742,-.04351,
.028652,-.038751,
.030691,-.033558,
.031798,-.028091,
.032,-.0245,
.032,-.0075,
.039,-.0075,
.039,-.0245,
.038408,-.031272,
.036648,-.037838,
.033775,-.043999,
.029876,-.049567,
.02507,-.054374,
.019501,-.058273,
.01334,-.061146,
.0075,-.06277,
.0075,-.05561,
90.*
%
%ADD26MACRO26*%
%AMMACRO71*
4,1,15,.02475,.01414,
.026829,.009627,
.028094,.004822,
.028504,-.000129,
.028049,-.005077,
.026741,-.009871,
.02475,-.01414,
.02984,-.01923,
.032726,-.013756,
.034617,-.007864,
.035457,-.001734,
.03522,.00445,
.033912,.010498,
.031574,.016227,
.02984,.01923,
.02475,.01414,
270.*
4,1,15,.01414,-.02475,
.009627,-.026829,
.004822,-.028094,
-.000129,-.028504,
-.005077,-.028049,
-.009871,-.026741,
-.01414,-.02475,
-.01923,-.02984,
-.013756,-.032726,
-.007864,-.034617,
-.001734,-.035457,
.00445,-.03522,
.010498,-.033912,
.016227,-.031574,
.01923,-.02984,
.01414,-.02475,
270.*
4,1,15,-.02475,-.01414,
-.026829,-.009627,
-.028094,-.004822,
-.028504,.000129,
-.028049,.005077,
-.026741,.009871,
-.02475,.01414,
-.02984,.01923,
-.032726,.013756,
-.034617,.007864,
-.035457,.001734,
-.03522,-.00445,
-.033912,-.010498,
-.031574,-.016227,
-.02984,-.01923,
-.02475,-.01414,
270.*
4,1,15,-.01414,.02475,
-.009627,.026829,
-.004822,.028094,
.000129,.028504,
.005077,.028049,
.009871,.026741,
.01414,.02475,
.01923,.02984,
.013756,.032726,
.007864,.034617,
.001734,.035457,
-.00445,.03522,
-.010498,.033912,
-.016227,.031574,
-.01923,.02984,
-.01414,.02475,
270.*
%
%ADD71MACRO71*%
%AMMACRO70*
4,1,15,.02142,.01082,
.022973,.006936,
.023829,.002841,
.02396,-.00134,
.023364,-.00548,
.022057,-.009454,
.02142,-.01082,
.02657,-.01597,
.02894,-.011114,
.03043,-.005919,
.030995,-.000545,
.030619,.004845,
.029313,.010088,
.027115,.015025,
.02657,.01597,
.02142,.01082,
180.*
4,1,15,.01082,-.02142,
.006936,-.022973,
.002841,-.023829,
-.00134,-.02396,
-.00548,-.023364,
-.009454,-.022057,
-.01082,-.02142,
-.01597,-.02657,
-.011114,-.02894,
-.005919,-.03043,
-.000545,-.030995,
.004845,-.030619,
.010088,-.029313,
.015025,-.027115,
.01597,-.02657,
.01082,-.02142,
180.*
4,1,15,-.02142,-.01082,
-.022973,-.006936,
-.023829,-.002841,
-.02396,.00134,
-.023364,.00548,
-.022057,.009454,
-.02142,.01082,
-.02657,.01597,
-.02894,.011114,
-.03043,.005919,
-.030995,.000545,
-.030619,-.004845,
-.029313,-.010088,
-.027115,-.015025,
-.02657,-.01597,
-.02142,-.01082,
180.*
4,1,15,-.01082,.02142,
-.006936,.022973,
-.002841,.023829,
.00134,.02396,
.00548,.023364,
.009454,.022057,
.01082,.02142,
.01597,.02657,
.011114,.02894,
.005919,.03043,
.000545,.030995,
-.004845,.030619,
-.010088,.029313,
-.015025,.027115,
-.01597,.02657,
-.01082,.02142,
180.*
%
%ADD70MACRO70*%
%AMMACRO69*
4,1,15,.02475,.01414,
.026829,.009627,
.028094,.004822,
.028504,-.000129,
.028049,-.005077,
.026741,-.009871,
.02475,-.01414,
.02984,-.01923,
.032726,-.013756,
.034617,-.007864,
.035457,-.001734,
.03522,.00445,
.033912,.010498,
.031574,.016227,
.02984,.01923,
.02475,.01414,
180.*
4,1,15,.01414,-.02475,
.009627,-.026829,
.004822,-.028094,
-.000129,-.028504,
-.005077,-.028049,
-.009871,-.026741,
-.01414,-.02475,
-.01923,-.02984,
-.013756,-.032726,
-.007864,-.034617,
-.001734,-.035457,
.00445,-.03522,
.010498,-.033912,
.016227,-.031574,
.01923,-.02984,
.01414,-.02475,
180.*
4,1,15,-.02475,-.01414,
-.026829,-.009627,
-.028094,-.004822,
-.028504,.000129,
-.028049,.005077,
-.026741,.009871,
-.02475,.01414,
-.02984,.01923,
-.032726,.013756,
-.034617,.007864,
-.035457,.001734,
-.03522,-.00445,
-.033912,-.010498,
-.031574,-.016227,
-.02984,-.01923,
-.02475,-.01414,
180.*
4,1,15,-.01414,.02475,
-.009627,.026829,
-.004822,.028094,
.000129,.028504,
.005077,.028049,
.009871,.026741,
.01414,.02475,
.01923,.02984,
.013756,.032726,
.007864,.034617,
.001734,.035457,
-.00445,.03522,
-.010498,.033912,
-.016227,.031574,
-.01923,.02984,
-.01414,.02475,
180.*
%
%ADD69MACRO69*%
%AMMACRO57*
4,1,18,.07103,.05689,
.07983,.043691,
.086204,.029165,
.089959,.013753,
.09098,-.002077,
.089237,-.017844,
.084783,-.033069,
.077753,-.047289,
.07103,-.05689,
.07601,-.06186,
.085597,-.047721,
.092583,-.032132,
.096757,-.015567,
.09799,.001471,
.096246,.018464,
.091577,.034897,
.084126,.050269,
.07601,.06186,
.07103,.05689,
270.*
4,1,18,.05689,-.07103,
.043691,-.07983,
.029165,-.086204,
.013753,-.089959,
-.002077,-.09098,
-.017844,-.089237,
-.033069,-.084783,
-.047289,-.077753,
-.05689,-.07103,
-.06186,-.07601,
-.047721,-.085597,
-.032132,-.092583,
-.015567,-.096757,
.001471,-.09799,
.018464,-.096246,
.034897,-.091577,
.050269,-.084126,
.06186,-.07601,
.05689,-.07103,
270.*
4,1,18,-.07103,-.05689,
-.07983,-.043691,
-.086204,-.029165,
-.089959,-.013753,
-.09098,.002077,
-.089237,.017844,
-.084783,.033069,
-.077753,.047289,
-.07103,.05689,
-.07601,.06186,
-.085597,.047721,
-.092583,.032132,
-.096757,.015567,
-.09799,-.001471,
-.096246,-.018464,
-.091577,-.034897,
-.084126,-.050269,
-.07601,-.06186,
-.07103,-.05689,
270.*
4,1,18,-.05689,.07103,
-.043691,.07983,
-.029165,.086204,
-.013753,.089959,
.002077,.09098,
.017844,.089237,
.033069,.084783,
.047289,.077753,
.05689,.07103,
.06186,.07601,
.047721,.085597,
.032132,.092583,
.015567,.096757,
-.001471,.09799,
-.018464,.096246,
-.034897,.091577,
-.050269,.084126,
-.06186,.07601,
-.05689,.07103,
270.*
%
%ADD57MACRO57*%
%AMMACRO49*
4,1,16,.02657,.01597,
.02894,.011114,
.03043,.005919,
.030995,.000545,
.030619,-.004845,
.029313,-.010088,
.027115,-.015025,
.02657,-.01597,
.03164,-.02104,
.034813,-.015226,
.036928,-.00895,
.037921,-.002401,
.037762,.00422,
.036455,.010713,
.034041,.016881,
.03164,.02104,
.02657,.01597,
180.*
4,1,16,.01597,-.02657,
.011114,-.02894,
.005919,-.03043,
.000545,-.030995,
-.004845,-.030619,
-.010088,-.029313,
-.015025,-.027115,
-.01597,-.02657,
-.02104,-.03164,
-.015226,-.034813,
-.00895,-.036928,
-.002401,-.037921,
.00422,-.037762,
.010713,-.036455,
.016881,-.034041,
.02104,-.03164,
.01597,-.02657,
180.*
4,1,16,-.02657,-.01597,
-.02894,-.011114,
-.03043,-.005919,
-.030995,-.000545,
-.030619,.004845,
-.029313,.010088,
-.027115,.015025,
-.02657,.01597,
-.03164,.02104,
-.034813,.015226,
-.036928,.00895,
-.037921,.002401,
-.037762,-.00422,
-.036455,-.010713,
-.034041,-.016881,
-.03164,-.02104,
-.02657,-.01597,
180.*
4,1,16,-.01597,.02657,
-.011114,.02894,
-.005919,.03043,
-.000545,.030995,
.004845,.030619,
.010088,.029313,
.015025,.027115,
.01597,.02657,
.02104,.03164,
.015226,.034813,
.00895,.036928,
.002401,.037921,
-.00422,.037762,
-.010713,.036455,
-.016881,.034041,
-.02104,.03164,
-.01597,.02657,
180.*
%
%ADD49MACRO49*%
%AMMACRO58*
4,1,15,.04124,.02356,
.044705,.016041,
.046811,.008034,
.047495,-.000216,
.046736,-.008461,
.044557,-.016448,
.04124,-.02356,
.04635,-.02867,
.050624,-.020186,
.05336,-.011088,
.054475,-.001654,
.053935,.007831,
.051756,.017077,
.048004,.025805,
.04635,.02867,
.04124,.02356,
0.0*
4,1,15,.02356,-.04124,
.016041,-.044705,
.008034,-.046811,
-.000216,-.047495,
-.008461,-.046736,
-.016448,-.044557,
-.02356,-.04124,
-.02867,-.04635,
-.020186,-.050624,
-.011088,-.05336,
-.001654,-.054475,
.007831,-.053935,
.017077,-.051756,
.025805,-.048004,
.02867,-.04635,
.02356,-.04124,
0.0*
4,1,15,-.04124,-.02356,
-.044705,-.016041,
-.046811,-.008034,
-.047495,.000216,
-.046736,.008461,
-.044557,.016448,
-.04124,.02356,
-.04635,.02867,
-.050624,.020186,
-.05336,.011088,
-.054475,.001654,
-.053935,-.007831,
-.051756,-.017077,
-.048004,-.025805,
-.04635,-.02867,
-.04124,-.02356,
0.0*
4,1,15,-.02356,.04124,
-.016041,.044705,
-.008034,.046811,
.000216,.047495,
.008461,.046736,
.016448,.044557,
.02356,.04124,
.02867,.04635,
.020186,.050624,
.011088,.05336,
.001654,.054475,
-.007831,.053935,
-.017077,.051756,
-.025805,.048004,
-.02867,.04635,
-.02356,.04124,
0.0*
%
%ADD58MACRO58*%
%AMMACRO78*
4,1,15,.03682,.01914,
.039584,.012455,
.041146,.005393,
.041457,-.001834,
.040509,-.009005,
.03833,-.015903,
.03682,-.01914,
.04197,-.0243,
.045552,-.016643,
.04775,-.00848,
.048497,-.000059,
.047771,.008363,
.045593,.016531,
.042029,.024197,
.04197,.0243,
.03682,.01914,
180.*
4,1,15,.01914,-.03682,
.012455,-.039584,
.005393,-.041146,
-.001834,-.041457,
-.009005,-.040509,
-.015903,-.03833,
-.01914,-.03682,
-.0243,-.04197,
-.016643,-.045552,
-.00848,-.04775,
-.000059,-.048497,
.008363,-.047771,
.016531,-.045593,
.024197,-.042029,
.0243,-.04197,
.01914,-.03682,
180.*
4,1,15,-.03682,-.01914,
-.039584,-.012455,
-.041146,-.005393,
-.041457,.001834,
-.040509,.009005,
-.03833,.015903,
-.03682,.01914,
-.04197,.0243,
-.045552,.016643,
-.04775,.00848,
-.048497,.000059,
-.047771,-.008363,
-.045593,-.016531,
-.042029,-.024197,
-.04197,-.0243,
-.03682,-.01914,
180.*
4,1,15,-.01914,.03682,
-.012455,.039584,
-.005393,.041146,
.001834,.041457,
.009005,.040509,
.015903,.03833,
.01914,.03682,
.0243,.04197,
.016643,.045552,
.00848,.04775,
.000059,.048497,
-.008363,.047771,
-.016531,.045593,
-.024197,.042029,
-.0243,.04197,
-.01914,.03682,
180.*
%
%ADD78MACRO78*%
%AMMACRO76*
4,1,15,-.03682,.01914,
-.039584,.012455,
-.041146,.005393,
-.041457,-.001834,
-.040509,-.009005,
-.03833,-.015903,
-.03682,-.01914,
-.04197,-.0243,
-.045552,-.016643,
-.04775,-.00848,
-.048497,-.000059,
-.047771,.008363,
-.045593,.016531,
-.042029,.024197,
-.04197,.0243,
-.03682,.01914,
180.*
4,1,15,-.01914,-.03682,
-.012455,-.039584,
-.005393,-.041146,
.001834,-.041457,
.009005,-.040509,
.015903,-.03833,
.01914,-.03682,
.0243,-.04197,
.016643,-.045552,
.00848,-.04775,
.000059,-.048497,
-.008363,-.047771,
-.016531,-.045593,
-.024197,-.042029,
-.0243,-.04197,
-.01914,-.03682,
180.*
4,1,15,.03682,-.01914,
.039584,-.012455,
.041146,-.005393,
.041457,.001834,
.040509,.009005,
.03833,.015903,
.03682,.01914,
.04197,.0243,
.045552,.016643,
.04775,.00848,
.048497,.000059,
.047771,-.008363,
.045593,-.016531,
.042029,-.024197,
.04197,-.0243,
.03682,-.01914,
180.*
4,1,15,.01914,.03682,
.012455,.039584,
.005393,.041146,
-.001834,.041457,
-.009005,.040509,
-.015903,.03833,
-.01914,.03682,
-.0243,.04197,
-.016643,.045552,
-.00848,.04775,
-.000059,.048497,
.008363,.047771,
.016531,.045593,
.024197,.042029,
.0243,.04197,
.01914,.03682,
180.*
%
%ADD76MACRO76*%
%ADD83C,.006*%
%ADD93C,.07005*%
%ADD100C,.07006*%
%ADD109C,.0761*%
%ADD87C,.07306*%
%ADD94C,.07608*%
%ADD97C,.07808*%
%ADD98C,.09708*%
%ADD105C,.311*%
%ADD108O,.03004X.07004*%
%ADD99C,.11006*%
%ADD104O,.03004X.06404*%
%ADD110C,.31502*%
%ADD103O,.03006X.06406*%
%ADD107O,.03004X.06904*%
%ADD91C,.16206*%
%ADD95C,.43406*%
%ADD85O,.03404X.06804*%
%ADD84C,.16506*%
%ADD106O,.03006X.06906*%
%ADD102O,.2363X.2993*%
%ADD96C,.25806*%
%ADD86O,.03406X.06806*%
%ADD90C,.19806*%
%ADD89C,.19807*%
%ADD88C,.19809*%
%ADD92C,.19786*%
%ADD101O,.43374X.77626*%
G75*
%LPD*%
G75*
G36*
G01X-476840Y-884638D02*
X5911000D01*
Y2768362D01*
X-476840D01*
Y-884638D01*
G37*
%LPC*%
G75*
G36*
G01X1007087Y132327D02*
G02X1009020Y130394I0J-1933D01*
G01Y46378D01*
G03X1018898Y36500I9878J0D01*
G01X1510244D01*
G02X1516114Y30630I0J-5870D01*
G01Y-1575D01*
G03X1525992Y-11453I9878J0D01*
G01X1796071D01*
G03X1805949Y-1575I0J9878D01*
G01Y30630D01*
G02X1811819Y36500I5870J0D01*
G01X1849606D01*
G02X1855476Y30630I0J-5870D01*
G01Y-40945D01*
G02X1849606Y-46815I-5870J0D01*
G01X7874D01*
G02X2004Y-40945I0J5870D01*
G01Y30630D01*
G02X7874Y36500I5870J0D01*
G01X35835D01*
G02X41705Y30630I0J-5870D01*
G01Y-1575D01*
G03X51583Y-11453I9878J0D01*
G01X321661D01*
G03X331539Y-1575I0J9878D01*
G01Y30630D01*
G02X337409Y36500I5870J0D01*
G01X480717D01*
G02X486587Y30630I0J-5870D01*
G01Y19212D01*
G03X496465Y9334I9878J0D01*
G01X766543D01*
G03X776421Y19212I0J9878D01*
G01Y30630D01*
G02X782291Y36500I5870J0D01*
G01X879134D01*
G03X889012Y46378I0J9878D01*
G01Y130394D01*
G02X890945Y132327I1933J0D01*
G01X1007087D01*
G37*
G36*
G01X1855476Y54252D02*
G02X1849606Y48382I-5870J0D01*
G01X1803945D01*
G03X1794067Y38504I0J-9878D01*
G01Y2204D01*
G02X1793867Y2004I-200J0D01*
G01X1528196D01*
G02X1527996Y2204I0J200D01*
G01Y38504D01*
G03X1518118Y48382I-9878J0D01*
G01X1026772D01*
G02X1020902Y54252I0J5870D01*
G01Y134331D01*
G03X1011024Y144209I-9878J0D01*
G01X887008D01*
G03X877130Y134331I0J-9878D01*
G01Y54252D01*
G02X871260Y48382I-5870J0D01*
G01X774417D01*
G03X764539Y38504I0J-9878D01*
G01Y22991D01*
G02X764339Y22791I-200J0D01*
G01X498669D01*
G02X498469Y22991I0J200D01*
G01Y38504D01*
G03X488591Y48382I-9878J0D01*
G01X329535D01*
G03X319657Y38504I0J-9878D01*
G01Y2204D01*
G02X319457Y2004I-200J0D01*
G01X53787D01*
G02X53587Y2204I0J200D01*
G01Y38504D01*
G03X43709Y48382I-9878J0D01*
G01X7874D01*
G02X2004Y54252I0J5870D01*
G01Y305795D01*
G02X3723Y309944I5869J-1D01*
G01X6985Y313206D01*
G03X9878Y320190I-6985J6985D01*
G01Y1588078D01*
G02X11597Y1592228I5870J-1D01*
G01X24701Y1605332D01*
G03X27595Y1612317I-6985J6986D01*
G01Y1732244D01*
G02X33465Y1738114I5870J0D01*
G01X765532D01*
G02X765732Y1737914I0J-200D01*
G01Y1736890D01*
G03X769705Y1732917I3973J0D01*
G01X1087854D01*
G03X1091827Y1736890I0J3973D01*
G01Y1737914D01*
G02X1092027Y1738114I200J0D01*
G01X1824016D01*
G02X1829886Y1732244I0J-5870D01*
G01Y1612316D01*
G03X1832779Y1605332I9878J1D01*
G01X1839978Y1598133D01*
G02X1841697Y1593984I-4150J-4150D01*
G01Y326095D01*
G03X1844590Y319111I9878J1D01*
G01X1853757Y309944D01*
G02X1855476Y305795I-4150J-4150D01*
G01Y54252D01*
G37*
G36*
G01X1873228Y1820942D02*
X2093700D01*
G02X2099570Y1815072I0J-5870D01*
G01Y1791450D01*
G02X2093700Y1785580I-5870J0D01*
G01X2031574D01*
G03X2021696Y1775702I0J-9878D01*
G01Y1229954D01*
G03X2031574Y1220076I9878J0D01*
G01X2093700D01*
G02X2099570Y1214206I0J-5870D01*
G01Y-40945D01*
G02X2093700Y-46815I-5870J0D01*
G01X1873228D01*
G02X1867358Y-40945I0J5870D01*
G01Y305795D01*
G03X1862159Y318346I-17750J0D01*
G01X1855299Y325206D01*
G02X1853579Y329357I4150J4151D01*
G01Y1593984D01*
G03X1848380Y1606535I-17750J0D01*
G01X1843487Y1611428D01*
G02X1841768Y1615578I4151J4150D01*
G01Y1732244D01*
G02X1847638Y1738114I5870J0D01*
G01X1857480D01*
G03X1867358Y1747992I0J9878D01*
G01Y1815072D01*
G02X1873228Y1820942I5870J0D01*
G37*
%LPD*%
G75*
G36*
G01X741579Y1609865D02*
G02X742998Y1610166I1421J-3202D01*
G02X744417Y1609865I-2J-3503D01*
G03X744579I81J183D01*
G02X745998Y1610166I1421J-3202D01*
G02X749500Y1606663I-1J-3503D01*
G01Y1606661D01*
G02X749200Y1605244I-3502J1D01*
G03Y1605082I183J-81D01*
G02X749500Y1603663I-3202J-1418D01*
G02X749157Y1602149I-3502J-2D01*
G03Y1601977I180J-86D01*
G02X749500Y1600463I-3159J-1512D01*
G02X749200Y1599044I-3502J-1D01*
G03Y1598882I183J-81D01*
G02X749500Y1597463I-3202J-1418D01*
G02X749200Y1596044I-3502J-1D01*
G03Y1595882I183J-81D01*
G02X749500Y1594463I-3202J-1418D01*
G02X745998Y1590960I-3502J-1D01*
G02X744579Y1591261I2J3503D01*
G03X744417I-81J-183D01*
G02X742998Y1590960I-1421J3202D01*
G02X741579Y1591261I2J3503D01*
G03X741417I-81J-183D01*
G02X740970Y1591098I-1421J3201D01*
G01X740913Y1591082D01*
X740837Y1590996D01*
X740770Y1590580D01*
G03X740855Y1590383I198J-32D01*
G02X742382Y1587491I-1975J-2892D01*
G02X741459Y1585121I-3504J0D01*
G03X741406Y1584986I147J-136D01*
G01Y1584866D01*
G03X741459Y1584731I200J1D01*
G02Y1579991I-2580J-2370D01*
G03X741406Y1579856I147J-136D01*
G01Y1579736D01*
G03X741459Y1579601I200J1D01*
G02X742382Y1577231I-2581J-2370D01*
G01Y1577229D01*
G02X738880Y1573728I-3502J1D01*
G02X736412Y1574746I1J3503D01*
G01X736411Y1574747D01*
G03X736271Y1574804I-140J-143D01*
G01X735989D01*
G03X735849Y1574747I0J-200D01*
G01X735848Y1574746D01*
G02X733380Y1573728I-2469J2485D01*
G02X730867Y1574791I0J3502D01*
G03X730723Y1574852I-144J-139D01*
G01X730437D01*
G03X730293Y1574791I0J-200D01*
G02X727780Y1573728I-2513J2439D01*
G02X724278Y1577231I1J3503D01*
G02X725201Y1579601I3504J0D01*
G03X725254Y1579736I-147J136D01*
G01Y1579856D01*
G03X725201Y1579991I-200J-1D01*
G02Y1584731I2580J2370D01*
G03X725254Y1584866I-147J136D01*
G01Y1584986D01*
G03X725201Y1585121I-200J-1D01*
G02X724278Y1587491I2581J2370D01*
G01Y1587493D01*
G02X727780Y1590994I3502J-1D01*
G02X730293Y1589931I0J-3502D01*
G03X730437Y1589870I144J139D01*
G01X730723D01*
G03X730867Y1589931I0J200D01*
G02X731217Y1590246I2513J-2440D01*
G03X731283Y1590468I-123J157D01*
G01X731161Y1590826D01*
G03X730973Y1590961I-189J-65D01*
G02X727496Y1594463I25J3502D01*
G01Y1594465D01*
G02X727796Y1595882I3502J-1D01*
G03Y1596044I-183J81D01*
G02X727496Y1597463I3202J1418D01*
G02X727796Y1598882I3502J1D01*
G03Y1599044I-183J81D01*
G02X727496Y1600463I3202J1418D01*
G02X727839Y1601977I3502J2D01*
G03Y1602149I-180J86D01*
G02X727496Y1603663I3159J1512D01*
G02X727796Y1605082I3502J1D01*
G03Y1605244I-183J81D01*
G02X727496Y1606663I3202J1418D01*
G02X730998Y1610166I3502J1D01*
G02X732417Y1609865I-2J-3503D01*
G03X732579I81J183D01*
G02X733998Y1610166I1421J-3202D01*
G02X735417Y1609865I-2J-3503D01*
G03X735579I81J183D01*
G02X736998Y1610166I1421J-3202D01*
G02X738417Y1609865I-2J-3503D01*
G03X738579I81J183D01*
G02X739998Y1610166I1421J-3202D01*
G02X741417Y1609865I-2J-3503D01*
G03X741579I81J183D01*
G37*
G36*
G01X916131Y1609735D02*
G02X917550Y1610036I1421J-3202D01*
G02X918969Y1609735I-2J-3503D01*
G03X919131I81J183D01*
G02X920550Y1610036I1421J-3202D01*
G02X924052Y1606533I-1J-3503D01*
G01Y1606531D01*
G02X923752Y1605114I-3502J1D01*
G03Y1604952I183J-81D01*
G02X924052Y1603535I-3202J-1418D01*
G01Y1603533D01*
G02X921161Y1600084I-3503J0D01*
G03X920999Y1599922I35J-197D01*
G02X920752Y1599114I-3449J612D01*
G03Y1598952I183J-81D01*
G02X921052Y1597533I-3202J-1418D01*
G02X920752Y1596114I-3502J-1D01*
G03Y1595952I183J-81D01*
G02X921052Y1594533I-3202J-1418D01*
G02X918832Y1591273I-3503J-1D01*
G01X918777Y1591252D01*
X918709Y1591159D01*
X918681Y1590740D01*
G03X918783Y1590552I200J-13D01*
G02X920580Y1587493I-1705J-3059D01*
G02X919656Y1585123I-3503J1D01*
G03X919603Y1584988I147J-136D01*
G01Y1584868D01*
G03X919656Y1584733I200J1D01*
G02X920580Y1582363I-2579J-2371D01*
G02X919656Y1579993I-3503J1D01*
G03X919603Y1579858I147J-136D01*
G01Y1579738D01*
G03X919656Y1579603I200J1D01*
G02X920580Y1577233I-2579J-2371D01*
G02X917077Y1573730I-3503J0D01*
G02X914609Y1574748I1J3503D01*
G01X914608Y1574749D01*
G03X914468Y1574806I-140J-143D01*
G01X914186D01*
G03X914046Y1574749I0J-200D01*
G01X914045Y1574748D01*
G02X911577Y1573730I-2469J2485D01*
G02X909064Y1574793I0J3502D01*
G03X908920Y1574854I-144J-139D01*
G01X908634D01*
G03X908490Y1574793I0J-200D01*
G02X905977Y1573730I-2513J2439D01*
G02X902474Y1577233I0J3503D01*
G02X903398Y1579603I3503J-1D01*
G03X903451Y1579738I-147J136D01*
G01Y1579858D01*
G03X903398Y1579993I-200J-1D01*
G02X902474Y1582363I2579J2371D01*
G02X903398Y1584733I3503J-1D01*
G03X903451Y1584868I-147J136D01*
G01Y1584988D01*
G03X903398Y1585123I-200J-1D01*
G02X902474Y1587493I2579J2371D01*
G02X904288Y1590561I3503J-1D01*
G03X904391Y1590748I-97J175D01*
G01X904370Y1591109D01*
G03X904244Y1591283I-200J-12D01*
G02X902048Y1594533I1307J3250D01*
G01Y1594535D01*
G02X902348Y1595952I3502J-1D01*
G03Y1596114I-183J81D01*
G02X902048Y1597533I3202J1418D01*
G02X902348Y1598952I3502J1D01*
G03Y1599114I-183J81D01*
G02X902101Y1599922I3202J1420D01*
G03X901939Y1600084I-197J-35D01*
G02X899101Y1602922I611J3449D01*
G03X898939Y1603084I-197J-35D01*
G02X896048Y1606533I612J3449D01*
G01Y1606535D01*
G02X899550Y1610036I3502J-1D01*
G02X900969Y1609735I-2J-3503D01*
G03X901131I81J183D01*
G02X902550Y1610036I1421J-3202D01*
G02X903969Y1609735I-2J-3503D01*
G03X904131I81J183D01*
G02X905550Y1610036I1421J-3202D01*
G02X906969Y1609735I-2J-3503D01*
G03X907131I81J183D01*
G02X908550Y1610036I1421J-3202D01*
G02X909969Y1609735I-2J-3503D01*
G03X910131I81J183D01*
G02X911550Y1610036I1421J-3202D01*
G02X912969Y1609735I-2J-3503D01*
G03X913131I81J183D01*
G02X914550Y1610036I1421J-3202D01*
G02X915969Y1609735I-2J-3503D01*
G03X916131I81J183D01*
G37*
G36*
G01X874131D02*
G02X875550Y1610036I1421J-3202D01*
G02X876969Y1609735I-2J-3503D01*
G03X877131I81J183D01*
G02X878550Y1610036I1421J-3202D01*
G02X882052Y1606533I-1J-3503D01*
G01Y1606531D01*
G02X881752Y1605114I-3502J1D01*
G03Y1604952I183J-81D01*
G02X882052Y1603535I-3202J-1418D01*
G01Y1603533D01*
G02X879161Y1600084I-3503J0D01*
G03X878999Y1599922I35J-197D01*
G02X878752Y1599114I-3449J612D01*
G03Y1598952I183J-81D01*
G02X879052Y1597533I-3202J-1418D01*
G02X878752Y1596114I-3502J-1D01*
G03Y1595952I183J-81D01*
G02X879052Y1594533I-3202J-1418D01*
G02X876832Y1591273I-3503J-1D01*
G01X876777Y1591252D01*
X876709Y1591159D01*
X876681Y1590740D01*
G03X876783Y1590552I200J-13D01*
G02X878580Y1587493I-1705J-3059D01*
G02X877656Y1585123I-3503J1D01*
G03X877603Y1584988I147J-136D01*
G01Y1584868D01*
G03X877656Y1584733I200J1D01*
G02X878580Y1582363I-2579J-2371D01*
G02X877656Y1579993I-3503J1D01*
G03X877603Y1579858I147J-136D01*
G01Y1579738D01*
G03X877656Y1579603I200J1D01*
G02X878580Y1577233I-2579J-2371D01*
G02X875077Y1573730I-3503J0D01*
G02X872609Y1574748I1J3503D01*
G01X872608Y1574749D01*
G03X872468Y1574806I-140J-143D01*
G01X872186D01*
G03X872046Y1574749I0J-200D01*
G01X872045Y1574748D01*
G02X869577Y1573730I-2469J2485D01*
G02X867064Y1574793I0J3502D01*
G03X866920Y1574854I-144J-139D01*
G01X866634D01*
G03X866490Y1574793I0J-200D01*
G02X863977Y1573730I-2513J2439D01*
G02X860474Y1577233I0J3503D01*
G02X861398Y1579603I3503J-1D01*
G03X861451Y1579738I-147J136D01*
G01Y1579858D01*
G03X861398Y1579993I-200J-1D01*
G02X860474Y1582363I2579J2371D01*
G02X861398Y1584733I3503J-1D01*
G03X861451Y1584868I-147J136D01*
G01Y1584988D01*
G03X861398Y1585123I-200J-1D01*
G02X860474Y1587493I2579J2371D01*
G02X862288Y1590561I3503J-1D01*
G03X862391Y1590748I-97J175D01*
G01X862370Y1591109D01*
G03X862244Y1591283I-200J-12D01*
G02X860048Y1594533I1307J3250D01*
G01Y1594535D01*
G02X860348Y1595952I3502J-1D01*
G03Y1596114I-183J81D01*
G02X860048Y1597533I3202J1418D01*
G02X860348Y1598952I3502J1D01*
G03Y1599114I-183J81D01*
G02X860101Y1599922I3202J1420D01*
G03X859939Y1600084I-197J-35D01*
G02X857101Y1602922I611J3449D01*
G03X856939Y1603084I-197J-35D01*
G02X854048Y1606533I612J3449D01*
G01Y1606535D01*
G02X857550Y1610036I3502J-1D01*
G02X858969Y1609735I-2J-3503D01*
G03X859131I81J183D01*
G02X860550Y1610036I1421J-3202D01*
G02X861969Y1609735I-2J-3503D01*
G03X862131I81J183D01*
G02X863550Y1610036I1421J-3202D01*
G02X864969Y1609735I-2J-3503D01*
G03X865131I81J183D01*
G02X866550Y1610036I1421J-3202D01*
G02X867969Y1609735I-2J-3503D01*
G03X868131I81J183D01*
G02X869550Y1610036I1421J-3202D01*
G02X870969Y1609735I-2J-3503D01*
G03X871131I81J183D01*
G02X872550Y1610036I1421J-3202D01*
G02X873969Y1609735I-2J-3503D01*
G03X874131I81J183D01*
G37*
G36*
G01X832131D02*
G02X833550Y1610036I1421J-3202D01*
G02X834969Y1609735I-2J-3503D01*
G03X835131I81J183D01*
G02X836550Y1610036I1421J-3202D01*
G02X840052Y1606533I-1J-3503D01*
G01Y1606531D01*
G02X839752Y1605114I-3502J1D01*
G03Y1604952I183J-81D01*
G02X840052Y1603535I-3202J-1418D01*
G01Y1603533D01*
G02X837161Y1600084I-3503J0D01*
G03X836999Y1599922I35J-197D01*
G02X836752Y1599114I-3449J612D01*
G03Y1598952I183J-81D01*
G02X837052Y1597533I-3202J-1418D01*
G02X836752Y1596114I-3502J-1D01*
G03Y1595952I183J-81D01*
G02X837052Y1594533I-3202J-1418D01*
G02X834832Y1591273I-3503J-1D01*
G01X834777Y1591252D01*
X834709Y1591159D01*
X834681Y1590740D01*
G03X834783Y1590552I200J-13D01*
G02X836580Y1587493I-1705J-3059D01*
G02X835656Y1585123I-3503J1D01*
G03X835603Y1584988I147J-136D01*
G01Y1584868D01*
G03X835656Y1584733I200J1D01*
G02X836580Y1582363I-2579J-2371D01*
G02X835656Y1579993I-3503J1D01*
G03X835603Y1579858I147J-136D01*
G01Y1579738D01*
G03X835656Y1579603I200J1D01*
G02X836580Y1577233I-2579J-2371D01*
G02X833077Y1573730I-3503J0D01*
G02X830609Y1574748I1J3503D01*
G01X830608Y1574749D01*
G03X830468Y1574806I-140J-143D01*
G01X830186D01*
G03X830046Y1574749I0J-200D01*
G01X830045Y1574748D01*
G02X827577Y1573730I-2469J2485D01*
G02X825064Y1574793I0J3502D01*
G03X824920Y1574854I-144J-139D01*
G01X824634D01*
G03X824490Y1574793I0J-200D01*
G02X821977Y1573730I-2513J2439D01*
G02X818474Y1577233I0J3503D01*
G02X819398Y1579603I3503J-1D01*
G03X819451Y1579738I-147J136D01*
G01Y1579858D01*
G03X819398Y1579993I-200J-1D01*
G02X818474Y1582363I2579J2371D01*
G02X819398Y1584733I3503J-1D01*
G03X819451Y1584868I-147J136D01*
G01Y1584988D01*
G03X819398Y1585123I-200J-1D01*
G02X818474Y1587493I2579J2371D01*
G02X820288Y1590561I3503J-1D01*
G03X820391Y1590748I-97J175D01*
G01X820370Y1591109D01*
G03X820244Y1591283I-200J-12D01*
G02X818048Y1594533I1307J3250D01*
G01Y1594535D01*
G02X818348Y1595952I3502J-1D01*
G03Y1596114I-183J81D01*
G02X818048Y1597533I3202J1418D01*
G02X818348Y1598952I3502J1D01*
G03Y1599114I-183J81D01*
G02X818101Y1599922I3202J1420D01*
G03X817939Y1600084I-197J-35D01*
G02X815101Y1602922I611J3449D01*
G03X814939Y1603084I-197J-35D01*
G02X812048Y1606533I612J3449D01*
G01Y1606535D01*
G02X815550Y1610036I3502J-1D01*
G02X816969Y1609735I-2J-3503D01*
G03X817131I81J183D01*
G02X818550Y1610036I1421J-3202D01*
G02X819969Y1609735I-2J-3503D01*
G03X820131I81J183D01*
G02X821550Y1610036I1421J-3202D01*
G02X822969Y1609735I-2J-3503D01*
G03X823131I81J183D01*
G02X824550Y1610036I1421J-3202D01*
G02X825969Y1609735I-2J-3503D01*
G03X826131I81J183D01*
G02X827550Y1610036I1421J-3202D01*
G02X828969Y1609735I-2J-3503D01*
G03X829131I81J183D01*
G02X830550Y1610036I1421J-3202D01*
G02X831969Y1609735I-2J-3503D01*
G03X832131I81J183D01*
G37*
G36*
G01X787131D02*
G02X788550Y1610036I1421J-3202D01*
G02X789969Y1609735I-2J-3503D01*
G03X790131I81J183D01*
G02X791550Y1610036I1421J-3202D01*
G02X795052Y1606533I-1J-3503D01*
G01Y1606531D01*
G02X794752Y1605114I-3502J1D01*
G03Y1604952I183J-81D01*
G02X795052Y1603533I-3202J-1418D01*
G02X794752Y1602114I-3502J-1D01*
G03Y1601952I183J-81D01*
G02X795052Y1600533I-3202J-1418D01*
G02X794752Y1599114I-3502J-1D01*
G03Y1598952I183J-81D01*
G02X795052Y1597533I-3202J-1418D01*
G02X794752Y1596114I-3502J-1D01*
G03Y1595952I183J-81D01*
G02X795052Y1594533I-3202J-1418D01*
G02X792832Y1591273I-3503J-1D01*
G01X792777Y1591252D01*
X792709Y1591159D01*
X792681Y1590740D01*
G03X792783Y1590552I200J-13D01*
G02X794580Y1587493I-1705J-3059D01*
G02X793656Y1585123I-3503J1D01*
G03X793603Y1584988I147J-136D01*
G01Y1584868D01*
G03X793656Y1584733I200J1D01*
G02X794580Y1582363I-2579J-2371D01*
G02X793656Y1579993I-3503J1D01*
G03X793603Y1579858I147J-136D01*
G01Y1579738D01*
G03X793656Y1579603I200J1D01*
G02X794580Y1577233I-2579J-2371D01*
G02X791077Y1573730I-3503J0D01*
G02X788609Y1574748I1J3503D01*
G01X788608Y1574749D01*
G03X788468Y1574806I-140J-143D01*
G01X788186D01*
G03X788046Y1574749I0J-200D01*
G01X788045Y1574748D01*
G02X785577Y1573730I-2469J2485D01*
G02X783064Y1574793I0J3502D01*
G03X782920Y1574854I-144J-139D01*
G01X782634D01*
G03X782490Y1574793I0J-200D01*
G02X779977Y1573730I-2513J2439D01*
G02X776474Y1577233I0J3503D01*
G02X777398Y1579603I3503J-1D01*
G03X777451Y1579738I-147J136D01*
G01Y1579858D01*
G03X777398Y1579993I-200J-1D01*
G02X776474Y1582363I2579J2371D01*
G02X777398Y1584733I3503J-1D01*
G03X777451Y1584868I-147J136D01*
G01Y1584988D01*
G03X777398Y1585123I-200J-1D01*
G02X776474Y1587493I2579J2371D01*
G02X778288Y1590561I3503J-1D01*
G03X778391Y1590748I-97J175D01*
G01X778370Y1591109D01*
G03X778244Y1591283I-200J-12D01*
G02X778131Y1591331I1313J3247D01*
G03X777969I-81J-183D01*
G02X776550Y1591030I-1421J3202D01*
G02X773048Y1594533I1J3503D01*
G01Y1594535D01*
G02X773348Y1595952I3502J-1D01*
G03Y1596114I-183J81D01*
G02X773048Y1597533I3202J1418D01*
G02X773348Y1598952I3502J1D01*
G03Y1599114I-183J81D01*
G02X773048Y1600533I3202J1418D01*
G02X773348Y1601952I3502J1D01*
G03Y1602114I-183J81D01*
G02X773048Y1603533I3202J1418D01*
G02X773348Y1604952I3502J1D01*
G03Y1605114I-183J81D01*
G02X773048Y1606533I3202J1418D01*
G02X776550Y1610036I3502J1D01*
G02X777969Y1609735I-2J-3503D01*
G03X778131I81J183D01*
G02X779550Y1610036I1421J-3202D01*
G02X780969Y1609735I-2J-3503D01*
G03X781131I81J183D01*
G02X782550Y1610036I1421J-3202D01*
G02X783969Y1609735I-2J-3503D01*
G03X784131I81J183D01*
G02X785550Y1610036I1421J-3202D01*
G02X786969Y1609735I-2J-3503D01*
G03X787131I81J183D01*
G37*
G36*
G01X1729836Y56026D02*
G02X1731332Y54658I0J-1502D01*
G03X1731443Y54496I199J18D01*
G02X1733398Y51354I-1547J-3142D01*
G02X1733316Y50602I-3503J1D01*
G03X1733334Y50465I195J-44D01*
G02X1733744Y48822I-3093J-1644D01*
G02X1733586Y47785I-3503J3D01*
G01X1733567Y47725D01*
X1733604Y47607D01*
X1733950Y47338D01*
G03X1734177Y47325I123J158D01*
G02X1736004Y47840I1828J-2987D01*
G01X1736006D01*
G02X1739508Y44338I0J-3502D01*
G01Y44335D01*
G02X1739303Y43155I-3502J1D01*
G03Y43021I188J-67D01*
G02X1739508Y41841I-3297J-1181D01*
G01Y41838D01*
G02X1732504I-3502J0D01*
G01Y41841D01*
G02X1732709Y43021I3502J-1D01*
G03Y43155I-188J67D01*
G02X1732504Y44335I3297J1181D01*
G01Y44338D01*
G02X1732661Y45375I3503J0D01*
G01X1732680Y45435D01*
X1732643Y45553D01*
X1732297Y45822D01*
G03X1732070Y45835I-123J-158D01*
G02X1730241Y45320I-1828J2987D01*
G02X1728585Y45735I-2J3502D01*
G03X1728397I-94J-176D01*
G02X1726741Y45320I-1654J3087D01*
G02X1725085Y45735I-2J3502D01*
G03X1724897I-94J-176D01*
G02X1723241Y45320I-1654J3087D01*
G02X1719738Y48822I-1J3502D01*
G02X1721117Y51607I3503J0D01*
G03X1721195Y51749I-121J159D01*
G02X1724685Y54956I3490J-295D01*
G02X1725575Y54842I4J-3502D01*
G03X1725722Y54860I51J193D01*
G01X1725828Y54918D01*
G03X1725920Y55026I-96J175D01*
G02X1727336Y56026I1416J-503D01*
G02X1728323Y55656I0J-1501D01*
G01X1728324D01*
Y55655D01*
G03X1728454Y55607I130J152D01*
G01X1728718D01*
G03X1728848Y55655I0J200D01*
G01X1728849Y55656D01*
G02X1729836Y56026I987J-1131D01*
G37*
G36*
G01X1421732Y1712135D02*
X1421691Y1712101D01*
X1421654Y1712004D01*
X1421716Y1711612D01*
G03X1421837Y1711458I198J31D01*
G02X1430690Y1698268I-5399J-13190D01*
G02X1402184I-14253J0D01*
G02X1402186Y1698468I14253J-43D01*
G01X1402185D01*
G02X1411037Y1711458I14252J-201D01*
G01X1411086Y1711478D01*
X1411150Y1711560D01*
X1411219Y1712004D01*
X1411182Y1712102D01*
X1411142Y1712135D01*
G02X1421732I5295J6330D01*
G37*
G36*
G01X446338D02*
X446297Y1712101D01*
X446260Y1712004D01*
X446322Y1711612D01*
G03X446443Y1711458I198J31D01*
G02X455296Y1698268I-5399J-13190D01*
G02X426790I-14253J0D01*
G02X435643Y1711458I14252J0D01*
G01X435692Y1711478D01*
X435756Y1711560D01*
X435826Y1712004D01*
X435789Y1712101D01*
X435748Y1712135D01*
G02X446338I5295J6330D01*
G37*
G36*
G01X408078Y1575148D02*
Y1575462D01*
G03X408001Y1575620I-200J0D01*
G02X407422Y1576805I923J1185D01*
G02X410428I1503J0D01*
G02X409849Y1575620I-1502J0D01*
G03X409772Y1575462I123J-158D01*
G01Y1575148D01*
G03X409849Y1574990I200J0D01*
G02X410428Y1573805I-923J-1185D01*
G02X407422I-1503J0D01*
G02X408001Y1574990I1502J0D01*
G03X408078Y1575148I-123J158D01*
G37*
G36*
G01X728916Y1423122D02*
G02X729216Y1424541I3502J1D01*
G03Y1424703I-183J81D01*
G02X728916Y1426120I3202J1418D01*
G01Y1426122D01*
G02X732418Y1429624I3502J0D01*
G01X732420D01*
G02X733837Y1429324I-1J-3502D01*
G03X733999I81J183D01*
G02X735416Y1429624I1418J-3202D01*
G01X735418D01*
G02X738920Y1426122I0J-3502D01*
G01Y1426120D01*
G02X738620Y1424703I-3502J1D01*
G03Y1424541I183J-81D01*
G02X738920Y1423122I-3202J-1418D01*
G02X738620Y1421703I-3502J-1D01*
G03Y1421541I183J-81D01*
G02X738920Y1420124I-3202J-1418D01*
G01Y1420122D01*
G02X735418Y1416620I-3502J0D01*
G01X735416D01*
G02X733999Y1416920I1J3502D01*
G03X733837I-81J-183D01*
G02X732420Y1416620I-1418J3202D01*
G01X732418D01*
G02X728916Y1420122I0J3502D01*
G01Y1420124D01*
G02X729216Y1421541I3502J-1D01*
G03Y1421703I-183J81D01*
G02X728916Y1423122I3202J1418D01*
G37*
G36*
G01X1710944Y1420213D02*
G02X1711245Y1421632I3503J-2D01*
G03Y1421794I-183J81D01*
G02X1710944Y1423213I3202J1421D01*
G02X1714447Y1426716I3503J0D01*
G02X1715866Y1426415I-2J-3503D01*
G03X1716028I81J183D01*
G02X1717447Y1426716I1421J-3202D01*
G02X1720950Y1423213I0J-3503D01*
G02X1720649Y1421794I-3503J2D01*
G03Y1421632I183J-81D01*
G02X1720950Y1420213I-3202J-1421D01*
G02X1720649Y1418794I-3503J2D01*
G03Y1418632I183J-81D01*
G02X1720950Y1417213I-3202J-1421D01*
G02X1717447Y1413710I-3503J0D01*
G02X1716028Y1414011I2J3503D01*
G03X1715866I-81J-183D01*
G02X1714447Y1413710I-1421J3202D01*
G02X1710944Y1417213I0J3503D01*
G02X1711245Y1418632I3503J-2D01*
G03Y1418794I-183J81D01*
G02X1710944Y1420213I3202J1421D01*
G37*
G36*
G01X159370Y1411611D02*
G02X159748Y1413192I3503J-2D01*
G03X159760Y1413343I-178J90D01*
G02X159596Y1414400I3339J1059D01*
G02X166602I3503J0D01*
G02X166224Y1412819I-3503J2D01*
G03X166212Y1412668I178J-90D01*
G02X166376Y1411611I-3339J-1059D01*
G02X166238Y1410639I-3503J2D01*
G03X166249Y1410501I192J-54D01*
G02X166564Y1409048I-3188J-1452D01*
G02X166358Y1407866I-3503J2D01*
G03Y1407730I188J-68D01*
G02X166564Y1406548I-3297J-1184D01*
G02X159558I-3503J0D01*
G02X159764Y1407730I3503J-2D01*
G03Y1407866I-188J68D01*
G02X159558Y1409048I3297J1184D01*
G02X159696Y1410020I3503J-2D01*
G03X159685Y1410158I-192J54D01*
G02X159370Y1411611I3188J1452D01*
G37*
G36*
G01X169474Y1411460D02*
G02X169851Y1413041I3502J0D01*
G03X169863Y1413192I-178J90D01*
G02X169700Y1414249I3340J1056D01*
G02X176704I3502J0D01*
G01Y1414248D01*
G02X176327Y1412668I-3502J1D01*
G03X176315Y1412517I178J-90D01*
G02X176478Y1411460I-3340J-1056D01*
G02X176341Y1410488I-3502J-2D01*
G03X176351Y1410350I192J-55D01*
G02X176666Y1408897I-3187J-1452D01*
G02X176461Y1407714I-3502J-2D01*
G03Y1407580I188J-67D01*
G02X176666Y1406400I-3297J-1181D01*
G01Y1406397D01*
G02X169662I-3502J0D01*
G01Y1406400D01*
G02X169867Y1407580I3502J-1D01*
G03Y1407714I-188J67D01*
G02X169662Y1408897I3297J1181D01*
G02X169799Y1409869I3502J2D01*
G03X169789Y1410007I-192J55D01*
G02X169474Y1411460I3187J1452D01*
G37*
G36*
G01X194307Y1413378D02*
G02X195490Y1413173I2J-3502D01*
G03X195624I67J188D01*
G02X196807Y1413378I1181J-3297D01*
G02X197990Y1413173I2J-3502D01*
G03X198124I67J188D01*
G02X199307Y1413378I1181J-3297D01*
G02X202810Y1409876I1J-3502D01*
G02X202672Y1408904I-3503J2D01*
G03X202683Y1408766I192J-54D01*
G02X202998Y1407313I-3188J-1452D01*
G02X202792Y1406131I-3503J2D01*
G03Y1405995I188J-68D01*
G02X202998Y1404813I-3297J-1184D01*
G02X199495Y1401310I-3503J0D01*
G02X198313Y1401516I2J3503D01*
G03X198177I-68J-188D01*
G02X196995Y1401310I-1184J3297D01*
G02X195813Y1401516I2J3503D01*
G03X195677I-68J-188D01*
G02X194495Y1401310I-1184J3297D01*
G02X193313Y1401516I2J3503D01*
G03X193177I-68J-188D01*
G02X191995Y1401310I-1184J3297D01*
G02X190434Y1401678I2J3503D01*
G03X190256I-89J-179D01*
G02X188695Y1401310I-1563J3135D01*
G02X185192Y1404813I0J3503D01*
G02X185398Y1405995I3503J-2D01*
G03Y1406131I-188J68D01*
G02X185192Y1407313I3297J1184D01*
G02X185330Y1408285I3503J-2D01*
G03X185319Y1408423I-192J54D01*
G02X185004Y1409876I3188J1452D01*
G02X188507Y1413378I3503J-1D01*
G02X190068Y1413011I0J-3503D01*
G03X190246I89J179D01*
G02X191807Y1413378I1561J-3136D01*
G01X191810D01*
G02X192990Y1413173I-1J-3502D01*
G03X193124I67J188D01*
G02X194307Y1413378I1181J-3297D01*
G37*
G36*
G01X1132465Y1407380D02*
G02X1133647Y1407174I-2J-3503D01*
G03X1133783I68J188D01*
G02X1134965Y1407380I1184J-3297D01*
G02X1136147Y1407174I-2J-3503D01*
G03X1136283I68J188D01*
G02X1137465Y1407380I1184J-3297D01*
G02X1140968Y1403877I0J-3503D01*
G02X1140762Y1402695I-3503J2D01*
G03Y1402559I188J-68D01*
G02X1140968Y1401377I-3297J-1184D01*
G02X1140718Y1400079I-3503J2D01*
G03X1140716Y1399936I186J-74D01*
G02X1140928Y1398737I-3291J-1200D01*
G02X1137425Y1395234I-3503J0D01*
G02X1136243Y1395440I2J3503D01*
G03X1136107I-68J-188D01*
G02X1134925Y1395234I-1184J3297D01*
G02X1133743Y1395440I2J3503D01*
G03X1133607I-68J-188D01*
G02X1132425Y1395234I-1184J3297D01*
G02X1131243Y1395440I2J3503D01*
G03X1131107I-68J-188D01*
G02X1129925Y1395234I-1184J3297D01*
G02X1128743Y1395440I2J3503D01*
G03X1128607I-68J-188D01*
G02X1127425Y1395234I-1184J3297D01*
G02X1123922Y1398737I0J3503D01*
G02X1124172Y1400035I3503J-2D01*
G03X1124174Y1400178I-186J74D01*
G02X1123962Y1401377I3291J1200D01*
G02X1124168Y1402559I3503J-2D01*
G03Y1402695I-188J68D01*
G02X1123962Y1403877I3297J1184D01*
G02X1127465Y1407380I3503J0D01*
G02X1128647Y1407174I-2J-3503D01*
G03X1128783I68J188D01*
G02X1129965Y1407380I1184J-3297D01*
G02X1131147Y1407174I-2J-3503D01*
G03X1131283I68J188D01*
G02X1132465Y1407380I1184J-3297D01*
G37*
G36*
G01X758089Y1394448D02*
G02X759238Y1394253I3J-3467D01*
G03X759370I66J189D01*
G02X759781Y1394369I1146J-3273D01*
G02X759780Y1394414I3501J100D01*
G01Y1394418D01*
G02X760060Y1395788I3503J-2D01*
G03Y1395944I-184J78D01*
G02X759780Y1397316I3223J1372D01*
G02X763283Y1400818I3503J-1D01*
G01X763284D01*
G02X765454Y1400064I-1J-3502D01*
G03X765685Y1400052I124J157D01*
G02X767549Y1400588I1862J-2967D01*
G02X771052Y1397086I1J-3502D01*
G02X770772Y1395714I-3503J0D01*
G03Y1395558I184J-78D01*
G02X771052Y1394186I-3223J-1372D01*
G02X770772Y1392814I-3503J0D01*
G03Y1392658I184J-78D01*
G02X771052Y1391286I-3223J-1372D01*
G02X767549Y1387784I-3503J1D01*
G02X764748Y1389183I0J3504D01*
G03X764631Y1389258I-160J-120D01*
G02X764581Y1389269I728J3426D01*
G01X764422Y1389099D01*
G03X764373Y1388913I145J-138D01*
G02X764482Y1388046I-3393J-867D01*
G02X764202Y1386674I-3502J0D01*
G03Y1386518I184J-78D01*
G02X764482Y1385147I-3222J-1372D01*
G01Y1385146D01*
G02X757478I-3502J0D01*
G01Y1385147D01*
G02X757758Y1386518I3502J-1D01*
G03X757757Y1386674I-185J77D01*
G02X757533Y1387427I3224J1369D01*
G03X757377Y1387587I-197J-36D01*
G02X756940Y1387709I712J3394D01*
G03X756808I-66J-189D01*
G02X755663Y1387514I-1146J3272D01*
G01X755659D01*
G02Y1394448I0J3467D01*
G01X755663D01*
G02X756808Y1394253I-1J-3467D01*
G03X756940I66J189D01*
G02X758089Y1394448I1146J-3272D01*
G37*
G36*
G01X725307Y1394348D02*
G02X726456Y1394153I3J-3467D01*
G03X726588I66J189D01*
G02X726999Y1394269I1146J-3273D01*
G02X726998Y1394314I3501J100D01*
G01Y1394318D01*
G02X727278Y1395688I3503J-2D01*
G03Y1395844I-184J78D01*
G02X726998Y1397216I3223J1372D01*
G02X730501Y1400718I3503J-1D01*
G01X730502D01*
G02X732672Y1399964I-1J-3502D01*
G03X732903Y1399952I124J157D01*
G02X734767Y1400488I1862J-2967D01*
G02X738270Y1396986I1J-3502D01*
G02X737990Y1395614I-3503J0D01*
G03Y1395458I184J-78D01*
G02X738270Y1394086I-3223J-1372D01*
G02X737990Y1392714I-3503J0D01*
G03Y1392558I184J-78D01*
G02X738270Y1391186I-3223J-1372D01*
G02X734767Y1387684I-3503J1D01*
G02X731966Y1389083I0J3504D01*
G03X731849Y1389158I-160J-120D01*
G02X731821Y1389164I720J3428D01*
G01X731661Y1388997D01*
G03X731611Y1388814I145J-138D01*
G02X731700Y1388026I-3413J-785D01*
G02X731420Y1386654I-3502J0D01*
G03Y1386498I184J-78D01*
G02X731700Y1385127I-3222J-1372D01*
G01Y1385126D01*
G02X724696I-3502J0D01*
G01Y1385127D01*
G02X724976Y1386498I3502J-1D01*
G03Y1386654I-184J78D01*
G02X724766Y1387328I3222J1373D01*
G03X724610Y1387484I-196J-40D01*
G02X724158Y1387609I696J3397D01*
G03X724026I-66J-189D01*
G02X722881Y1387414I-1146J3272D01*
G01X722877D01*
G02Y1394348I0J3467D01*
G01X722881D01*
G02X724026Y1394153I-1J-3467D01*
G03X724158I66J189D01*
G02X725307Y1394348I1146J-3272D01*
G37*
G36*
G01X1707794Y1395233D02*
G02X1707514Y1396605I3222J1372D01*
G02X1711016Y1400108I3502J1D01*
G02X1713187Y1399353I-1J-3503D01*
G03X1713418Y1399341I124J157D01*
G02X1715282Y1399878I1864J-2967D01*
G02X1718784Y1396375I-1J-3503D01*
G01Y1396374D01*
G02X1718504Y1395003I-3502J1D01*
G03Y1394847I184J-78D01*
G02X1718784Y1393475I-3222J-1372D01*
G02X1718504Y1392103I-3502J0D01*
G03Y1391947I184J-78D01*
G02X1718784Y1390575I-3222J-1372D01*
G02X1715282Y1387072I-3502J-1D01*
G02X1712481Y1388472I0J3502D01*
G03X1712363Y1388547I-159J-121D01*
G02X1712314Y1388558I743J3423D01*
G01X1712155Y1388389D01*
G03X1712107Y1388202I146J-137D01*
G02X1712216Y1387335I-3394J-867D01*
G02X1711936Y1385963I-3503J0D01*
G03Y1385807I184J-78D01*
G02X1712216Y1384435I-3223J-1372D01*
G02X1705210I-3503J0D01*
G02X1705490Y1385807I3503J0D01*
G03Y1385963I-184J78D01*
G02X1705266Y1386716I3224J1369D01*
G03X1705110Y1386876I-197J-36D01*
G02X1704673Y1386998I712J3394D01*
G03X1704541I-66J-189D01*
G02X1703392Y1386802I-1149J3272D01*
G02Y1393738I0J3468D01*
G02X1704541Y1393542I0J-3468D01*
G03X1704673I66J189D01*
G02X1705822Y1393738I1149J-3272D01*
G02X1706971Y1393542I0J-3468D01*
G03X1707103I66J189D01*
G02X1707514Y1393658I1146J-3273D01*
G01Y1393705D01*
G02X1707794Y1395077I3502J0D01*
G03Y1395233I-184J78D01*
G37*
G36*
G01X1675012Y1395133D02*
G02X1674732Y1396505I3222J1372D01*
G02X1678234Y1400008I3502J1D01*
G02X1680405Y1399253I-1J-3503D01*
G03X1680636Y1399241I124J157D01*
G02X1682500Y1399778I1864J-2967D01*
G02X1686002Y1396275I-1J-3503D01*
G01Y1396274D01*
G02X1685722Y1394903I-3502J1D01*
G03Y1394747I184J-78D01*
G02X1686002Y1393375I-3222J-1372D01*
G02X1685722Y1392003I-3502J0D01*
G03Y1391847I184J-78D01*
G02X1686002Y1390475I-3222J-1372D01*
G02X1682500Y1386972I-3502J-1D01*
G02X1679699Y1388372I0J3502D01*
G03X1679581Y1388447I-159J-121D01*
G02X1679532Y1388458I743J3423D01*
G01X1679373Y1388289D01*
G03X1679325Y1388102I146J-137D01*
G02X1679434Y1387235I-3394J-867D01*
G02X1679154Y1385863I-3503J0D01*
G03Y1385707I184J-78D01*
G02X1679434Y1384335I-3223J-1372D01*
G02X1672428I-3503J0D01*
G02X1672708Y1385707I3503J0D01*
G03Y1385863I-184J78D01*
G02X1672484Y1386616I3224J1369D01*
G03X1672328Y1386776I-197J-36D01*
G02X1671891Y1386898I712J3394D01*
G03X1671759I-66J-189D01*
G02X1670610Y1386702I-1149J3272D01*
G02Y1393638I0J3468D01*
G02X1671759Y1393442I0J-3468D01*
G03X1671891I66J189D01*
G02X1673040Y1393638I1149J-3272D01*
G02X1674189Y1393442I0J-3468D01*
G03X1674321I66J189D01*
G02X1674732Y1393558I1146J-3273D01*
G01Y1393605D01*
G02X1675012Y1394977I3502J0D01*
G03Y1395133I-184J78D01*
G37*
G36*
G01X291182Y1387040D02*
G02X291534Y1388572I3502J2D01*
G03Y1388747I-180J88D01*
G02X291180Y1390281I3149J1535D01*
G02X298186I3503J0D01*
G02X297833Y1388748I-3504J0D01*
G03Y1388574I180J-87D01*
G02X298186Y1387040I-3149J-1532D01*
G02X297879Y1385605I-3502J-1D01*
G03X297871Y1385462I183J-82D01*
G02X298036Y1384401I-3338J-1062D01*
G02X297860Y1383305I-3503J0D01*
G03X297870Y1383154I190J-63D01*
G02X298228Y1381612I-3145J-1543D01*
G02X291222I-3503J0D01*
G02X291398Y1382708I3503J0D01*
G03X291388Y1382859I-190J63D01*
G02X291030Y1384401I3145J1543D01*
G02X291338Y1385836I3503J-1D01*
G03X291346Y1385979I-183J82D01*
G02X291182Y1387040I3338J1059D01*
G37*
G36*
G01X1343712Y1393306D02*
G02X1344895Y1393101I2J-3502D01*
G03X1345029I67J188D01*
G02X1346212Y1393306I1181J-3297D01*
G02X1347395Y1393101I2J-3502D01*
G03X1347529I67J188D01*
G02X1348712Y1393306I1181J-3297D01*
G02X1350387Y1392879I-1J-3502D01*
G03X1350577I95J176D01*
G02X1352225Y1393290I1646J-3091D01*
G02X1355728Y1389788I1J-3502D01*
G02X1355431Y1388378I-3503J2D01*
G03Y1388216I183J-81D01*
G02X1355728Y1386804I-3205J-1411D01*
G02X1355428Y1385385I-3502J-1D01*
G03Y1385223I183J-81D01*
G02X1355728Y1383806I-3202J-1418D01*
G01Y1383804D01*
G02X1352226Y1380302I-3502J0D01*
G02X1351121Y1380480I-3J3502D01*
G03X1350977Y1380473I-63J-190D01*
G02X1349556Y1380172I-1420J3201D01*
G02X1348137Y1380472I-1J3502D01*
G03X1347975I-81J-183D01*
G02X1346556Y1380172I-1418J3202D01*
G02X1345137Y1380472I-1J3502D01*
G03X1344975I-81J-183D01*
G02X1343556Y1380172I-1418J3202D01*
G02X1342137Y1380472I-1J3502D01*
G03X1341975I-81J-183D01*
G02X1340556Y1380172I-1418J3202D01*
G02X1339137Y1380472I-1J3502D01*
G03X1338975I-81J-183D01*
G02X1337558Y1380172I-1418J3202D01*
G01X1337556D01*
G02X1334054Y1383674I0J3502D01*
G01Y1383676D01*
G02X1334354Y1385093I3502J-1D01*
G03Y1385255I-183J81D01*
G02X1334054Y1386674I3202J1418D01*
G02X1334350Y1388084I3502J1D01*
G03Y1388246I-183J81D01*
G02X1334052Y1389658I3205J1414D01*
G02X1337555Y1393160I3503J-1D01*
G01X1337556D01*
G02X1339163Y1392769I-1J-3502D01*
G03X1339360Y1392777I91J178D01*
G02X1341212Y1393306I1851J-2973D01*
G02X1342395Y1393101I2J-3502D01*
G03X1342529I67J188D01*
G02X1343712Y1393306I1181J-3297D01*
G37*
G36*
G01X301660Y1386889D02*
G02X301918Y1388209I3503J1D01*
G03Y1388359I-185J75D01*
G02X301660Y1389678I3245J1319D01*
G02X308666I3503J0D01*
G02X308408Y1388359I-3503J0D01*
G03Y1388209I185J-75D01*
G02X308666Y1386889I-3245J-1319D01*
G02X308358Y1385454I-3503J1D01*
G03X308350Y1385311I183J-82D01*
G02X308514Y1384250I-3338J-1059D01*
G02X308338Y1383153I-3502J-1D01*
G03X308349Y1383003I190J-61D01*
G02X308706Y1381463I-3145J-1541D01*
G01Y1381461D01*
G02X301702I-3502J0D01*
G01Y1381465D01*
G02X301878Y1382558I3502J-3D01*
G03X301867Y1382708I-190J61D01*
G02X301510Y1384250I3145J1541D01*
G02X301817Y1385685I3502J1D01*
G03X301825Y1385828I-183J82D01*
G02X301660Y1386889I3338J1062D01*
G37*
G36*
G01X320208Y1376259D02*
G02X320560Y1377791I3502J2D01*
G03Y1377966I-180J88D01*
G02X320206Y1379500I3149J1535D01*
G02X327212I3503J0D01*
G02X326859Y1377967I-3504J0D01*
G03Y1377793I180J-87D01*
G02X327212Y1376259I-3149J-1532D01*
G02X326905Y1374824I-3502J-1D01*
G03X326897Y1374681I183J-82D01*
G02X327062Y1373620I-3338J-1062D01*
G02X326886Y1372524I-3503J0D01*
G03X326896Y1372373I190J-63D01*
G02X327254Y1370831I-3145J-1543D01*
G02X320248I-3503J0D01*
G02X320424Y1371927I3503J0D01*
G03X320414Y1372078I-190J63D01*
G02X320056Y1373620I3145J1543D01*
G02X320364Y1375055I3503J-1D01*
G03X320372Y1375198I-183J82D01*
G02X320208Y1376259I3338J1059D01*
G37*
G36*
G01X250442Y1376309D02*
G02X250722Y1377679I3503J-2D01*
G03Y1377835I-184J78D01*
G02X250442Y1379207I3223J1372D01*
G02X253945Y1382710I3503J0D01*
G02X256116Y1381955I-1J-3503D01*
G03X256347Y1381943I124J157D01*
G02X258211Y1382480I1864J-2967D01*
G02X261714Y1378977I0J-3503D01*
G02X261434Y1377605I-3503J0D01*
G03Y1377449I184J-78D01*
G02X261714Y1376077I-3223J-1372D01*
G02X261434Y1374705I-3503J0D01*
G03Y1374549I184J-78D01*
G02X261714Y1373177I-3223J-1372D01*
G02X258211Y1369674I-3503J0D01*
G02X256286Y1370251I1J3503D01*
G01X256285Y1370252D01*
G03X256088Y1370264I-109J-168D01*
G01X255731Y1370090D01*
X255671Y1370002D01*
X255667Y1369950D01*
G02X255396Y1368861I-3456J282D01*
G03Y1368703I184J-79D01*
G02X255678Y1367335I-3185J-1370D01*
G01Y1367332D01*
G02X248744I-3467J0D01*
G01Y1367335D01*
G02X249026Y1368703I3467J-2D01*
G03Y1368861I-184J79D01*
G02X248843Y1369406I3184J1372D01*
G02X248752Y1369404I-122J3465D01*
G01X248750D01*
G02X247602Y1369600I1J3468D01*
G03X247470I-66J-189D01*
G02X246321Y1369404I-1149J3272D01*
G02Y1376340I0J3468D01*
G02X247470Y1376144I0J-3468D01*
G03X247602I66J189D01*
G02X248751Y1376340I1149J-3272D01*
G02X249900Y1376144I0J-3468D01*
G03X250032I66J189D01*
G02X250443Y1376260I1146J-3273D01*
G02X250442Y1376305I3501J100D01*
G01Y1376309D01*
G37*
G36*
G01X217642D02*
G02X217922Y1377679I3503J-2D01*
G03Y1377835I-184J78D01*
G02X217642Y1379207I3223J1372D01*
G02X221145Y1382710I3503J0D01*
G02X223316Y1381955I-1J-3503D01*
G03X223547Y1381943I124J157D01*
G02X225411Y1382480I1864J-2967D01*
G02X228914Y1378977I0J-3503D01*
G02X228634Y1377605I-3503J0D01*
G03Y1377449I184J-78D01*
G02X228914Y1376077I-3223J-1372D01*
G02X228634Y1374705I-3503J0D01*
G03Y1374549I184J-78D01*
G02X228914Y1373177I-3223J-1372D01*
G02X225411Y1369674I-3503J0D01*
G02X223516Y1370231I0J3502D01*
G01X223471Y1370260D01*
X223364Y1370266D01*
X222960Y1370056D01*
X222902Y1369966D01*
X222900Y1369913D01*
G02X222624Y1368695I-3499J153D01*
G03Y1368539I184J-78D01*
G02X222904Y1367167I-3223J-1372D01*
G02X215898I-3503J0D01*
G02X216178Y1368539I3503J0D01*
G03X216179Y1368695I-184J79D01*
G02X215962Y1369405I3222J1373D01*
G01X215960D01*
G02X215942Y1369404I-20J199D01*
G02X214802Y1369600I9J3468D01*
G03X214670I-66J-189D01*
G02X213521Y1369404I-1149J3272D01*
G02Y1376340I0J3468D01*
G02X214670Y1376144I0J-3468D01*
G03X214802I66J189D01*
G02X215951Y1376340I1149J-3272D01*
G02X217100Y1376144I0J-3468D01*
G03X217232I66J189D01*
G02X217643Y1376260I1146J-3273D01*
G02X217642Y1376305I3501J100D01*
G01Y1376309D01*
G37*
G36*
G01X184742D02*
G02X185022Y1377679I3503J-2D01*
G03Y1377835I-184J78D01*
G02X184742Y1379207I3223J1372D01*
G02X188245Y1382710I3503J0D01*
G02X190416Y1381955I-1J-3503D01*
G03X190647Y1381943I124J157D01*
G02X192511Y1382480I1864J-2967D01*
G02X196014Y1378977I0J-3503D01*
G02X195734Y1377605I-3503J0D01*
G03Y1377449I184J-78D01*
G02X196014Y1376077I-3223J-1372D01*
G02X195734Y1374705I-3503J0D01*
G03Y1374549I184J-78D01*
G02X196014Y1373177I-3223J-1372D01*
G02X192511Y1369674I-3503J0D01*
G02X190595Y1370245I1J3503D01*
G01X190550Y1370275D01*
X190445Y1370281D01*
X190087Y1370101D01*
G03X189977Y1369934I90J-179D01*
G02X189704Y1368775I-3496J212D01*
G03Y1368619I184J-78D01*
G02X189984Y1367247I-3223J-1372D01*
G02X182978I-3503J0D01*
G02X183258Y1368619I3503J0D01*
G03Y1368775I-184J78D01*
G02X183058Y1369405I3224J1370D01*
G02X183051Y1369404I-489J3398D01*
G02X181902Y1369600I0J3468D01*
G03X181770I-66J-189D01*
G02X180621Y1369404I-1149J3272D01*
G02Y1376340I0J3468D01*
G02X181770Y1376144I0J-3468D01*
G03X181902I66J189D01*
G02X183051Y1376340I1149J-3272D01*
G02X184200Y1376144I0J-3468D01*
G03X184332I66J189D01*
G02X184743Y1376260I1146J-3273D01*
G02X184742Y1376305I3501J100D01*
G01Y1376309D01*
G37*
G36*
G01X152042D02*
G02X152322Y1377679I3503J-2D01*
G03Y1377835I-184J78D01*
G02X152042Y1379207I3223J1372D01*
G02X155545Y1382710I3503J0D01*
G02X157716Y1381955I-1J-3503D01*
G03X157947Y1381943I124J157D01*
G02X159811Y1382480I1864J-2967D01*
G02X163314Y1378977I0J-3503D01*
G02X163034Y1377605I-3503J0D01*
G03Y1377449I184J-78D01*
G02X163314Y1376077I-3223J-1372D01*
G02X163034Y1374705I-3503J0D01*
G03Y1374549I184J-78D01*
G02X163314Y1373177I-3223J-1372D01*
G02X159811Y1369674I-3503J0D01*
G02X157865Y1370265I1J3503D01*
G01X157819Y1370295D01*
X157709Y1370301D01*
X157350Y1370111D01*
G03X157243Y1369938I93J-177D01*
G01Y1369937D01*
G02X156963Y1368605I-3502J41D01*
G03X156964Y1368449I185J-77D01*
G02X157244Y1367077I-3223J-1372D01*
G02X150238I-3503J0D01*
G02X150518Y1368449I3503J0D01*
G03X150519Y1368605I-184J79D01*
G02X150315Y1369253I3223J1371D01*
G03X150132Y1369411I-196J-42D01*
G02X149202Y1369600I219J3461D01*
G03X149070I-66J-189D01*
G02X147921Y1369404I-1149J3272D01*
G02Y1376340I0J3468D01*
G02X149070Y1376144I0J-3468D01*
G03X149202I66J189D01*
G02X150351Y1376340I1149J-3272D01*
G02X151500Y1376144I0J-3468D01*
G03X151632I66J189D01*
G02X152043Y1376260I1146J-3273D01*
G02X152042Y1376305I3501J100D01*
G01Y1376309D01*
G37*
G36*
G01X119442D02*
G02X119722Y1377679I3503J-2D01*
G03Y1377835I-184J78D01*
G02X119442Y1379207I3223J1372D01*
G02X122945Y1382710I3503J0D01*
G02X125116Y1381955I-1J-3503D01*
G03X125347Y1381943I124J157D01*
G02X127211Y1382480I1864J-2967D01*
G02X130714Y1378977I0J-3503D01*
G02X130434Y1377605I-3503J0D01*
G03Y1377449I184J-78D01*
G02X130714Y1376077I-3223J-1372D01*
G02X130434Y1374705I-3503J0D01*
G03Y1374549I184J-78D01*
G02X130714Y1373177I-3223J-1372D01*
G02X127211Y1369674I-3503J0D01*
G02X125355Y1370207I1J3503D01*
G03X125153Y1370213I-106J-169D01*
G01X124800Y1370022D01*
X124744Y1369930D01*
X124743Y1369876D01*
G02X124464Y1368575I-3502J71D01*
G03Y1368419I184J-78D01*
G02X124744Y1367047I-3223J-1372D01*
G02X122784Y1363903I-3502J0D01*
G03X122672Y1363714I88J-180D01*
G02X122674Y1363643I-1465J-77D01*
G02X119740I-1467J0D01*
G02X119743Y1363743I1467J6D01*
G03X119635Y1363934I-199J13D01*
G02X117738Y1367047I1606J3113D01*
G02X118018Y1368419I3503J0D01*
G03X118019Y1368575I-184J79D01*
G02X117781Y1369405I3222J1373D01*
G02X117754Y1369404I-142J3463D01*
G01X117748D01*
G02X116602Y1369600I3J3468D01*
G03X116470I-66J-189D01*
G02X115321Y1369404I-1149J3272D01*
G02Y1376340I0J3468D01*
G02X116470Y1376144I0J-3468D01*
G03X116602I66J189D01*
G02X117751Y1376340I1149J-3272D01*
G02X118900Y1376144I0J-3468D01*
G03X119032I66J189D01*
G02X119443Y1376260I1146J-3273D01*
G02X119442Y1376305I3501J100D01*
G01Y1376309D01*
G37*
G36*
G01X1220489Y1376320D02*
G02X1221638Y1376125I3J-3467D01*
G03X1221770I66J189D01*
G02X1222181Y1376241I1146J-3273D01*
G02X1222180Y1376286I3501J100D01*
G01Y1376290D01*
G02X1222460Y1377660I3503J-2D01*
G03Y1377816I-184J78D01*
G02X1222180Y1379188I3223J1372D01*
G02X1225683Y1382690I3503J-1D01*
G01X1225684D01*
G02X1227854Y1381936I-1J-3502D01*
G03X1228085Y1381924I124J157D01*
G02X1229949Y1382460I1862J-2967D01*
G02X1233452Y1378958I1J-3502D01*
G02X1233172Y1377586I-3503J0D01*
G03Y1377430I184J-78D01*
G02X1233452Y1376058I-3223J-1372D01*
G02X1233172Y1374686I-3503J0D01*
G03Y1374530I184J-78D01*
G02X1233452Y1373158I-3223J-1372D01*
G02X1229949Y1369656I-3503J1D01*
G01X1229948D01*
G02X1228009Y1370242I0J3502D01*
G01X1227964Y1370272D01*
X1227857Y1370279D01*
X1227497Y1370097D01*
G03X1227388Y1369927I91J-178D01*
G02X1227112Y1368716I-3499J161D01*
G03Y1368560I184J-78D01*
G02X1227392Y1367188I-3223J-1372D01*
G02X1220386I-3503J0D01*
G02X1220666Y1368560I3503J0D01*
G03X1220667Y1368716I-184J79D01*
G02X1220491Y1369239I3221J1375D01*
G03X1220308Y1369391I-194J-48D01*
G02X1219340Y1369581I177J3463D01*
G03X1219208I-66J-189D01*
G02X1218063Y1369386I-1146J3272D01*
G01X1218059D01*
G02Y1376320I0J3467D01*
G01X1218063D01*
G02X1219208Y1376125I-1J-3467D01*
G03X1219340I66J189D01*
G02X1220489Y1376320I1146J-3272D01*
G37*
G36*
G01X1187689D02*
G02X1188838Y1376125I3J-3467D01*
G03X1188970I66J189D01*
G02X1189381Y1376241I1146J-3273D01*
G02X1189380Y1376286I3501J100D01*
G01Y1376290D01*
G02X1189660Y1377660I3503J-2D01*
G03Y1377816I-184J78D01*
G02X1189380Y1379188I3223J1372D01*
G02X1192883Y1382690I3503J-1D01*
G01X1192884D01*
G02X1195054Y1381936I-1J-3502D01*
G03X1195285Y1381924I124J157D01*
G02X1197149Y1382460I1862J-2967D01*
G02X1200652Y1378958I1J-3502D01*
G02X1200372Y1377586I-3503J0D01*
G03Y1377430I184J-78D01*
G02X1200652Y1376058I-3223J-1372D01*
G02X1200372Y1374686I-3503J0D01*
G03Y1374530I184J-78D01*
G02X1200652Y1373158I-3223J-1372D01*
G02X1197149Y1369656I-3503J1D01*
G01X1197146D01*
G02X1195174Y1370265I2J3502D01*
G01X1195129Y1370296D01*
X1195021Y1370304D01*
X1194609Y1370097D01*
X1194551Y1370006D01*
X1194549Y1369951D01*
G02X1194272Y1368716I-3500J136D01*
G03Y1368560I184J-78D01*
G02X1194552Y1367188I-3223J-1372D01*
G02X1187546I-3503J0D01*
G02X1187826Y1368560I3503J0D01*
G03X1187827Y1368716I-184J79D01*
G02X1187651Y1369241I3222J1372D01*
G03X1187469Y1369392I-194J-49D01*
G02X1186540Y1369581I220J3461D01*
G03X1186408I-66J-189D01*
G02X1185263Y1369386I-1146J3272D01*
G01X1185259D01*
G02Y1376320I0J3467D01*
G01X1185263D01*
G02X1186408Y1376125I-1J-3467D01*
G03X1186540I66J189D01*
G02X1187689Y1376320I1146J-3272D01*
G37*
G36*
G01X1154789D02*
G02X1155938Y1376125I3J-3467D01*
G03X1156070I66J189D01*
G02X1156481Y1376241I1146J-3273D01*
G02X1156480Y1376286I3501J100D01*
G01Y1376290D01*
G02X1156760Y1377660I3503J-2D01*
G03Y1377816I-184J78D01*
G02X1156480Y1379188I3223J1372D01*
G02X1159983Y1382690I3503J-1D01*
G01X1159984D01*
G02X1162154Y1381936I-1J-3502D01*
G03X1162385Y1381924I124J157D01*
G02X1164249Y1382460I1862J-2967D01*
G02X1167752Y1378958I1J-3502D01*
G02X1167472Y1377586I-3503J0D01*
G03Y1377430I184J-78D01*
G02X1167752Y1376058I-3223J-1372D01*
G02X1167472Y1374686I-3503J0D01*
G03Y1374530I184J-78D01*
G02X1167752Y1373158I-3223J-1372D01*
G02X1164249Y1369656I-3503J1D01*
G01X1164247D01*
G02X1162195Y1370321I1J3502D01*
G01X1162149Y1370354D01*
X1162036Y1370362D01*
X1161617Y1370144D01*
X1161560Y1370046D01*
X1161561Y1369989D01*
G02X1161562Y1369918I-3502J-85D01*
G02X1161282Y1368546I-3503J0D01*
G03Y1368390I184J-78D01*
G02X1161562Y1367018I-3223J-1372D01*
G02X1154556I-3503J0D01*
G02X1154836Y1368390I3503J0D01*
G03Y1368546I-184J78D01*
G02X1154622Y1369242I3223J1372D01*
G03X1154446Y1369403I-196J-38D01*
G02X1153640Y1369581I339J3451D01*
G03X1153508I-66J-189D01*
G02X1152363Y1369386I-1146J3272D01*
G01X1152359D01*
G02Y1376320I0J3467D01*
G01X1152363D01*
G02X1153508Y1376125I-1J-3467D01*
G03X1153640I66J189D01*
G02X1154789Y1376320I1146J-3272D01*
G37*
G36*
G01X1122089D02*
G02X1123238Y1376125I3J-3467D01*
G03X1123370I66J189D01*
G02X1123781Y1376241I1146J-3273D01*
G02X1123780Y1376286I3501J100D01*
G01Y1376290D01*
G02X1124060Y1377660I3503J-2D01*
G03Y1377816I-184J78D01*
G02X1123780Y1379188I3223J1372D01*
G02X1127283Y1382690I3503J-1D01*
G01X1127284D01*
G02X1129454Y1381936I-1J-3502D01*
G03X1129685Y1381924I124J157D01*
G02X1131549Y1382460I1862J-2967D01*
G02X1135052Y1378958I1J-3502D01*
G02X1134772Y1377586I-3503J0D01*
G03Y1377430I184J-78D01*
G02X1135052Y1376058I-3223J-1372D01*
G02X1134772Y1374686I-3503J0D01*
G03Y1374530I184J-78D01*
G02X1135052Y1373158I-3223J-1372D01*
G02X1131549Y1369656I-3503J1D01*
G01X1131548D01*
G02X1129594Y1370252I0J3502D01*
G01X1129593Y1370253D01*
G03X1129390Y1370264I-111J-167D01*
G01X1129030Y1370077D01*
X1128972Y1369984D01*
X1128971Y1369929D01*
G02X1128692Y1368636I-3502J79D01*
G03Y1368480I184J-78D01*
G02X1128972Y1367108I-3223J-1372D01*
G02X1121966I-3503J0D01*
G02X1122246Y1368480I3503J0D01*
G03Y1368636I-184J78D01*
G02X1122052Y1369237I3223J1372D01*
G03X1121870Y1369392I-195J-44D01*
G02X1120940Y1369581I219J3461D01*
G03X1120808I-66J-189D01*
G02X1119663Y1369386I-1146J3272D01*
G01X1119659D01*
G02Y1376320I0J3467D01*
G01X1119663D01*
G02X1120808Y1376125I-1J-3467D01*
G03X1120940I66J189D01*
G02X1122089Y1376320I1146J-3272D01*
G37*
G36*
G01X1089489D02*
G02X1090638Y1376125I3J-3467D01*
G03X1090770I66J189D01*
G02X1091181Y1376241I1146J-3273D01*
G02X1091180Y1376286I3501J100D01*
G01Y1376290D01*
G02X1091460Y1377660I3503J-2D01*
G03Y1377816I-184J78D01*
G02X1091180Y1379188I3223J1372D01*
G02X1094683Y1382690I3503J-1D01*
G01X1094684D01*
G02X1096854Y1381936I-1J-3502D01*
G03X1097085Y1381924I124J157D01*
G02X1098949Y1382460I1862J-2967D01*
G02X1102452Y1378958I1J-3502D01*
G02X1102172Y1377586I-3503J0D01*
G03Y1377430I184J-78D01*
G02X1102452Y1376058I-3223J-1372D01*
G02X1102172Y1374686I-3503J0D01*
G03Y1374530I184J-78D01*
G02X1102452Y1373158I-3223J-1372D01*
G02X1098949Y1369656I-3503J1D01*
G01X1098947D01*
G02X1097004Y1370245I1J3502D01*
G01X1096960Y1370274D01*
X1096853Y1370282D01*
X1096494Y1370105D01*
G03X1096383Y1369939I89J-179D01*
G02X1096111Y1368806I-3494J240D01*
G03X1096112Y1368650I185J-77D01*
G02X1096392Y1367278I-3223J-1372D01*
G02X1089386I-3503J0D01*
G02X1089666Y1368650I3503J0D01*
G03Y1368806I-184J78D01*
G02X1089513Y1369243I3222J1373D01*
G03X1089330Y1369390I-193J-53D01*
G02X1088340Y1369581I155J3464D01*
G03X1088208I-66J-189D01*
G02X1087063Y1369386I-1146J3272D01*
G01X1087059D01*
G02Y1376320I0J3467D01*
G01X1087063D01*
G02X1088208Y1376125I-1J-3467D01*
G03X1088340I66J189D01*
G02X1089489Y1376320I1146J-3272D01*
G37*
G36*
G01X330686Y1376108D02*
G02X330944Y1377427I3503J0D01*
G03Y1377577I-185J75D01*
G02X330686Y1378897I3245J1319D01*
G02X337692I3503J0D01*
G02X337434Y1377577I-3503J-1D01*
G03Y1377427I185J-75D01*
G02X337692Y1376108I-3245J-1319D01*
G02X337384Y1374673I-3503J1D01*
G03X337376Y1374530I183J-82D01*
G02X337540Y1373469I-3338J-1059D01*
G02X337364Y1372372I-3502J-1D01*
G03X337375Y1372222I190J-61D01*
G02X337732Y1370682I-3145J-1541D01*
G01Y1370680D01*
G02X330728I-3502J0D01*
G01Y1370684D01*
G02X330904Y1371777I3502J-3D01*
G03X330893Y1371927I-190J61D01*
G02X330536Y1373469I3145J1541D01*
G02X330843Y1374904I3502J1D01*
G03X330851Y1375047I-183J82D01*
G02X330686Y1376108I3338J1062D01*
G37*
G36*
G01X362223Y1368226D02*
G02X363406Y1368021I2J-3502D01*
G03X363540I67J188D01*
G02X364723Y1368226I1181J-3297D01*
G02X368226Y1364724I1J-3502D01*
G02X367918Y1363289I-3503J1D01*
G03X367910Y1363146I183J-82D01*
G02X368074Y1362085I-3338J-1059D01*
G02X367898Y1360988I-3502J-1D01*
G03X367909Y1360838I190J-61D01*
G02X368266Y1359298I-3145J-1541D01*
G01Y1359296D01*
G02X364764Y1355794I-3502J0D01*
G01X364761D01*
G02X363581Y1355999I1J3502D01*
G03X363447I-67J-188D01*
G02X362264Y1355794I-1181J3297D01*
G02X361081Y1355999I-2J3502D01*
G03X360947I-67J-188D01*
G02X359764Y1355794I-1181J3297D01*
G02X358345Y1356094I-1J3502D01*
G03X358183I-81J-183D01*
G02X356764Y1355794I-1418J3202D01*
G02X355581Y1355999I-2J3502D01*
G03X355447I-67J-188D01*
G02X354264Y1355794I-1181J3297D01*
G02X353135Y1355981I0J3502D01*
G03X352993Y1355976I-64J-190D01*
G02X351632Y1355700I-1363J3227D01*
G02X348130Y1359203I1J3503D01*
G01Y1359206D01*
G02X348476Y1360723I3502J-1D01*
G03X348484Y1360878I-180J87D01*
G02X348270Y1362085I3288J1205D01*
G02X348577Y1363520I3502J1D01*
G03X348585Y1363663I-183J82D01*
G02X348420Y1364724I3338J1062D01*
G02X351923Y1368226I3503J-1D01*
G01X351926D01*
G02X353106Y1368021I-1J-3502D01*
G03X353240I67J188D01*
G02X354423Y1368226I1181J-3297D01*
G02X355606Y1368021I2J-3502D01*
G03X355740I67J188D01*
G02X356923Y1368226I1181J-3297D01*
G02X358106Y1368021I2J-3502D01*
G03X358240I67J188D01*
G02X359423Y1368226I1181J-3297D01*
G02X360747Y1367967I2J-3502D01*
G03X360899I76J185D01*
G02X362223Y1368226I1322J-3243D01*
G37*
G36*
G01X415198Y1349687D02*
G02X415452Y1350638I3477J-419D01*
G03Y1350794I-184J78D01*
G02X415172Y1352166I3223J1372D01*
G02X417978Y1355599I3503J0D01*
G03X418121Y1355713I-39J196D01*
G02X421315Y1357778I3194J-1438D01*
G01X421317D01*
G02X424818Y1354276I-1J-3502D01*
G02X424538Y1352904I-3503J0D01*
G03Y1352748I184J-78D01*
G02X424818Y1351376I-3223J-1372D01*
G02X424505Y1349928I-3502J-1D01*
G03X424499Y1349777I182J-83D01*
G02X424708Y1348586I-3294J-1192D01*
G02X424428Y1347214I-3503J0D01*
G03Y1347058I184J-78D01*
G02X424708Y1345686I-3223J-1372D01*
G02X421205Y1342184I-3503J1D01*
G01X421203D01*
G02X420507Y1342254I1J3502D01*
G03X420282Y1342132I-39J-196D01*
G02X420248Y1342052I-3208J1316D01*
G03Y1341894I184J-79D01*
G02X420530Y1340526I-3185J-1370D01*
G01Y1340523D01*
G02X413596I-3467J0D01*
G01Y1340526D01*
G02X413878Y1341894I3467J-2D01*
G03Y1342052I-184J79D01*
G02X413670Y1342707I3185J1372D01*
G02X413533Y1342704I-144J3465D01*
G02X412384Y1342900I0J3468D01*
G03X412252I-66J-189D01*
G02X411103Y1342704I-1149J3272D01*
G02Y1349640I0J3468D01*
G02X412252Y1349444I0J-3468D01*
G03X412384I66J189D01*
G02X413533Y1349640I1149J-3272D01*
G02X414682Y1349444I0J-3468D01*
G03X414814I66J189D01*
G02X415052Y1349518I1148J-3272D01*
G03X415198Y1349687I-53J193D01*
G37*
G36*
G01X1389662Y1349620D02*
G02X1390811Y1349425I3J-3467D01*
G03X1390943I66J189D01*
G02X1391354Y1349541I1146J-3273D01*
G01Y1349588D01*
G02X1391634Y1350960I3502J0D01*
G03Y1351116I-184J78D01*
G02X1391354Y1352487I3222J1372D01*
G01Y1352488D01*
G02X1394856Y1355990I3502J0D01*
G01X1394857D01*
G02X1397027Y1355236I-1J-3502D01*
G03X1397258Y1355224I124J157D01*
G02X1399119Y1355760I1862J-2967D01*
G01X1399122D01*
G02X1402624Y1352258I0J-3502D01*
G01Y1352257D01*
G02X1402344Y1350886I-3502J1D01*
G03Y1350730I184J-78D01*
G02X1402624Y1349358I-3222J-1372D01*
G02X1402344Y1347986I-3502J0D01*
G03Y1347830I184J-78D01*
G02X1402624Y1346459I-3222J-1372D01*
G01Y1346458D01*
G02X1399122Y1342956I-3502J0D01*
G01X1399120D01*
G02X1397123Y1343582I1J3502D01*
G01X1397122D01*
G03X1397009Y1343618I-114J-164D01*
G01X1397008D01*
G03X1396808Y1343418I0J-200D01*
G01Y1343414D01*
G02X1396528Y1342043I-3502J1D01*
G03Y1341887I184J-78D01*
G02X1396808Y1340516I-3222J-1372D01*
G01Y1340515D01*
G02X1389804I-3502J0D01*
G01Y1340516D01*
G02X1390084Y1341887I3502J-1D01*
G03Y1342043I-184J78D01*
G02X1389916Y1342536I3222J1373D01*
G03X1389719Y1342686I-194J-50D01*
G01X1389662D01*
G02X1388513Y1342881I-3J3467D01*
G03X1388381I-66J-189D01*
G02X1387236Y1342686I-1146J3272D01*
G01X1387232D01*
G02Y1349620I0J3467D01*
G01X1387236D01*
G02X1388381Y1349425I-1J-3467D01*
G03X1388513I66J189D01*
G02X1389662Y1349620I1146J-3272D01*
G37*
G36*
G01X380951Y1330308D02*
G02X382100Y1330113I3J-3467D01*
G03X382232I66J189D01*
G02X382643Y1330229I1146J-3273D01*
G02X382642Y1330274I3501J100D01*
G01Y1330278D01*
G02X382922Y1331648I3503J-2D01*
G03Y1331804I-184J78D01*
G02X382642Y1333176I3223J1372D01*
G02X383188Y1335053I3503J-1D01*
G03X383213Y1335208I-169J107D01*
G02X383108Y1336056I3398J851D01*
G02X385773Y1339457I3503J0D01*
G03X385890Y1339537I-47J194D01*
G02X388771Y1341048I2881J-1991D01*
G01X388773D01*
G02X392274Y1337546I-1J-3502D01*
G02X391973Y1336127I-3503J2D01*
G03Y1335965I183J-81D01*
G02X392274Y1334546I-3202J-1421D01*
G02X391711Y1332643I-3503J1D01*
G03X391686Y1332481I168J-109D01*
G02X391814Y1331546I-3375J-938D01*
G02X391464Y1330021I-3503J1D01*
G03X391459Y1329859I180J-87D01*
G02X391714Y1328546I-3248J-1312D01*
G02X388300Y1325045I-3502J0D01*
G01X388298D01*
G03X388152Y1324974I7J-200D01*
G01X387930Y1324713D01*
X387907Y1324630D01*
X387913Y1324588D01*
G02X387948Y1324092I-3432J-491D01*
G02X387666Y1322721I-3467J-1D01*
G03Y1322563I184J-79D01*
G02X387948Y1321195I-3185J-1370D01*
G01Y1321192D01*
G02X381014I-3467J0D01*
G01Y1321195D01*
G02X381296Y1322563I3467J-2D01*
G03Y1322721I-184J79D01*
G02X381088Y1323376I3185J1372D01*
G02X380952Y1323374I-119J3465D01*
G01X380950D01*
G02X379802Y1323569I-2J3467D01*
G03X379670I-66J-189D01*
G02X378525Y1323374I-1146J3272D01*
G01X378521D01*
G02Y1330308I0J3467D01*
G01X378525D01*
G02X379670Y1330113I-1J-3467D01*
G03X379802I66J189D01*
G02X380951Y1330308I1146J-3272D01*
G37*
G36*
G01X1357080Y1323354D02*
G02X1355931Y1323550I0J3468D01*
G03X1355799I-66J-189D01*
G02X1354650Y1323354I-1149J3272D01*
G02Y1330290I0J3468D01*
G02X1355799Y1330094I0J-3468D01*
G03X1355931I66J189D01*
G02X1357080Y1330290I1149J-3272D01*
G02X1358229Y1330094I0J-3468D01*
G03X1358361I66J189D01*
G02X1358772Y1330210I1146J-3273D01*
G01Y1330257D01*
G02X1359052Y1331629I3502J0D01*
G03Y1331785I-184J78D01*
G02X1358772Y1333157I3222J1372D01*
G02X1359052Y1334529I3502J0D01*
G03Y1334685I-184J78D01*
G02X1358772Y1336056I3222J1372D01*
G01Y1336057D01*
G02X1361459Y1339463I3502J0D01*
G03X1361576Y1339543I-47J194D01*
G02X1364440Y1341030I2865J-2016D01*
G02X1367942Y1337527I-1J-3503D01*
G01Y1337525D01*
G02X1367642Y1336108I-3502J1D01*
G03Y1335946I183J-81D01*
G02X1367942Y1334527I-3202J-1418D01*
G02X1367642Y1333108I-3502J-1D01*
G03Y1332946I183J-81D01*
G02X1367942Y1331527I-3202J-1418D01*
G02X1367593Y1330002I-3502J-1D01*
G03X1367587Y1329840I180J-88D01*
G02X1367842Y1328531I-3247J-1312D01*
G01Y1328527D01*
G02X1364563Y1325032I-3502J0D01*
G01X1364561D01*
G03X1364420Y1324959I14J-200D01*
G01X1364208Y1324699D01*
X1364186Y1324618D01*
X1364192Y1324576D01*
G02X1364226Y1324084I-3468J-487D01*
G02X1363946Y1322712I-3502J0D01*
G03Y1322556I184J-78D01*
G02X1364226Y1321185I-3222J-1372D01*
G01Y1321184D01*
G02X1357222I-3502J0D01*
G01Y1321185D01*
G02X1357502Y1322556I3502J-1D01*
G03Y1322712I-184J78D01*
G02X1357334Y1323205I3222J1373D01*
G03X1357137Y1323355I-194J-50D01*
G02X1357080Y1323354I-89J3466D01*
G37*
G36*
G01X284042Y1330163D02*
G02X284322Y1331533I3503J-2D01*
G03Y1331689I-184J78D01*
G02X284042Y1333061I3223J1372D01*
G02X287545Y1336564I3503J0D01*
G02X289716Y1335809I-1J-3503D01*
G03X289947Y1335797I124J157D01*
G02X291811Y1336334I1864J-2967D01*
G02X295314Y1332831I0J-3503D01*
G02X295034Y1331459I-3503J0D01*
G03Y1331303I184J-78D01*
G02X295314Y1329931I-3223J-1372D01*
G02X295034Y1328559I-3503J0D01*
G03Y1328403I184J-78D01*
G02X295314Y1327031I-3223J-1372D01*
G02X291811Y1323528I-3503J0D01*
G02X289967Y1324053I1J3503D01*
G01X289921Y1324082D01*
X289815Y1324085D01*
X289415Y1323871D01*
X289358Y1323780D01*
X289357Y1323727D01*
G02X289076Y1322471I-3466J116D01*
G03Y1322313I184J-79D01*
G02X289358Y1320945I-3185J-1370D01*
G01Y1320942D01*
G02X282424I-3467J0D01*
G01Y1320945D01*
G02X282706Y1322313I3467J-2D01*
G03Y1322471I-184J79D01*
G02X282473Y1323261I3186J1369D01*
G02X282352Y1323258I-146J3464D01*
G01X282350D01*
G02X281202Y1323454I1J3468D01*
G03X281070I-66J-189D01*
G02X279921Y1323258I-1149J3272D01*
G02Y1330194I0J3468D01*
G02X281070Y1329998I0J-3468D01*
G03X281202I66J189D01*
G02X282351Y1330194I1149J-3272D01*
G02X283500Y1329998I0J-3468D01*
G03X283632I66J189D01*
G02X284043Y1330114I1146J-3273D01*
G02X284042Y1330159I3501J100D01*
G01Y1330163D01*
G37*
G36*
G01X1258480Y1330174D02*
G02X1259629Y1329979I3J-3467D01*
G03X1259761I66J189D01*
G02X1260172Y1330095I1146J-3273D01*
G01Y1330142D01*
G02X1260452Y1331514I3502J0D01*
G03Y1331670I-184J78D01*
G02X1260172Y1333041I3222J1372D01*
G01Y1333042D01*
G02X1263674Y1336544I3502J0D01*
G01X1263675D01*
G02X1265845Y1335790I-1J-3502D01*
G03X1266076Y1335778I124J157D01*
G02X1267937Y1336314I1862J-2967D01*
G01X1267940D01*
G02X1271442Y1332812I0J-3502D01*
G01Y1332811D01*
G02X1271162Y1331440I-3502J1D01*
G03Y1331284I184J-78D01*
G02X1271442Y1329912I-3222J-1372D01*
G02X1271162Y1328540I-3502J0D01*
G03Y1328384I184J-78D01*
G02X1271442Y1327013I-3222J-1372D01*
G01Y1327012D01*
G02X1267940Y1323510I-3502J0D01*
G01X1267938D01*
G02X1266154Y1323999I1J3502D01*
G01X1266108Y1324026D01*
X1266003Y1324028D01*
X1265607Y1323810D01*
X1265552Y1323720D01*
X1265551Y1323667D01*
G02X1265273Y1322406I-3501J111D01*
G03X1265272Y1322250I184J-79D01*
G02X1265552Y1320879I-3222J-1372D01*
G01Y1320878D01*
G02X1258548I-3502J0D01*
G01Y1320879D01*
G02X1258828Y1322250I3502J-1D01*
G03Y1322406I-184J78D01*
G02X1258589Y1323241I3222J1374D01*
G02X1258481Y1323240I-86J3466D01*
G01X1258479D01*
G02X1257331Y1323435I-2J3467D01*
G03X1257199I-66J-189D01*
G02X1256054Y1323240I-1146J3272D01*
G01X1256050D01*
G02Y1330174I0J3467D01*
G01X1256054D01*
G02X1257199Y1329979I-1J-3467D01*
G03X1257331I66J189D01*
G02X1258480Y1330174I1146J-3272D01*
G37*
G36*
G01X316938Y1330135D02*
G02X317218Y1331505I3503J-2D01*
G03Y1331661I-184J78D01*
G02X316938Y1333033I3223J1372D01*
G02X320441Y1336536I3503J0D01*
G02X322612Y1335781I-1J-3503D01*
G03X322843Y1335769I124J157D01*
G02X324707Y1336306I1864J-2967D01*
G02X328210Y1332803I0J-3503D01*
G02X327930Y1331431I-3503J0D01*
G03Y1331275I184J-78D01*
G02X328210Y1329903I-3223J-1372D01*
G02X327930Y1328531I-3503J0D01*
G03Y1328375I184J-78D01*
G02X328210Y1327003I-3223J-1372D01*
G02X324707Y1323500I-3503J0D01*
G02X322884Y1324012I0J3503D01*
G01X322838Y1324040D01*
X322732Y1324043D01*
X322381Y1323853D01*
G03X322276Y1323684I95J-176D01*
G02X321996Y1322431I-3465J117D01*
G03Y1322273I184J-79D01*
G02X322278Y1320905I-3185J-1370D01*
G01Y1320902D01*
G02X315344I-3467J0D01*
G01Y1320905D01*
G02X315626Y1322273I3467J-2D01*
G03Y1322431I-184J79D01*
G02X315390Y1323233I3184J1373D01*
G02X315247Y1323230I-144J3465D01*
G02X314098Y1323426I0J3468D01*
G03X313966I-66J-189D01*
G02X312817Y1323230I-1149J3272D01*
G02Y1330166I0J3468D01*
G02X313966Y1329970I0J-3468D01*
G03X314098I66J189D01*
G02X315247Y1330166I1149J-3272D01*
G02X316396Y1329970I0J-3468D01*
G03X316528I66J189D01*
G02X316939Y1330086I1146J-3273D01*
G02X316938Y1330131I3501J100D01*
G01Y1330135D01*
G37*
G36*
G01X1291376Y1330146D02*
G02X1292525Y1329951I3J-3467D01*
G03X1292657I66J189D01*
G02X1293068Y1330067I1146J-3273D01*
G01Y1330114D01*
G02X1293348Y1331486I3502J0D01*
G03Y1331642I-184J78D01*
G02X1293068Y1333013I3222J1372D01*
G01Y1333014D01*
G02X1296570Y1336516I3502J0D01*
G01X1296571D01*
G02X1298741Y1335762I-1J-3502D01*
G03X1298972Y1335750I124J157D01*
G02X1300833Y1336286I1862J-2967D01*
G01X1300836D01*
G02X1304338Y1332784I0J-3502D01*
G01Y1332783D01*
G02X1304058Y1331412I-3502J1D01*
G03Y1331256I184J-78D01*
G02X1304338Y1329884I-3222J-1372D01*
G02X1304058Y1328512I-3502J0D01*
G03Y1328356I184J-78D01*
G02X1304338Y1326985I-3222J-1372D01*
G01Y1326984D01*
G02X1300836Y1323482I-3502J0D01*
G02X1299056Y1323968I0J3503D01*
G03X1298860Y1323972I-102J-172D01*
G01X1298512Y1323785D01*
X1298456Y1323697D01*
X1298453Y1323645D01*
G02X1298178Y1322462I-3497J189D01*
G03Y1322306I184J-78D01*
G02X1298458Y1320935I-3222J-1372D01*
G01Y1320934D01*
G02X1291454I-3502J0D01*
G01Y1320935D01*
G02X1291734Y1322306I3502J-1D01*
G03Y1322462I-184J78D01*
G02X1291509Y1323214I3222J1374D01*
G02X1291376Y1323212I-119J3465D01*
G02X1290227Y1323407I-3J3467D01*
G03X1290095I-66J-189D01*
G02X1288950Y1323212I-1146J3272D01*
G01X1288946D01*
G02Y1330146I0J3467D01*
G01X1288950D01*
G02X1290095Y1329951I-1J-3467D01*
G03X1290227I66J189D01*
G02X1291376Y1330146I1146J-3272D01*
G37*
G36*
G01X348151Y1330108D02*
G02X349300Y1329913I3J-3467D01*
G03X349432I66J189D01*
G02X349843Y1330029I1146J-3273D01*
G02X349842Y1330074I3501J100D01*
G01Y1330078D01*
G02X350122Y1331448I3503J-2D01*
G03Y1331604I-184J78D01*
G02X349842Y1332976I3223J1372D01*
G02X353345Y1336478I3503J-1D01*
G01X353346D01*
G02X355516Y1335724I-1J-3502D01*
G03X355747Y1335712I124J157D01*
G02X357611Y1336248I1862J-2967D01*
G02X361114Y1332746I1J-3502D01*
G02X360834Y1331374I-3503J0D01*
G03Y1331218I184J-78D01*
G02X361114Y1329846I-3223J-1372D01*
G02X360834Y1328474I-3503J0D01*
G03Y1328318I184J-78D01*
G02X361114Y1326946I-3223J-1372D01*
G02X357611Y1323444I-3503J1D01*
G01X357609D01*
G02X355729Y1323992I1J3502D01*
G01X355683Y1324021D01*
X355578Y1324026D01*
X355222Y1323842D01*
G03X355114Y1323675I92J-178D01*
G01Y1323674D01*
G02X354836Y1322471I-3463J167D01*
G03Y1322313I184J-79D01*
G02X355118Y1320945I-3185J-1370D01*
G01Y1320942D01*
G02X348184I-3467J0D01*
G01Y1320945D01*
G02X348466Y1322313I3467J-2D01*
G03Y1322471I-184J79D01*
G02X348248Y1323175I3185J1372D01*
G02X348151Y1323174I-84J3466D01*
G02X347002Y1323369I-3J3467D01*
G03X346870I-66J-189D01*
G02X345725Y1323174I-1146J3272D01*
G01X345721D01*
G02Y1330108I0J3467D01*
G01X345725D01*
G02X346870Y1329913I-1J-3467D01*
G03X347002I66J189D01*
G02X348151Y1330108I1146J-3272D01*
G37*
G36*
G01X1326252Y1331585D02*
G02X1325972Y1332957I3222J1372D01*
G02X1329474Y1336460I3502J1D01*
G02X1331645Y1335705I-1J-3503D01*
G03X1331876Y1335693I124J157D01*
G02X1333740Y1336230I1864J-2967D01*
G02X1337242Y1332727I-1J-3503D01*
G01Y1332726D01*
G02X1336962Y1331355I-3502J1D01*
G03Y1331199I184J-78D01*
G02X1337242Y1329827I-3222J-1372D01*
G02X1336962Y1328455I-3502J0D01*
G03Y1328299I184J-78D01*
G02X1337242Y1326927I-3222J-1372D01*
G02X1333740Y1323424I-3502J-1D01*
G02X1331971Y1323904I1J3503D01*
G01X1331926Y1323930D01*
X1331823Y1323932D01*
X1331476Y1323750D01*
G03X1331370Y1323587I94J-177D01*
G02X1331099Y1322462I-3494J247D01*
G03X1331098Y1322306I184J-79D01*
G02X1331378Y1320935I-3222J-1372D01*
G01Y1320934D01*
G02X1324374I-3502J0D01*
G01Y1320935D01*
G02X1324654Y1322306I3502J-1D01*
G03X1324653Y1322462I-185J77D01*
G02X1324439Y1323158I3223J1372D01*
G02X1324280Y1323154I-167J3464D01*
G02X1323131Y1323350I0J3468D01*
G03X1322999I-66J-189D01*
G02X1321850Y1323154I-1149J3272D01*
G02Y1330090I0J3468D01*
G02X1322999Y1329894I0J-3468D01*
G03X1323131I66J189D01*
G02X1324280Y1330090I1149J-3272D01*
G02X1325429Y1329894I0J-3468D01*
G03X1325561I66J189D01*
G02X1325972Y1330010I1146J-3273D01*
G01Y1330057D01*
G02X1326252Y1331429I3502J0D01*
G03Y1331585I-184J78D01*
G37*
G36*
G01X1521562Y714544D02*
G02X1521842Y715916I3502J0D01*
G03Y716072I-184J78D01*
G02X1521562Y717443I3222J1372D01*
G01Y717444D01*
G02X1528566I3502J0D01*
G01Y717443D01*
G02X1528286Y716072I-3502J1D01*
G03X1528287Y715916I185J-77D01*
G02X1528506Y715190I-3224J-1369D01*
G03X1528662Y715031I197J37D01*
G02X1529106Y714908I-702J-3396D01*
G03X1529238I66J189D01*
G02X1530387Y715104I1149J-3272D01*
G02Y708168I0J-3468D01*
G02X1529238Y708364I0J3468D01*
G03X1529106I-66J-189D01*
G02X1527957Y708168I-1149J3272D01*
G02X1526808Y708364I0J3468D01*
G03X1526676I-66J-189D01*
G02X1526265Y708248I-1146J3273D01*
G02X1526266Y708203I-3501J-100D01*
G01Y708199D01*
G02X1525986Y706829I-3503J2D01*
G03Y706673I184J-78D01*
G02X1526266Y705301I-3223J-1372D01*
G02X1522763Y701798I-3503J0D01*
G02X1520592Y702553I1J3503D01*
G03X1520361Y702565I-124J-157D01*
G02X1518497Y702028I-1864J2967D01*
G02X1514994Y705531I0J3503D01*
G02X1515274Y706903I3503J0D01*
G03Y707059I-184J78D01*
G02X1514994Y708431I3223J1372D01*
G02X1515274Y709803I3503J0D01*
G03Y709959I-184J78D01*
G02X1514994Y711331I3223J1372D01*
G02X1518497Y714834I3503J0D01*
G02X1521298Y713434I0J-3502D01*
G03X1521415Y713359I160J120D01*
G02X1521455Y713350I-749J-3421D01*
G01X1521615Y713519D01*
G03X1521664Y713704I-146J138D01*
G02X1521562Y714544I3400J839D01*
G37*
G36*
G01X1488762D02*
G02X1489042Y715916I3502J0D01*
G03Y716072I-184J78D01*
G02X1488762Y717443I3222J1372D01*
G01Y717444D01*
G02X1495766I3502J0D01*
G01Y717443D01*
G02X1495486Y716072I-3502J1D01*
G03X1495487Y715916I185J-77D01*
G02X1495706Y715190I-3224J-1369D01*
G03X1495862Y715031I197J37D01*
G02X1496306Y714908I-702J-3396D01*
G03X1496438I66J189D01*
G02X1497587Y715104I1149J-3272D01*
G02Y708168I0J-3468D01*
G02X1496438Y708364I0J3468D01*
G03X1496306I-66J-189D01*
G02X1495157Y708168I-1149J3272D01*
G02X1494008Y708364I0J3468D01*
G03X1493876I-66J-189D01*
G02X1493465Y708248I-1146J3273D01*
G02X1493466Y708203I-3501J-100D01*
G01Y708199D01*
G02X1493186Y706829I-3503J2D01*
G03Y706673I184J-78D01*
G02X1493466Y705301I-3223J-1372D01*
G02X1489963Y701798I-3503J0D01*
G02X1487792Y702553I1J3503D01*
G03X1487561Y702565I-124J-157D01*
G02X1485697Y702028I-1864J2967D01*
G02X1482194Y705531I0J3503D01*
G02X1482474Y706903I3503J0D01*
G03Y707059I-184J78D01*
G02X1482194Y708431I3223J1372D01*
G02X1482474Y709803I3503J0D01*
G03Y709959I-184J78D01*
G02X1482194Y711331I3223J1372D01*
G02X1485697Y714834I3503J0D01*
G02X1488498Y713434I0J-3502D01*
G03X1488615Y713359I160J120D01*
G02X1488655Y713350I-749J-3421D01*
G01X1488815Y713519D01*
G03X1488864Y713704I-146J138D01*
G02X1488762Y714544I3400J839D01*
G37*
G36*
G01X312410Y714500D02*
G02X312690Y715872I3502J0D01*
G03Y716028I-184J78D01*
G02X312410Y717399I3222J1372D01*
G01Y717400D01*
G02X319414I3502J0D01*
G01Y717399D01*
G02X319134Y716028I-3502J1D01*
G03X319135Y715872I185J-77D01*
G02X319346Y715189I-3224J-1370D01*
G03X319502Y715033I196J40D01*
G02X319954Y714908I-696J-3397D01*
G03X320086I66J189D01*
G02X321235Y715104I1149J-3272D01*
G02Y708168I0J-3468D01*
G02X320086Y708364I0J3468D01*
G03X319954I-66J-189D01*
G02X318805Y708168I-1149J3272D01*
G02X317656Y708364I0J3468D01*
G03X317524I-66J-189D01*
G02X317113Y708248I-1146J3273D01*
G02X317114Y708203I-3501J-100D01*
G01Y708199D01*
G02X316834Y706829I-3503J2D01*
G03Y706673I184J-78D01*
G02X317114Y705301I-3223J-1372D01*
G02X316143Y702881I-3503J1D01*
G03X316089Y702719I144J-138D01*
G02X316114Y702301I-3478J-418D01*
G02X313343Y698876I-3502J0D01*
G03X313226Y698802I42J-196D01*
G02X310445Y697428I-2782J2129D01*
G02X306942Y700931I0J3503D01*
G02X307243Y702350I3503J-2D01*
G03Y702512I-183J81D01*
G02X306942Y703931I3202J1421D01*
G02X307913Y706351I3503J-1D01*
G03X307967Y706513I-144J138D01*
G02X307942Y706931I3478J418D01*
G02X308292Y708456I3503J-1D01*
G03X308297Y708618I-180J87D01*
G02X308042Y709931I3248J1312D01*
G02X311545Y713434I3503J0D01*
G02X312019Y713401I-6J-3503D01*
G01X312067Y713394D01*
X312157Y713426D01*
X312415Y713696D01*
G03X312467Y713869I-145J138D01*
G01Y713870D01*
G02X312410Y714500I3445J629D01*
G37*
G36*
G01X1455274Y714194D02*
G02X1455554Y715566I3503J0D01*
G03Y715722I-184J78D01*
G02X1455274Y717094I3223J1372D01*
G02X1462280I3503J0D01*
G02X1462000Y715723I-3503J1D01*
G03Y715566I184J-78D01*
G02X1462059Y715418I-3223J-1371D01*
G03X1462235Y715288I188J70D01*
G02X1463194Y715098I-188J-3462D01*
G03X1463326I66J189D01*
G02X1464475Y715294I1149J-3272D01*
G02Y708358I0J-3468D01*
G02X1463326Y708554I0J3468D01*
G03X1463194I-66J-189D01*
G02X1462045Y708358I-1149J3272D01*
G02X1460896Y708554I0J3468D01*
G03X1460764I-66J-189D01*
G02X1460530Y708481I-1149J3272D01*
G03X1460383Y708283I53J-193D01*
G02X1460384Y708201I-3502J-84D01*
G02X1460104Y706829I-3503J0D01*
G03Y706673I184J-78D01*
G02X1460384Y705301I-3223J-1372D01*
G02X1458218Y702064I-3502J0D01*
G03X1458101Y701828I76J-185D01*
G02X1458218Y700932I-3386J-898D01*
G01Y700931D01*
G02X1451212I-3503J0D01*
G02X1451371Y701972I3503J-2D01*
G03X1451362Y702115I-191J60D01*
G01X1451313Y702222D01*
G03X1451211Y702323I-182J-82D01*
G02X1449112Y705531I1403J3209D01*
G02X1451314Y708783I3502J0D01*
G03X1451433Y709021I-74J186D01*
G02X1451312Y709931I3382J913D01*
G02X1454814Y713434I3503J0D01*
G01X1454816D01*
G02X1454883Y713433I-19J-3503D01*
G01X1454926Y713432D01*
X1455005Y713465D01*
X1455237Y713716D01*
G03X1455290Y713870I-146J136D01*
G02X1455274Y714194I3486J335D01*
G37*
G36*
G01X378310Y714157D02*
Y714161D01*
G02X378590Y715532I3502J-1D01*
G03Y715688I-184J78D01*
G02X378310Y717059I3222J1372D01*
G01Y717060D01*
G02X385314I3502J0D01*
G01Y717059D01*
G02X385034Y715688I-3502J1D01*
G03Y715532I184J-78D01*
G02X385207Y715020I-3221J-1374D01*
G03X385374Y714871I194J49D01*
G02X386054Y714708I-464J-3436D01*
G03X386186I66J189D01*
G02X387335Y714904I1149J-3272D01*
G02Y707968I0J-3468D01*
G02X386186Y708164I0J3468D01*
G03X386054I-66J-189D01*
G02X384905Y707968I-1149J3272D01*
G02X383756Y708164I0J3468D01*
G03X383624I-66J-189D01*
G02X383213Y708048I-1146J3273D01*
G02X383214Y708003I-3501J-100D01*
G01Y707999D01*
G02X382934Y706629I-3503J2D01*
G03Y706473I184J-78D01*
G02X383214Y705101I-3223J-1372D01*
G02X379711Y701598I-3503J0D01*
G02X377540Y702353I1J3503D01*
G03X377309Y702365I-124J-157D01*
G02X375445Y701828I-1864J2967D01*
G02X371942Y705331I0J3503D01*
G02X372222Y706703I3503J0D01*
G03Y706859I-184J78D01*
G02X371942Y708231I3223J1372D01*
G02X372222Y709603I3503J0D01*
G03Y709759I-184J78D01*
G02X371942Y711131I3223J1372D01*
G02X375445Y714634I3503J0D01*
G02X377657Y713847I0J-3502D01*
G01X377702Y713810D01*
X377816Y713796D01*
X378196Y713977D01*
G03X378310Y714157I-86J181D01*
G37*
G36*
G01X345172Y715688D02*
G02X344892Y717060I3223J1372D01*
G02X351898I3503J0D01*
G02X351618Y715688I-3503J0D01*
G03Y715532I184J-78D01*
G02X351832Y714835I-3223J-1371D01*
G02X351862Y714836I130J-3464D01*
G01X351868D01*
G02X353014Y714640I-3J-3468D01*
G03X353146I66J189D01*
G02X354295Y714836I1149J-3272D01*
G02Y707900I0J-3468D01*
G02X353146Y708096I0J3468D01*
G03X353014I-66J-189D01*
G02X351865Y707900I-1149J3272D01*
G02X350716Y708096I0J3468D01*
G03X350584I-66J-189D01*
G02X350173Y707980I-1146J3273D01*
G02X350174Y707935I-3501J-100D01*
G01Y707931D01*
G02X349894Y706561I-3503J2D01*
G03Y706405I184J-78D01*
G02X350174Y705033I-3223J-1372D01*
G02X346671Y701530I-3503J0D01*
G02X344500Y702285I1J3503D01*
G03X344269Y702297I-124J-157D01*
G02X342405Y701760I-1864J2967D01*
G02X338902Y705263I0J3503D01*
G02X339182Y706635I3503J0D01*
G03Y706791I-184J78D01*
G02X338902Y708163I3223J1372D01*
G02X339182Y709535I3503J0D01*
G03Y709691I-184J78D01*
G02X338902Y711063I3223J1372D01*
G02X342405Y714566I3503J0D01*
G02X344283Y714019I-2J-3503D01*
G01X344328Y713990D01*
X344434Y713986D01*
X344789Y714169D01*
G03X344897Y714337I-92J178D01*
G02X345172Y715532I3498J-176D01*
G03Y715688I-184J78D01*
G37*
G36*
G01X411210Y696540D02*
G02X411490Y697912I3502J0D01*
G03Y698068I-184J78D01*
G02X411210Y699439I3222J1372D01*
G01Y699440D01*
G02X418214I3502J0D01*
G01Y699439D01*
G02X417934Y698068I-3502J1D01*
G03X417935Y697912I185J-77D01*
G02X418145Y697237I-3223J-1373D01*
G03X418317Y697079I196J40D01*
G02X419054Y696908I-411J-3443D01*
G03X419186I66J189D01*
G02X420335Y697104I1149J-3272D01*
G02Y690168I0J-3468D01*
G02X419186Y690364I0J3468D01*
G03X419054I-66J-189D01*
G02X417905Y690168I-1149J3272D01*
G02X416756Y690364I0J3468D01*
G03X416624I-66J-189D01*
G02X416213Y690248I-1146J3273D01*
G02X416214Y690203I-3501J-100D01*
G01Y690199D01*
G02X415934Y688829I-3503J2D01*
G03Y688673I184J-78D01*
G02X416214Y687301I-3223J-1372D01*
G02X412711Y683798I-3503J0D01*
G02X410540Y684553I1J3503D01*
G03X410309Y684565I-124J-157D01*
G02X408445Y684028I-1864J2967D01*
G02X404942Y687531I0J3503D01*
G02X405222Y688903I3503J0D01*
G03Y689059I-184J78D01*
G02X404942Y690431I3223J1372D01*
G02X405222Y691803I3503J0D01*
G03Y691959I-184J78D01*
G02X404942Y693331I3223J1372D01*
G02X408445Y696834I3503J0D01*
G02X410567Y696116I-3J-3502D01*
G01X410569D01*
Y696115D01*
G03X410780Y696097I120J160D01*
G01X411102Y696262D01*
G03X411211Y696445I-91J178D01*
G02X411210Y696540I3501J84D01*
G37*
G36*
G01X1429187Y688892D02*
G02X1428038Y689087I-3J3467D01*
G03X1427906I-66J-189D01*
G02X1427612Y688998I-1151J3271D01*
G03X1427461Y688794I49J-194D01*
G02X1427466Y688624I-3497J-188D01*
G02X1427186Y687252I-3503J0D01*
G03Y687096I184J-78D01*
G02X1427466Y685724I-3223J-1372D01*
G02X1423963Y682222I-3503J1D01*
G01X1423962D01*
G02X1421792Y682976I1J3502D01*
G03X1421561Y682988I-124J-157D01*
G02X1419697Y682452I-1862J2967D01*
G02X1416194Y685954I-1J3502D01*
G02X1416474Y687326I3503J0D01*
G03Y687482I-184J78D01*
G02X1416194Y688854I3223J1372D01*
G02X1416474Y690226I3503J0D01*
G03Y690382I-184J78D01*
G02X1416194Y691754I3223J1372D01*
G02X1419697Y695256I3503J-1D01*
G02X1422498Y693857I0J-3504D01*
G03X1422615Y693782I160J120D01*
G02X1422652Y693774I-722J-3427D01*
G01X1422812Y693943D01*
G03X1422861Y694127I-145J137D01*
G02X1422762Y694954I3405J827D01*
G01Y694955D01*
G02X1423042Y696326I3502J-1D01*
G03Y696482I-184J78D01*
G02X1422762Y697853I3222J1372D01*
G01Y697854D01*
G02X1429766I3502J0D01*
G01Y697853D01*
G02X1429486Y696482I-3502J1D01*
G03Y696326I184J-78D01*
G02X1429631Y695916I-3223J-1370D01*
G03X1429789Y695773I193J54D01*
G02X1430336Y695631I-595J-3416D01*
G03X1430468I66J189D01*
G02X1431613Y695826I1146J-3272D01*
G01X1431617D01*
G02Y688892I0J-3467D01*
G01X1431613D01*
G02X1430468Y689087I1J3467D01*
G03X1430336I-66J-189D01*
G02X1429187Y688892I-1146J3272D01*
G37*
G36*
G01X286035Y688026D02*
G02X284886Y688221I-3J3467D01*
G03X284754I-66J-189D01*
G02X284343Y688105I-1146J3273D01*
G02X284344Y688052I-3501J-93D01*
G01Y688050D01*
G02X284064Y686679I-3503J1D01*
G03Y686523I184J-78D01*
G02X284344Y685151I-3223J-1372D01*
G02X280841Y681648I-3503J0D01*
G02X278670Y682403I1J3503D01*
G03X278439Y682415I-124J-157D01*
G02X276575Y681878I-1864J2967D01*
G02X273072Y685381I0J3503D01*
G02X273352Y686753I3503J0D01*
G03Y686909I-184J78D01*
G02X273072Y688281I3223J1372D01*
G02X273352Y689653I3503J0D01*
G03Y689809I-184J78D01*
G02X273072Y691181I3223J1372D01*
G02X276575Y694684I3503J0D01*
G02X278885Y693814I0J-3502D01*
G01X278930Y693774D01*
X279050Y693758D01*
X279437Y693949D01*
G03X279548Y694142I-88J179D01*
G02X279540Y694380I3494J237D01*
G02X279820Y695752I3502J0D01*
G03Y695908I-184J78D01*
G02X279540Y697279I3222J1372D01*
G01Y697280D01*
G02X286544I3502J0D01*
G01Y697279D01*
G02X286264Y695908I-3502J1D01*
G03Y695752I184J-78D01*
G02X286477Y695066I-3221J-1376D01*
G03X286638Y694908I196J39D01*
G02X287184Y694765I-603J-3415D01*
G03X287316I66J189D01*
G02X288461Y694960I1146J-3272D01*
G01X288465D01*
G02Y688026I0J-3467D01*
G01X288461D01*
G02X287316Y688221I1J3467D01*
G03X287184I-66J-189D01*
G02X286035Y688026I-1146J3272D01*
G37*
G36*
G01X1554692Y692501D02*
G02X1554992Y693920I3502J1D01*
G03Y694082I-183J81D01*
G02X1554692Y695499I3202J1418D01*
G01Y695501D01*
G02X1561696I3502J0D01*
G01Y695499D01*
G02X1561396Y694082I-3502J1D01*
G03Y693920I183J-81D01*
G02X1561616Y693249I-3201J-1421D01*
G03X1561772Y693095I196J42D01*
G02X1562236Y692968I-681J-3400D01*
G03X1562368I66J189D01*
G02X1563517Y693164I1149J-3272D01*
G02Y686228I0J-3468D01*
G02X1562368Y686424I0J3468D01*
G03X1562236I-66J-189D01*
G02X1561087Y686228I-1149J3272D01*
G02X1559938Y686424I0J3468D01*
G03X1559806I-66J-189D01*
G02X1559395Y686308I-1146J3273D01*
G02X1559396Y686263I-3501J-100D01*
G01Y686259D01*
G02X1559116Y684889I-3503J2D01*
G03Y684733I184J-78D01*
G02X1559396Y683361I-3223J-1372D01*
G02X1559161Y682101I-3503J1D01*
G03X1559168Y681940I186J-73D01*
G02X1559530Y680391I-3141J-1551D01*
G02X1556581Y676933I-3502J0D01*
G03X1556453Y676856I32J-198D01*
G02X1553657Y675462I-2797J2109D01*
G02X1550154Y678965I0J3503D01*
G02X1550455Y680384I3503J-2D01*
G03Y680546I-183J81D01*
G02X1550154Y681965I3202J1421D01*
G02X1550494Y683470I3503J0D01*
G03X1550498Y683634I-180J86D01*
G02X1550224Y684991I3229J1358D01*
G02X1550574Y686516I3503J-1D01*
G03X1550579Y686678I-180J87D01*
G02X1550324Y687991I3248J1312D01*
G02X1554292Y691463I3503J0D01*
G01X1554340Y691456D01*
X1554429Y691487D01*
X1554686Y691752D01*
G03X1554739Y691925I-144J139D01*
G02X1554692Y692501I3455J572D01*
G37*
G36*
G01X443990Y673168D02*
G02X443710Y674539I3222J1372D01*
G01Y674540D01*
G02X450714I3502J0D01*
G01Y674539D01*
G02X450434Y673168I-3502J1D01*
G03X450435Y673012I185J-77D01*
G02X450575Y672618I-3225J-1368D01*
G03X450742Y672476I192J56D01*
G02X451454Y672308I-436J-3440D01*
G03X451586I66J189D01*
G02X452735Y672504I1149J-3272D01*
G02Y665568I0J-3468D01*
G02X451586Y665764I0J3468D01*
G03X451454I-66J-189D01*
G02X450305Y665568I-1149J3272D01*
G02X449156Y665764I0J3468D01*
G03X449024I-66J-189D01*
G02X448613Y665648I-1146J3273D01*
G02X448614Y665603I-3501J-100D01*
G01Y665599D01*
G02X448334Y664229I-3503J2D01*
G03Y664073I184J-78D01*
G02X448614Y662701I-3223J-1372D01*
G02X445111Y659198I-3503J0D01*
G02X442940Y659953I1J3503D01*
G03X442709Y659965I-124J-157D01*
G02X440845Y659428I-1864J2967D01*
G02X437342Y662931I0J3503D01*
G02X437622Y664303I3503J0D01*
G03Y664459I-184J78D01*
G02X437342Y665831I3223J1372D01*
G02X437622Y667203I3503J0D01*
G03Y667359I-184J78D01*
G02X437342Y668731I3223J1372D01*
G02X440845Y672234I3503J0D01*
G02X443057Y671445I-2J-3502D01*
G01X443059D01*
Y671444D01*
G03X443267Y671418I125J156D01*
G01X443594Y671567D01*
G03X443711Y671743I-83J182D01*
G01Y671744D01*
G02X443990Y673012I3501J-106D01*
G03Y673168I-184J78D01*
G37*
G36*
G01X1396557Y656012D02*
G02X1395408Y656207I-3J3467D01*
G03X1395276I-66J-189D01*
G02X1394865Y656091I-1146J3273D01*
G02X1394866Y656046I-3501J-100D01*
G01Y656042D01*
G02X1394586Y654672I-3503J2D01*
G03Y654516I184J-78D01*
G02X1394866Y653144I-3223J-1372D01*
G02X1391363Y649642I-3503J1D01*
G01X1391362D01*
G02X1389192Y650396I1J3502D01*
G03X1388961Y650408I-124J-157D01*
G02X1387097Y649872I-1862J2967D01*
G02X1383594Y653374I-1J3502D01*
G02X1383874Y654746I3503J0D01*
G03Y654902I-184J78D01*
G02X1383594Y656274I3223J1372D01*
G02X1383874Y657646I3503J0D01*
G03Y657802I-184J78D01*
G02X1383594Y659174I3223J1372D01*
G02X1387097Y662676I3503J-1D01*
G02X1389897Y661278I0J-3503D01*
G03X1390016Y661202I160J120D01*
G02X1390055Y661194I-684J-3435D01*
G01X1390214Y661362D01*
G03X1390263Y661547I-145J138D01*
G02X1390162Y662384I3401J835D01*
G02X1390442Y663756I3502J0D01*
G03Y663912I-184J78D01*
G02X1390162Y665283I3222J1372D01*
G01Y665284D01*
G02X1397166I3502J0D01*
G01Y665283D01*
G02X1396886Y663912I-3502J1D01*
G03Y663756I184J-78D01*
G02X1397105Y663033I-3223J-1371D01*
G03X1397261Y662874I197J37D01*
G02X1397706Y662751I-699J-3396D01*
G03X1397838I66J189D01*
G02X1398983Y662946I1146J-3272D01*
G01X1398987D01*
G02Y656012I0J-3467D01*
G01X1398983D01*
G02X1397838Y656207I1J3467D01*
G03X1397706I-66J-189D01*
G02X1396557Y656012I-1146J3272D01*
G37*
G36*
G01X253305Y653778D02*
G02X252156Y653973I-3J3467D01*
G03X252024I-66J-189D01*
G02X251613Y653857I-1146J3273D01*
G02X251614Y653812I-3501J-100D01*
G01Y653808D01*
G02X251334Y652438I-3503J2D01*
G03Y652282I184J-78D01*
G02X251614Y650910I-3223J-1372D01*
G02X248111Y647408I-3503J1D01*
G01X248110D01*
G02X245940Y648162I1J3502D01*
G03X245709Y648174I-124J-157D01*
G02X243845Y647638I-1862J2967D01*
G02X240342Y651140I-1J3502D01*
G02X240622Y652512I3503J0D01*
G03Y652668I-184J78D01*
G02X240342Y654040I3223J1372D01*
G02X240622Y655412I3503J0D01*
G03Y655568I-184J78D01*
G02X240342Y656940I3223J1372D01*
G02X243845Y660442I3503J-1D01*
G01X243846D01*
G02X246158Y659570I0J-3502D01*
G01X246204Y659529D01*
X246324Y659514D01*
X246711Y659708D01*
G03X246821Y659902I-89J179D01*
G02X246810Y660180I3491J277D01*
G02X247090Y661552I3502J0D01*
G03Y661708I-184J78D01*
G02X246810Y663079I3222J1372D01*
G01Y663080D01*
G02X253814I3502J0D01*
G01Y663079D01*
G02X253534Y661708I-3502J1D01*
G03X253535Y661552I185J-77D01*
G02X253756Y660818I-3223J-1371D01*
G03X253917Y660658I197J37D01*
G02X254454Y660517I-609J-3414D01*
G03X254586I66J189D01*
G02X255731Y660712I1146J-3272D01*
G01X255735D01*
G02Y653778I0J-3467D01*
G01X255731D01*
G02X254586Y653973I1J3467D01*
G03X254454I-66J-189D01*
G02X253305Y653778I-1146J3272D01*
G37*
G36*
G01X1593857Y652460D02*
G02X1592708Y652655I-3J3467D01*
G03X1592576I-66J-189D01*
G02X1592165Y652539I-1146J3273D01*
G02X1592166Y652494I-3501J-100D01*
G01Y652490D01*
G02X1591886Y651120I-3503J2D01*
G03Y650964I184J-78D01*
G02X1592166Y649592I-3223J-1372D01*
G02X1588663Y646090I-3503J1D01*
G01X1588662D01*
G02X1586492Y646844I1J3502D01*
G03X1586261Y646856I-124J-157D01*
G02X1584397Y646320I-1862J2967D01*
G02X1580894Y649822I-1J3502D01*
G02X1581174Y651194I3503J0D01*
G03Y651350I-184J78D01*
G02X1580894Y652722I3223J1372D01*
G02X1581174Y654094I3503J0D01*
G03Y654250I-184J78D01*
G02X1580894Y655622I3223J1372D01*
G02X1584397Y659124I3503J-1D01*
G02X1587198Y657726I1J-3504D01*
G03X1587316Y657650I160J119D01*
G02X1587330Y657647I-727J-3426D01*
G01X1587490Y657813D01*
G03X1587542Y657994I-143J139D01*
G02X1587462Y658741I3422J744D01*
G02X1587762Y660160I3502J1D01*
G03Y660322I-183J81D01*
G02X1587462Y661739I3202J1418D01*
G01Y661741D01*
G02X1594466I3502J0D01*
G01Y661739D01*
G02X1594166Y660322I-3502J1D01*
G03Y660160I183J-81D01*
G02X1594387Y659480I-3203J-1417D01*
G03X1594543Y659326I196J42D01*
G02X1595006Y659199I-684J-3400D01*
G03X1595138I66J189D01*
G02X1596283Y659394I1146J-3272D01*
G01X1596287D01*
G02Y652460I0J-3467D01*
G01X1596283D01*
G02X1595138Y652655I1J3467D01*
G03X1595006I-66J-189D01*
G02X1593857Y652460I-1146J3272D01*
G37*
G36*
G01X1454046Y653872D02*
G02X1455229Y653667I2J-3502D01*
G03X1455363I67J188D01*
G02X1456546Y653872I1181J-3297D01*
G02X1457918Y653592I0J-3502D01*
G03X1458074I78J184D01*
G02X1459445Y653872I1372J-3222D01*
G01X1459446D01*
G02X1462948Y650370I0J-3502D01*
G01Y650365D01*
G02X1462701Y649077I-3502J4D01*
G03X1462699Y648936I186J-73D01*
G02X1462898Y647770I-3303J-1164D01*
G02X1462693Y646587I-3502J-2D01*
G03Y646453I188J-67D01*
G02X1462898Y645273I-3297J-1181D01*
G01Y645270D01*
G02X1459396Y641768I-3502J0D01*
G01X1459395D01*
G02X1458024Y642048I1J3502D01*
G03X1457868I-78J-184D01*
G02X1456496Y641768I-1372J3222D01*
G02X1455313Y641973I-2J3502D01*
G03X1455179I-67J-188D01*
G02X1453996Y641768I-1181J3297D01*
G02X1452813Y641973I-2J3502D01*
G03X1452679I-67J-188D01*
G02X1451496Y641768I-1181J3297D01*
G02X1450313Y641973I-2J3502D01*
G03X1450179I-67J-188D01*
G02X1448996Y641768I-1181J3297D01*
G02X1447757Y641994I-1J3502D01*
G03X1447615I-71J-187D01*
G02X1446376Y641768I-1238J3276D01*
G02X1445193Y641973I-2J3502D01*
G03X1445059I-67J-188D01*
G02X1443879Y641768I-1181J3297D01*
G01X1443876D01*
G02X1440374Y645270I0J3502D01*
G01Y645273D01*
G02X1440579Y646453I3502J-1D01*
G03Y646587I-188J67D01*
G02X1440374Y647770I3297J1181D01*
G02X1440621Y649063I3502J1D01*
G03X1440623Y649204I-186J73D01*
G02X1440424Y650366I3303J1164D01*
G01Y650370D01*
G02X1443926Y653872I3502J0D01*
G01X1443929D01*
G02X1445109Y653667I-1J-3502D01*
G03X1445243I67J188D01*
G02X1446426Y653872I1181J-3297D01*
G02X1447665Y653646I1J-3502D01*
G03X1447807I71J187D01*
G02X1449046Y653872I1238J-3276D01*
G02X1450229Y653667I2J-3502D01*
G03X1450363I67J188D01*
G02X1451546Y653872I1181J-3297D01*
G02X1452729Y653667I2J-3502D01*
G03X1452863I67J188D01*
G02X1454046Y653872I1181J-3297D01*
G37*
G36*
G01X476590Y646768D02*
G02X476310Y648139I3222J1372D01*
G01Y648140D01*
G02X483314I3502J0D01*
G01Y648139D01*
G02X483034Y646768I-3502J1D01*
G03X483035Y646612I185J-77D01*
G02X483202Y646120I-3224J-1369D01*
G03X483369Y645972I194J50D01*
G02X484054Y645808I-461J-3437D01*
G03X484186I66J189D01*
G02X485335Y646004I1149J-3272D01*
G02Y639068I0J-3468D01*
G02X484186Y639264I0J3468D01*
G03X484054I-66J-189D01*
G02X482905Y639068I-1149J3272D01*
G02X481756Y639264I0J3468D01*
G03X481624I-66J-189D01*
G02X481213Y639148I-1146J3273D01*
G02X481214Y639103I-3501J-100D01*
G01Y639099D01*
G02X480934Y637729I-3503J2D01*
G03Y637573I184J-78D01*
G02X481214Y636201I-3223J-1372D01*
G02X477711Y632698I-3503J0D01*
G02X475540Y633453I1J3503D01*
G03X475309Y633465I-124J-157D01*
G02X473445Y632928I-1864J2967D01*
G02X469942Y636431I0J3503D01*
G02X470222Y637803I3503J0D01*
G03Y637959I-184J78D01*
G02X469942Y639331I3223J1372D01*
G02X470222Y640703I3503J0D01*
G03Y640859I-184J78D01*
G02X469942Y642231I3223J1372D01*
G02X473445Y645734I3503J0D01*
G02X475657Y644947I0J-3502D01*
G03X475869Y644921I127J155D01*
G01X476196Y645075D01*
G03X476310Y645255I-86J181D01*
G02X476590Y646612I3502J-15D01*
G03Y646768I-184J78D01*
G37*
G36*
G01X350095Y649556D02*
G02X351278Y649351I2J-3502D01*
G03X351412I67J188D01*
G02X352595Y649556I1181J-3297D01*
G02X353774Y649352I1J-3502D01*
G03X353915Y649354I68J188D01*
G02X355195Y649596I1279J-3260D01*
G02X358698Y646094I1J-3502D01*
G02X358517Y644986I-3502J3D01*
G03X358522Y644848I190J-62D01*
G02X358778Y643534I-3247J-1315D01*
G02X358572Y642352I-3503J2D01*
G03Y642216I188J-68D01*
G02X358778Y641034I-3297J-1184D01*
G02X355275Y637532I-3503J1D01*
G01X355272D01*
G02X354096Y637736I2J3502D01*
G03X353955Y637734I-68J-188D01*
G02X352675Y637492I-1279J3260D01*
G02X351492Y637697I-2J3502D01*
G03X351358I-67J-188D01*
G02X350175Y637492I-1181J3297D01*
G02X348992Y637697I-2J3502D01*
G03X348858I-67J-188D01*
G02X347675Y637492I-1181J3297D01*
G02X346492Y637697I-2J3502D01*
G03X346358I-67J-188D01*
G02X345175Y637492I-1181J3297D01*
G02X343992Y637697I-2J3502D01*
G03X343858I-67J-188D01*
G02X342675Y637492I-1181J3297D01*
G02X339172Y640994I-1J3502D01*
G02X339378Y642176I3503J-2D01*
G03Y642312I-188J68D01*
G02X339172Y643494I3297J1184D01*
G02X339353Y644602I3502J-3D01*
G03X339348Y644740I-190J62D01*
G02X339092Y646054I3247J1315D01*
G02X342595Y649556I3503J-1D01*
G01X342598D01*
G02X343778Y649351I-1J-3502D01*
G03X343912I67J188D01*
G02X345095Y649556I1181J-3297D01*
G02X346278Y649351I2J-3502D01*
G03X346412I67J188D01*
G02X347595Y649556I1181J-3297D01*
G02X348778Y649351I2J-3502D01*
G03X348912I67J188D01*
G02X350095Y649556I1181J-3297D01*
G37*
G36*
G01X1626857Y633460D02*
G02X1625708Y633655I-3J3467D01*
G03X1625576I-66J-189D01*
G02X1625165Y633539I-1146J3273D01*
G02X1625166Y633494I-3501J-100D01*
G01Y633490D01*
G02X1624886Y632120I-3503J2D01*
G03Y631964I184J-78D01*
G02X1625166Y630592I-3223J-1372D01*
G02X1621663Y627090I-3503J1D01*
G01X1621662D01*
G02X1619492Y627844I1J3502D01*
G03X1619261Y627856I-124J-157D01*
G02X1617397Y627320I-1862J2967D01*
G02X1613894Y630822I-1J3502D01*
G02X1614174Y632194I3503J0D01*
G03Y632350I-184J78D01*
G02X1613894Y633722I3223J1372D01*
G02X1614174Y635094I3503J0D01*
G03Y635250I-184J78D01*
G02X1613894Y636622I3223J1372D01*
G02X1617397Y640124I3503J-1D01*
G02X1620198Y638726I1J-3504D01*
G03X1620316Y638650I160J119D01*
G02X1620330Y638647I-727J-3426D01*
G01X1620490Y638813D01*
G03X1620542Y638994I-143J139D01*
G02X1620462Y639741I3422J744D01*
G02X1620762Y641160I3502J1D01*
G03Y641322I-183J81D01*
G02X1620462Y642739I3202J1418D01*
G01Y642741D01*
G02X1627466I3502J0D01*
G01Y642739D01*
G02X1627166Y641322I-3502J1D01*
G03Y641160I183J-81D01*
G02X1627387Y640480I-3203J-1417D01*
G03X1627543Y640326I196J42D01*
G02X1628006Y640199I-684J-3400D01*
G03X1628138I66J189D01*
G02X1629283Y640394I1146J-3272D01*
G01X1629287D01*
G02Y633460I0J-3467D01*
G01X1629283D01*
G02X1628138Y633655I1J3467D01*
G03X1628006I-66J-189D01*
G02X1626857Y633460I-1146J3272D01*
G37*
G36*
G01X1363857Y623112D02*
G02X1362708Y623307I-3J3467D01*
G03X1362576I-66J-189D01*
G02X1362165Y623191I-1146J3273D01*
G02X1362166Y623146I-3501J-100D01*
G01Y623142D01*
G02X1361886Y621772I-3503J2D01*
G03Y621616I184J-78D01*
G02X1362166Y620244I-3223J-1372D01*
G02X1358663Y616742I-3503J1D01*
G01X1358662D01*
G02X1356492Y617496I1J3502D01*
G03X1356261Y617508I-124J-157D01*
G02X1354397Y616972I-1862J2967D01*
G02X1350894Y620474I-1J3502D01*
G02X1351174Y621846I3503J0D01*
G03Y622002I-184J78D01*
G02X1350894Y623374I3223J1372D01*
G02X1351174Y624746I3503J0D01*
G03Y624902I-184J78D01*
G02X1350894Y626274I3223J1372D01*
G02X1354397Y629776I3503J-1D01*
G02X1357197Y628378I0J-3503D01*
G03X1357316Y628302I160J120D01*
G02X1357363Y628292I-705J-3431D01*
G01X1357522Y628461D01*
G03X1357570Y628647I-146J137D01*
G02X1357462Y629514I3394J863D01*
G02X1357742Y630886I3502J0D01*
G03Y631042I-184J78D01*
G02X1357462Y632413I3222J1372D01*
G01Y632414D01*
G02X1364466I3502J0D01*
G01Y632413D01*
G02X1364186Y631042I-3502J1D01*
G03X1364187Y630886I185J-77D01*
G02X1364411Y630133I-3224J-1369D01*
G03X1364567Y629973I197J36D01*
G02X1365006Y629851I-707J-3395D01*
G03X1365138I66J189D01*
G02X1366283Y630046I1146J-3272D01*
G01X1366287D01*
G02Y623112I0J-3467D01*
G01X1366283D01*
G02X1365138Y623307I1J3467D01*
G03X1365006I-66J-189D01*
G02X1363857Y623112I-1146J3272D01*
G37*
G36*
G01X1521274Y615618D02*
G02X1521480Y616800I3503J-2D01*
G03Y616936I-188J68D01*
G02X1521274Y618118I3297J1184D01*
G02X1524777Y621620I3503J-1D01*
G01X1524780D01*
G02X1525960Y621415I-1J-3502D01*
G03X1526094I67J188D01*
G02X1527277Y621620I1181J-3297D01*
G02X1530780Y618118I1J-3502D01*
G02X1530574Y616936I-3503J2D01*
G03Y616800I188J-68D01*
G02X1530780Y615618I-3297J-1184D01*
G02X1530569Y614421I-3503J0D01*
G03Y614285I188J-68D01*
G02X1530780Y613088I-3292J-1197D01*
G02X1530574Y611906I-3503J2D01*
G03Y611770I188J-68D01*
G02X1530780Y610588I-3297J-1184D01*
G02X1530556Y609358I-3503J2D01*
G03Y609218I188J-70D01*
G02X1530780Y607988I-3279J-1232D01*
G02X1530574Y606806I-3503J2D01*
G03Y606670I188J-68D01*
G02X1530780Y605488I-3297J-1184D01*
G02X1527277Y601986I-3503J1D01*
G01X1527274D01*
G02X1526094Y602191I1J3502D01*
G03X1525960I-67J-188D01*
G02X1524777Y601986I-1181J3297D01*
G02X1521274Y605488I-1J3502D01*
G02X1521480Y606670I3503J-2D01*
G03Y606806I-188J68D01*
G02X1521274Y607988I3297J1184D01*
G02X1521498Y609218I3503J-2D01*
G03Y609358I-188J70D01*
G02X1521274Y610588I3279J1232D01*
G02X1521480Y611770I3503J-2D01*
G03Y611906I-188J68D01*
G02X1521274Y613088I3297J1184D01*
G02X1521485Y614285I3503J0D01*
G03Y614421I-188J68D01*
G02X1521274Y615618I3292J1197D01*
G37*
G36*
G01X509790Y612568D02*
G02X509510Y613939I3222J1372D01*
G01Y613940D01*
G02X516514I3502J0D01*
G01Y613939D01*
G02X516234Y612568I-3502J1D01*
G03X516235Y612412I185J-77D01*
G02X516372Y612030I-3223J-1372D01*
G03X516544Y611887I192J56D01*
G02X517354Y611708I-338J-3451D01*
G03X517486I66J189D01*
G02X518635Y611904I1149J-3272D01*
G02Y604968I0J-3468D01*
G02X517486Y605164I0J3468D01*
G03X517354I-66J-189D01*
G02X516205Y604968I-1149J3272D01*
G02X515056Y605164I0J3468D01*
G03X514924I-66J-189D01*
G02X514513Y605048I-1146J3273D01*
G02X514514Y605003I-3501J-100D01*
G01Y604999D01*
G02X514234Y603629I-3503J2D01*
G03Y603473I184J-78D01*
G02X514514Y602101I-3223J-1372D01*
G02X511011Y598598I-3503J0D01*
G02X508840Y599353I1J3503D01*
G03X508609Y599365I-124J-157D01*
G02X506745Y598828I-1864J2967D01*
G02X503242Y602331I0J3503D01*
G02X503522Y603703I3503J0D01*
G03Y603859I-184J78D01*
G02X503242Y605231I3223J1372D01*
G02X503522Y606603I3503J0D01*
G03Y606759I-184J78D01*
G02X503242Y608131I3223J1372D01*
G02X506745Y611634I3503J0D01*
G02X508871Y610914I-1J-3503D01*
G01X508916Y610880D01*
X509025Y610868D01*
X509449Y611065D01*
X509511Y611157D01*
X509514Y611212D01*
G02X509790Y612412I3498J-173D01*
G03Y612568I-184J78D01*
G37*
G36*
G01X465331Y604516D02*
G02X466514Y604311I2J-3502D01*
G03X466648I67J188D01*
G02X467831Y604516I1181J-3297D01*
G02X469014Y604311I2J-3502D01*
G03X469148I67J188D01*
G02X470331Y604516I1181J-3297D01*
G02X473834Y601014I1J-3502D01*
G02X473628Y599832I-3503J2D01*
G03Y599696I188J-68D01*
G02X473834Y598514I-3297J-1184D01*
G02X470331Y595012I-3503J1D01*
G01X470328D01*
G02X469148Y595217I1J3502D01*
G03X469014I-67J-188D01*
G02X467831Y595012I-1181J3297D01*
G02X466648Y595217I-2J3502D01*
G03X466514I-67J-188D01*
G02X465331Y595012I-1181J3297D01*
G02X464148Y595217I-2J3502D01*
G03X464014I-67J-188D01*
G02X462831Y595012I-1181J3297D01*
G02X461592Y595238I-1J3502D01*
G03X461450I-71J-187D01*
G02X460211Y595012I-1238J3276D01*
G02X459028Y595217I-2J3502D01*
G03X458894I-67J-188D01*
G02X457711Y595012I-1181J3297D01*
G02X454208Y598514I-1J3502D01*
G02X454414Y599696I3503J-2D01*
G03Y599832I-188J68D01*
G02X454208Y601014I3297J1184D01*
G02X457711Y604516I3503J-1D01*
G01X457714D01*
G02X458894Y604311I-1J-3502D01*
G03X459028I67J188D01*
G02X460211Y604516I1181J-3297D01*
G02X461450Y604290I1J-3502D01*
G03X461592I71J187D01*
G02X462831Y604516I1238J-3276D01*
G02X464014Y604311I2J-3502D01*
G03X464148I67J188D01*
G02X465331Y604516I1181J-3297D01*
G37*
G36*
G01X981891Y205046D02*
G02X983641Y205656I1987J-2884D01*
G03X983827Y205842I-14J200D01*
G02X987321Y209102I3494J-242D01*
G02X987564Y209093I-8J-3503D01*
G03X987721Y209152I15J199D01*
G02X990221Y210202I2501J-2453D01*
G02X993724Y206699I0J-3503D01*
G02X993308Y205044I-3503J1D01*
G03Y204854I176J-95D01*
G02X993724Y203199I-3087J-1656D01*
G02X993308Y201544I-3503J1D01*
G03Y201354I176J-95D01*
G02X993724Y199699I-3087J-1656D01*
G02X990221Y196196I-3503J0D01*
G02X989978Y196205I8J3503D01*
G03X989821Y196146I-15J-199D01*
G02X989542Y195890I-2504J2449D01*
G03X989471Y195701I126J-155D01*
G02X989524Y195099I-3450J-607D01*
G02X982518I-3503J0D01*
G02X983800Y197808I3503J0D01*
G03X983871Y197997I-126J155D01*
G02X983818Y198598I3450J607D01*
G01Y198600D01*
G02X983819Y198660I3503J-28D01*
G02X982055Y199171I59J3502D01*
G03X981837Y199165I-104J-170D01*
G02X979849Y198546I-1988J2884D01*
G02X977910Y199132I1J3503D01*
G03X977688I-111J-166D01*
G02X975749Y198546I-1940J2917D01*
G02X972359Y201167I0J3503D01*
G03X972153Y201317I-194J-50D01*
G02X971943Y201310I-222J3496D01*
G02X970051Y201866I2J3503D01*
G03X969835I-108J-169D01*
G02X967943Y201310I-1894J2947D01*
G02X964686Y203525I0J3502D01*
G03X964536Y203648I-186J-74D01*
G02X963305Y205125I271J1477D01*
G02X964807Y206627I1502J0D01*
G01X964833D01*
G03X965004Y206718I3J200D01*
G02X967943Y208316I2939J-1904D01*
G02X969835Y207760I-2J-3503D01*
G03X970051I108J169D01*
G02X971943Y208316I1894J-2947D01*
G02X974028Y207627I-1J-3503D01*
G01X974059Y207604D01*
X974131Y207584D01*
X974478Y207624D01*
X974544Y207658D01*
X974569Y207687D01*
G02X977221Y208902I2652J-2287D01*
G02X980718Y205584I0J-3502D01*
G03X980860Y205403I200J11D01*
G02X981673Y205040I-1010J-3354D01*
G03X981891Y205046I104J170D01*
G37*
G36*
G01X943221Y179892D02*
G02X944403Y179686I-2J-3503D01*
G03X944539I68J188D01*
G02X945721Y179892I1184J-3297D01*
G02X946854Y179703I-2J-3503D01*
G03X946999Y179709I65J189D01*
G02X948401Y180002I1402J-3210D01*
G02X951904Y176499I0J-3503D01*
G02X949342Y173125I-3503J0D01*
G03X949197Y172957I54J-193D01*
G02X945721Y169886I-3476J432D01*
G02X944539Y170092I2J3503D01*
G03X944403I-68J-188D01*
G02X943221Y169886I-1184J3297D01*
G02X942039Y170092I2J3503D01*
G03X941903I-68J-188D01*
G02X940721Y169886I-1184J3297D01*
G02X939510Y170103I3J3503D01*
G03X939372I-69J-188D01*
G02X938161Y169886I-1214J3286D01*
G02X937002Y170084I2J3503D01*
G03X936861Y170081I-67J-189D01*
G02X935551Y169826I-1312J3248D01*
G02X932048Y173329I0J3503D01*
G02X932313Y174663I3503J-2D01*
G03X932315Y174810I-185J76D01*
G02X932088Y176049I3276J1240D01*
G02X935591Y179552I3503J0D01*
G02X936376Y179463I0J-3503D01*
G03X936515Y179481I45J195D01*
G02X938161Y179892I1646J-3091D01*
G02X939372Y179675I-3J-3503D01*
G03X939510I69J188D01*
G02X940721Y179892I1214J-3286D01*
G02X941903Y179686I-2J-3503D01*
G03X942039I68J188D01*
G02X943221Y179892I1184J-3297D01*
G37*
G36*
G01X959170Y167763D02*
G02X959376Y168945I3503J-2D01*
G03Y169081I-188J68D01*
G02X959170Y170263I3297J1184D01*
G02X966176I3503J0D01*
G02X965970Y169081I-3503J2D01*
G03Y168945I188J-68D01*
G02X966176Y167763I-3297J-1184D01*
G02X959170I-3503J0D01*
G37*
G36*
G01X975691Y157718D02*
G02Y164722I0J3502D01*
G01X975693D01*
G02X978131Y163733I-1J-3502D01*
G01X978159Y163705D01*
X978231Y163676D01*
X978548Y163675D01*
G03X978686Y163730I0J200D01*
G01X978687Y163731D01*
G02X981112Y164706I2425J-2528D01*
G02Y157702I0J-3502D01*
G01X981110D01*
G02X978672Y158691I1J3502D01*
G01X978644Y158719D01*
X978572Y158748D01*
X978255Y158749D01*
G03X978117Y158694I0J-200D01*
G01X978116Y158693D01*
G02X975691Y157718I-2425J2528D01*
G37*
G36*
G01X786322Y149471D02*
G02X783651Y146068I-3503J0D01*
G03X783507Y145933I47J-194D01*
G02X780159Y143458I-3348J1027D01*
G02X776656Y146961I0J3503D01*
G02X779327Y150364I3503J0D01*
G03X779471Y150499I-47J194D01*
G02X782819Y152974I3348J-1027D01*
G02X786322Y149471I0J-3503D01*
G37*
G36*
G01X787681Y124450D02*
G02X788863Y124244I-2J-3503D01*
G03X788999I68J188D01*
G02X790181Y124450I1184J-3297D01*
G02X791363Y124244I-2J-3503D01*
G03X791499I68J188D01*
G02X792681Y124450I1184J-3297D01*
G02Y117444I0J-3503D01*
G02X792393Y117456I2J3503D01*
G03X792191Y117331I-16J-199D01*
G02X788941Y115134I-3250J1305D01*
G02X787759Y115340I2J3503D01*
G03X787623I-68J-188D01*
G02X786441Y115134I-1184J3297D01*
G02X785259Y115340I2J3503D01*
G03X785123I-68J-188D01*
G02X783941Y115134I-1184J3297D01*
G02X782759Y115340I2J3503D01*
G03X782623I-68J-188D01*
G02X781441Y115134I-1184J3297D01*
G02Y122140I0J3503D01*
G02X781729Y122128I-2J-3503D01*
G03X781931Y122253I16J199D01*
G02X785181Y124450I3250J-1305D01*
G02X786363Y124244I-2J-3503D01*
G03X786499I68J188D01*
G02X787681Y124450I1184J-3297D01*
G37*
G36*
G01X694221Y108364D02*
X694223D01*
G02X695877Y107949I0J-3502D01*
G03X696065I94J176D01*
G02X697721Y108364I1654J-3087D01*
G02X699377Y107949I2J-3502D01*
G03X699565I94J176D01*
G02X701219Y108364I1654J-3087D01*
G01X701221D01*
G02X704713Y105131I0J-3502D01*
G03X704794Y104985I200J15D01*
G02X705722Y103968I-2073J-2823D01*
G03X705938Y103876I171J103D01*
G02X706716Y103964I780J-3414D01*
G01X706721D01*
G02Y96960I0J-3502D01*
G02X703720Y98656I0J3503D01*
G03X703504Y98748I-171J-103D01*
G02X702721Y98660I-780J3414D01*
G02X701065Y99075I-2J3502D01*
G03X700877I-94J-176D01*
G02X699221Y98660I-1654J3087D01*
G02X697565Y99075I-2J3502D01*
G03X697377I-94J-176D01*
G02X695723Y98660I-1654J3087D01*
G01X695721D01*
G02X692229Y101893I0J3502D01*
G03X692148Y102039I-200J-15D01*
G02X690718Y104862I2071J2823D01*
G02X694221Y108364I3503J-1D01*
G37*
G36*
G01X1736731Y105796D02*
G02X1738386Y105380I-1J-3503D01*
G03X1738576I95J176D01*
G02X1740231Y105796I1656J-3087D01*
G02X1741886Y105380I-1J-3503D01*
G03X1742076I95J176D01*
G02X1743731Y105796I1656J-3087D01*
G02X1747049Y103414I0J-3502D01*
G03X1747141Y103303I190J64D01*
G02X1748844Y101047I-1706J-3059D01*
G03X1749019Y100894I195J46D01*
G02X1752188Y97408I-333J-3486D01*
G02X1748686Y93906I-3502J0D01*
G02X1745277Y96605I0J3502D01*
G03X1745102Y96758I-195J-46D01*
G02X1743779Y97157I330J3487D01*
G03X1743591I-94J-176D01*
G02X1741935Y96742I-1654J3087D01*
G02X1740279Y97157I-2J3502D01*
G03X1740091I-94J-176D01*
G02X1738437Y96742I-1654J3087D01*
G01X1738435D01*
G02X1735117Y99123I0J3502D01*
G03X1735025Y99234I-190J-64D01*
G02X1733228Y102293I1705J3059D01*
G02X1736731Y105796I3503J0D01*
G37*
G36*
G01X261416Y104168D02*
G02X263071Y103752I-1J-3503D01*
G03X263261I95J176D01*
G02X264916Y104168I1656J-3087D01*
G02X266571Y103752I-1J-3503D01*
G03X266761I95J176D01*
G02X268416Y104168I1656J-3087D01*
G02X271908Y100934I0J-3502D01*
G03X271989Y100788I200J15D01*
G02X272651Y100153I-2073J-2823D01*
G03X272851Y100083I156J125D01*
G02X273616Y100168I767J-3418D01*
G02Y93162I0J-3503D01*
G02X270881Y94477I0J3502D01*
G03X270681Y94547I-156J-125D01*
G02X269916Y94462I-767J3418D01*
G02X268261Y94878I1J3503D01*
G03X268071I-95J-176D01*
G02X266416Y94462I-1656J3087D01*
G02X264761Y94878I1J3503D01*
G03X264571I-95J-176D01*
G02X262916Y94462I-1656J3087D01*
G02X259424Y97696I0J3502D01*
G03X259343Y97842I-200J-15D01*
G02X257914Y100665I2073J2823D01*
G02X261416Y104168I3502J1D01*
G37*
G36*
G01X746532Y89988D02*
Y89989D01*
G02X746812Y91360I3502J-1D01*
G03Y91516I-184J78D01*
G02X746532Y92887I3222J1372D01*
G01Y92888D01*
G02X753536I3502J0D01*
G01Y92887D01*
G02X753256Y91516I-3502J1D01*
G03Y91360I184J-78D01*
G02X753536Y89989I-3222J-1372D01*
G01Y89988D01*
G02X746532I-3502J0D01*
G37*
G36*
G01X693226Y81552D02*
G02X693431Y82735I3502J2D01*
G03Y82869I-188J67D01*
G02X693226Y84049I3297J1181D01*
G01Y84052D01*
G02X695374Y87282I3503J0D01*
G03X695481Y87389I-77J184D01*
G02X698711Y89538I3230J-1353D01*
G02X702214Y86035I0J-3503D01*
G02X700174Y82852I-3503J0D01*
G03X700067Y82610I84J-182D01*
G02X700230Y81556I-3339J-1056D01*
G01Y81552D01*
G02X699726Y79743I-3501J1D01*
G03X699707Y79578I171J-103D01*
G02X699874Y78512I-3336J-1069D01*
G02X692868I-3503J0D01*
G02X693373Y80321I3502J-3D01*
G03X693392Y80486I-171J103D01*
G02X693226Y81552I3336J1065D01*
G37*
G36*
G01X1734114Y79140D02*
G02X1734320Y80322I3503J-2D01*
G03Y80458I-188J68D01*
G02X1734114Y81640I3297J1184D01*
G02X1737617Y85142I3503J-1D01*
G01X1737620D01*
G02X1738824Y84928I-1J-3502D01*
G03X1739040Y84981I68J188D01*
G02X1741621Y86116I2581J-2367D01*
G02X1745124Y82613I0J-3503D01*
G02X1744918Y81431I-3503J2D01*
G03Y81295I188J-68D01*
G02X1745124Y80113I-3297J-1184D01*
G02X1744708Y78458I-3503J1D01*
G03Y78268I176J-95D01*
G02X1745124Y76613I-3087J-1656D01*
G02X1744918Y75431I-3503J2D01*
G03Y75295I188J-68D01*
G02X1745124Y74113I-3297J-1184D01*
G02X1741621Y70610I-3503J0D01*
G02X1740414Y70825I1J3503D01*
G03X1740198Y70772I-68J-188D01*
G02X1737617Y69638I-2580J2368D01*
G02X1734114Y73140I-1J3502D01*
G02X1734320Y74322I3503J-2D01*
G03Y74458I-188J68D01*
G02X1734114Y75640I3297J1184D01*
G02X1734530Y77295I3503J-1D01*
G03Y77485I-176J95D01*
G02X1734114Y79140I3087J1656D01*
G37*
G36*
G01X1454786Y76366D02*
G02Y84312I0J3973D01*
G01X1454886D01*
G02X1458808Y80389I-1J-3923D01*
G02X1454786Y76366I-4022J-1D01*
G37*
G36*
G01X259390Y77529D02*
G02X259596Y78711I3503J-2D01*
G03Y78847I-188J68D01*
G02X259390Y80029I3297J1184D01*
G02X266396I3503J0D01*
G02X266190Y78847I-3503J2D01*
G03Y78711I188J-68D01*
G02X266396Y77529I-3297J-1184D01*
G02X265926Y75777I-3503J1D01*
G03X265941Y75554I173J-100D01*
G02X266353Y74883I-2760J-2157D01*
G01Y74881D01*
G03X266515Y74768I181J86D01*
G01X266858Y74735D01*
G03X267037Y74814I19J199D01*
G01X267038Y74815D01*
G02X269860Y76244I2823J-2074D01*
G02Y69238I0J-3503D01*
G02X266689Y71254I0J3503D01*
G01Y71256D01*
G03X266527Y71369I-181J-86D01*
G01X266184Y71402D01*
G03X266005Y71323I-19J-199D01*
G01X266004Y71322D01*
G02X263182Y69894I-2822J2074D01*
G02X259680Y73396I0J3502D01*
G01Y73397D01*
G02X260149Y75148I3502J0D01*
G03X260134Y75371I-173J100D01*
G02X259390Y77529I2758J2158D01*
G37*
G36*
G01X1776242Y70073D02*
Y70074D01*
G02X1776522Y71445I3502J-1D01*
G03Y71601I-184J78D01*
G02X1776242Y72972I3222J1372D01*
G01Y72973D01*
G02X1783246I3502J0D01*
G01Y72972D01*
G02X1782966Y71601I-3502J1D01*
G03Y71445I184J-78D01*
G02X1783246Y70074I-3222J-1372D01*
G01Y70073D01*
G02X1776242I-3502J0D01*
G37*
G36*
G01X311150Y68906D02*
G02X311430Y70278I3503J0D01*
G03Y70434I-184J78D01*
G02X311150Y71806I3223J1372D01*
G02X318156I3503J0D01*
G02X317876Y70434I-3503J0D01*
G03Y70278I184J-78D01*
G02X318156Y68906I-3223J-1372D01*
G02X311150I-3503J0D01*
G37*
G36*
G01X1225541Y63504D02*
X1225441D01*
G02X1221518Y67427I0J3923D01*
G02X1225540Y71450I4023J0D01*
G01X1225541D01*
G02Y63504I0J-3973D01*
G37*
G36*
G01X306470Y61658D02*
X306466D01*
G02X305379Y61832I3J3502D01*
G03X305238Y61825I-61J-190D01*
G02X303854Y61540I-1384J3217D01*
G01X303852D01*
G02Y68544I0J3502D01*
G01X303856D01*
G02X304943Y68370I-3J-3502D01*
G03X305084Y68377I61J190D01*
G02X306468Y68662I1384J-3217D01*
G01X306470D01*
G02Y61658I0J-3502D01*
G37*
G36*
G01X757721Y68134D02*
X757724D01*
G02X758904Y67929I-1J-3502D01*
G03X759038I67J188D01*
G02X760221Y68134I1181J-3297D01*
G02X761115Y68018I0J-3502D01*
G03X761277Y68045I51J194D01*
G02X763221Y68634I1944J-2913D01*
G02X766724Y65132I1J-3502D01*
G02X766134Y63188I-3503J2D01*
G03X766107Y63026I167J-111D01*
G02X766224Y62132I-3386J-898D01*
G02X762721Y58630I-3503J1D01*
G01X762718D01*
G02X761538Y58835I1J3502D01*
G03X761404I-67J-188D01*
G02X760221Y58630I-1181J3297D01*
G02X759038Y58835I-2J3502D01*
G03X758904I-67J-188D01*
G02X757721Y58630I-1181J3297D01*
G02X754218Y62132I-1J3502D01*
G02X754424Y63314I3503J-2D01*
G03Y63450I-188J68D01*
G02X754218Y64632I3297J1184D01*
G02X757721Y68134I3503J-1D01*
G37*
G36*
G01X1770792Y60133D02*
G02X1771072Y61505I3502J0D01*
G03Y61661I-184J78D01*
G02X1770792Y63032I3222J1372D01*
G01Y63033D01*
G02X1777796I3502J0D01*
G01Y63032D01*
G02X1777516Y61661I-3502J1D01*
G03Y61505I184J-78D01*
G02X1777796Y60133I-3222J-1372D01*
G02X1777507Y58738I-3502J-2D01*
G03Y58579I183J-79D01*
G02X1777794Y57191I-3216J-1389D01*
G02X1770788I-3503J0D01*
G02X1771078Y58586I3503J-1D01*
G03X1771079Y58745I-183J81D01*
G02X1770792Y60133I3215J1388D01*
G37*
G36*
G01X1734590Y53103D02*
G02X1734796Y54285I3503J-2D01*
G03Y54421I-188J68D01*
G02X1734590Y55603I3297J1184D01*
G02X1741596I3503J0D01*
G02X1741390Y54421I-3503J2D01*
G03Y54285I188J-68D01*
G02X1741596Y53103I-3297J-1184D01*
G02X1734590I-3503J0D01*
G37*
G36*
G01X752118Y51602D02*
G02X755621Y55104I3503J-1D01*
G01X755623D01*
G02X757040Y54804I-1J-3502D01*
G03X757202I81J183D01*
G02X758621Y55104I1418J-3202D01*
G02X762124Y51602I1J-3502D01*
G02X760383Y48575I-3502J0D01*
G01X760382Y48574D01*
G03X760284Y48421I101J-173D01*
G01X760252Y48099D01*
G03X760319Y47929I199J-20D01*
G02X754928Y47567I-2516J-2851D01*
G01X754962Y47606D01*
X754984Y47707D01*
X754852Y48131D01*
X754778Y48202D01*
X754728Y48215D01*
G02X752118Y51602I893J3387D01*
G37*
G36*
G01X257516Y55068D02*
G02X259171Y54652I-1J-3503D01*
G03X259361I95J176D01*
G02X261016Y55068I1656J-3087D01*
G02X262198Y54862I-2J-3503D01*
G03X262334I68J188D01*
G02X263516Y55068I1184J-3297D01*
G02X266921Y52387I0J-3503D01*
G03X267021Y52257I195J46D01*
G02X268868Y49171I-1655J-3086D01*
G02X265365Y45668I-3503J0D01*
G02X263864Y46006I0J3503D01*
G03X263672Y45995I-86J-181D01*
G02X261816Y45462I-1857J2970D01*
G02X260634Y45668I2J3503D01*
G03X260498I-68J-188D01*
G02X259316Y45462I-1184J3297D01*
G02X257661Y45878I1J3503D01*
G03X257471I-95J-176D01*
G02X255816Y45462I-1656J3087D01*
G02X254161Y45878I1J3503D01*
G03X253971I-95J-176D01*
G02X252316Y45462I-1656J3087D01*
G02X250661Y45878I1J3503D01*
G03X250471I-95J-176D01*
G02X248816Y45462I-1656J3087D01*
G02X245314Y48965I1J3503D01*
G02X246959Y51935I3504J0D01*
G03X247051Y52075I-106J170D01*
G02X250516Y55068I3465J-509D01*
G02X252171Y54652I-1J-3503D01*
G03X252361I95J176D01*
G02X254016Y55068I1656J-3087D01*
G02X255671Y54652I-1J-3503D01*
G03X255861I95J176D01*
G02X257516Y55068I1656J-3087D01*
G37*
G36*
G01X365287Y197050D02*
X371587D01*
G02Y173422I0J-11814D01*
G01X365287D01*
G02Y197050I0J11814D01*
G37*
G36*
G01X280826Y52152D02*
X284226D01*
G02Y49146I0J-1503D01*
G01X280826D01*
G02Y52152I0J1503D01*
G37*
G36*
G01X280828Y27438D02*
X284228D01*
G02Y24432I0J-1503D01*
G01X280828D01*
G02Y27438I0J1503D01*
G37*
G36*
G01X247177Y197836D02*
X253476D01*
G02Y172636I0J-12600D01*
G01X247177D01*
G02Y197836I0J12600D01*
G37*
G36*
G01X225727Y52152D02*
X229127D01*
G02Y49146I0J-1503D01*
G01X225727D01*
G02Y52152I0J1503D01*
G37*
G36*
G01X69964Y110535D02*
X65662Y105934D01*
G02X47255Y123148I-9203J8607D01*
G01X51557Y127748D01*
G02X69964Y110535I9203J-8607D01*
G37*
G36*
G01X634794Y592006D02*
X638694D01*
G02Y589002I0J-1502D01*
G01X634794D01*
G02Y592006I0J1502D01*
G37*
G36*
G01X646358Y591818D02*
X650258D01*
G02Y588814I0J-1502D01*
G01X646358D01*
G02Y591818I0J1502D01*
G37*
G36*
G01X635567Y673276D02*
X638967D01*
G02Y670272I0J-1502D01*
G01X635567D01*
G02Y673276I0J1502D01*
G37*
G36*
G01X670613Y43966D02*
X674013D01*
G02Y40962I0J-1502D01*
G01X670613D01*
G02Y43966I0J1502D01*
G37*
G36*
G01X857187Y343712D02*
X860587D01*
G02Y340708I0J-1502D01*
G01X857187D01*
G02Y343712I0J1502D01*
G37*
G36*
G01X860942Y332360D02*
X864342D01*
G02Y329356I0J-1502D01*
G01X860942D01*
G02Y332360I0J1502D01*
G37*
G36*
G01X1700136Y52152D02*
X1703536D01*
G02Y49146I0J-1503D01*
G01X1700136D01*
G02Y52152I0J1503D01*
G37*
G36*
G01X1755238Y27980D02*
X1758638D01*
G02Y24974I0J-1503D01*
G01X1755238D01*
G02Y27980I0J1503D01*
G37*
G36*
G01X1755235Y52152D02*
X1758635D01*
G02Y49146I0J-1503D01*
G01X1755235D01*
G02Y52152I0J1503D01*
G37*
G36*
G01X873175Y748970D02*
X869275D01*
G02Y751974I0J1502D01*
G01X873175D01*
G02Y748970I0J-1502D01*
G37*
G36*
G01X1705561Y643052D02*
X1701661D01*
G02Y646056I0J1502D01*
G01X1705561D01*
G02Y643052I0J-1502D01*
G37*
G36*
G01X937341Y309612D02*
X920139D01*
G02X937341I8601J12042D01*
G37*
G36*
G01X425469Y1593930D02*
X422069D01*
G02Y1596936I0J1503D01*
G01X425469D01*
G02Y1593930I0J-1503D01*
G37*
G36*
G01X413396Y1593094D02*
G02X412333Y1593534I0J1504D01*
G01X409929Y1595939D01*
G02X412054Y1598064I1063J1062D01*
G01X414459Y1595660D01*
G02X414899Y1594597I-1064J-1063D01*
G02X413396Y1593094I-1503J0D01*
G37*
G36*
G01X1113847Y1606056D02*
X1117247D01*
G02Y1603052I0J-1502D01*
G01X1113847D01*
G02Y1606056I0J1502D01*
G37*
G36*
G01X1125784Y1664208D02*
X1129184D01*
G02Y1661202I0J-1503D01*
G01X1125784D01*
G02Y1664208I0J1503D01*
G37*
G36*
G01X417365Y1629198D02*
X420765D01*
G02Y1626192I0J-1503D01*
G01X417365D01*
G02Y1629198I0J1503D01*
G37*
G36*
G01X648314Y569666D02*
X644414D01*
G02Y572672I0J1503D01*
G01X648314D01*
G02Y569666I0J-1503D01*
G37*
G36*
G01X816152Y1720920D02*
X901868D01*
G02X902752Y1720554I0J-1251D01*
G01X906384Y1716922D01*
G02X906750Y1716038I-885J-884D01*
G01Y1662730D01*
G03X906809Y1662588I200J0D01*
G01X925253Y1644144D01*
G03X925395Y1644085I142J141D01*
G01X1071615D01*
G02X1072499Y1643719I0J-1251D01*
G01X1104694Y1611524D01*
G02X1105060Y1610640I-885J-884D01*
G01Y1554972D01*
G02X1104267Y1553063I-2700J2D01*
G01X1102758Y1551554D01*
G02X1102734Y1551530I-1921J1897D01*
G01X1102705Y1551502D01*
X1102674Y1551429D01*
X1102672Y1551104D01*
G03X1102731Y1550962I200J0D01*
G01X1105128Y1548565D01*
G02X1105494Y1547681I-885J-884D01*
G01Y1546325D01*
G03X1105553Y1546183I200J0D01*
G01X1106834Y1544902D01*
G02X1107200Y1544018I-885J-884D01*
G01Y1528142D01*
G03X1107318Y1527960I200J0D01*
G02Y1525222I-618J-1369D01*
G03X1107200Y1525040I82J-182D01*
G01Y1512882D01*
G02X1106834Y1511998I-1251J0D01*
G01X1104042Y1509206D01*
G02X1103158Y1508840I-884J885D01*
G01X1082180D01*
G02X1081296Y1509206I0J1251D01*
G01X1079878Y1510624D01*
G03X1079731Y1510683I-142J-141D01*
G01X1079443Y1510676D01*
G03X1079300Y1510611I5J-200D01*
G02X1079205Y1510512I-1995J1819D01*
G01X1078341Y1509648D01*
G03X1078339Y1509646I140J-142D01*
G01X1078143Y1509442D01*
G02X1077714Y1509153I-898J870D01*
G01X1077169Y1508932D01*
G02X1076699Y1508840I-471J1158D01*
G01X943079D01*
G02X941170Y1509633I2J2700D01*
G01X939306Y1511497D01*
G03X939304Y1511499I-142J-140D01*
G01X939100Y1511695D01*
G02X938811Y1512124I870J898D01*
G01X938590Y1512669D01*
G02X938498Y1513139I1158J471D01*
G01Y1547259D01*
G02X939291Y1549168I2700J-2D01*
G01X939871Y1549749D01*
G03Y1550031I-142J141D01*
G01X939599Y1550303D01*
G02X939233Y1551187I885J884D01*
G01Y1598413D01*
G03X939174Y1598555I-200J0D01*
G01X923632Y1614097D01*
G03X923490Y1614156I-142J-141D01*
G01X903713D01*
G02X902829Y1614522I0J1251D01*
G01X892963Y1624388D01*
G03X892821Y1624447I-142J-141D01*
G01X770850D01*
G02X769966Y1624813I0J1251D01*
G01X766466Y1628313D01*
G02X766100Y1629197I885J884D01*
G01Y1656302D01*
G02X766893Y1658211I2700J-2D01*
G01X799393Y1690712D01*
G03X799410Y1690974I-142J141D01*
G01X799171Y1691289D01*
G03X798913Y1691342I-159J-121D01*
G02X791281Y1689340I-7632J13548D01*
G01X791280D01*
G02X806830Y1704890I0J15550D01*
G01Y1704889D01*
G02X804828Y1697257I-15550J0D01*
G01X804791Y1697191D01*
X804821Y1697045D01*
X805197Y1696760D01*
G03X805459Y1696778I121J160D01*
G01X808681Y1700000D01*
G03X808740Y1700142I-141J142D01*
G01Y1713508D01*
G02X809106Y1714392I1251J0D01*
G01X815268Y1720554D01*
G02X816152Y1720920I884J-885D01*
G37*
G36*
G01X1438232Y1664144D02*
G02X1438436Y1664348I204J0D01*
G01X1457722D01*
G02X1457926Y1664144I0J-204D01*
G01Y1658386D01*
Y1658186D01*
X1457740D01*
X1457330D01*
G03X1457154Y1658008I23J-199D01*
G01Y1656632D01*
G03X1457330Y1656454I199J21D01*
G01X1457726D01*
X1457926D01*
Y1656268D01*
Y1637396D01*
G02X1457722Y1637192I-204J0D01*
G01X1438436D01*
G02X1438232Y1637396I0J204D01*
G01Y1664144D01*
G37*
G36*
G01X791296Y1359655D02*
G02X790770Y1361500I2977J1846D01*
G02X791071Y1362919I3503J-2D01*
G03Y1363081I-183J81D01*
G02X790770Y1364500I3202J1421D01*
G02X797776I3503J0D01*
G02X797475Y1363081I-3503J2D01*
G03Y1362919I183J-81D01*
G02X797776Y1361500I-3202J-1421D01*
G02X797250Y1359655I-3503J1D01*
G03Y1359445I170J-105D01*
G02X797776Y1357600I-2977J-1846D01*
G02X797475Y1356181I-3503J2D01*
G03Y1356019I183J-81D01*
G02X797776Y1354600I-3202J-1421D01*
G02X790770I-3503J0D01*
G02X791071Y1356019I3503J-2D01*
G03Y1356181I-183J81D01*
G02X790770Y1357600I3202J1421D01*
G02X791296Y1359445I3503J-1D01*
G03Y1359655I-170J105D01*
G37*
G36*
G01X382478Y1657961D02*
G02X382681Y1658164I203J0D01*
G01X401967D01*
G02X402170Y1657961I0J-203D01*
G01Y1631213D01*
G02X401967Y1631010I-203J0D01*
G01X382681D01*
G02X382478Y1631213I0J203D01*
G01Y1657961D01*
G37*
G36*
G01X60921Y429304D02*
G02Y432308I0J1502D01*
G01X64821D01*
G02Y429304I0J-1502D01*
G01X60921D01*
G37*
G36*
G01X45960Y427304D02*
G02Y430308I0J1502D01*
G01X49360D01*
G02Y427304I0J-1502D01*
G01X45960D01*
G37*
G36*
G01X225731Y24974D02*
G02Y27980I0J1503D01*
G01X229131D01*
G02Y24974I0J-1503D01*
G01X225731D01*
G37*
G36*
G01X1700183Y25002D02*
G02Y28008I0J1503D01*
G01X1703583D01*
G02Y25002I0J-1503D01*
G01X1700183D01*
G37*
G36*
G01X551721Y80874D02*
G02Y77870I0J-1502D01*
G01X547821D01*
G02Y80874I0J1502D01*
G01X551721D01*
G37*
G36*
G01X512658Y45110D02*
G02Y48116I0J1503D01*
G01X516058D01*
G02Y45110I0J-1503D01*
G01X512658D01*
G37*
G36*
G01X541003Y69934D02*
G02Y72938I0J1502D01*
G01X544403D01*
G02Y69934I0J-1502D01*
G01X541003D01*
G37*
G36*
G01X509572Y863824D02*
G02Y866830I0J1503D01*
G01X513572D01*
G02Y863824I0J-1503D01*
G01X509572D01*
G37*
G36*
G01X1332812Y854880D02*
G02Y857886I0J1503D01*
G01X1336812D01*
G02Y854880I0J-1503D01*
G01X1332812D01*
G37*
G36*
G01X1659645Y1553264D02*
G02X1660705Y1553900I1060J-565D01*
G02X1661908Y1552698I1J-1202D01*
G02X1661747Y1552098I-1204J1D01*
G01X1660202Y1549425D01*
X1660200Y1549421D01*
G02X1659130Y1548768I-1070J550D01*
G02X1657928Y1549970I0J1202D01*
G01Y1549972D01*
G02X1658077Y1550551I1202J-1D01*
G01X1659643Y1553261D01*
X1659645Y1553264D01*
G37*
G36*
G01X1654920D02*
G02X1655980Y1553900I1060J-565D01*
G02X1657182Y1552698I0J-1202D01*
G02X1657022Y1552098I-1203J0D01*
G01X1655477Y1549425D01*
X1655475Y1549421D01*
G02X1654405Y1548768I-1070J550D01*
G02X1653202Y1549970I-1J1202D01*
G01Y1549972D01*
G02X1653352Y1550551I1203J-3D01*
G01X1654918Y1553261D01*
X1654920Y1553264D01*
G37*
G36*
G01X1645471D02*
G02X1646531Y1553900I1060J-565D01*
G02X1647734Y1552698I1J-1202D01*
G02X1647573Y1552098I-1204J1D01*
G01X1646028Y1549425D01*
X1646026Y1549421D01*
G02X1644956Y1548768I-1070J550D01*
G02X1643754Y1549970I0J1202D01*
G01Y1549972D01*
G02X1643903Y1550551I1202J-1D01*
G01X1645469Y1553261D01*
X1645471Y1553264D01*
G37*
G36*
G01X1650196D02*
G02X1651256Y1553900I1060J-565D01*
G02X1652458Y1552698I0J-1202D01*
G02X1652298Y1552098I-1203J0D01*
G01X1650753Y1549425D01*
X1650751Y1549421D01*
G02X1649681Y1548768I-1070J550D01*
G02X1648478Y1549970I-1J1202D01*
G01Y1549972D01*
G02X1648628Y1550551I1203J-3D01*
G01X1650194Y1553261D01*
X1650196Y1553264D01*
G37*
G36*
G01X1640747D02*
G02X1641807Y1553900I1060J-565D01*
G02X1643010Y1552698I1J-1202D01*
G02X1642849Y1552098I-1204J1D01*
G01X1641304Y1549425D01*
X1641302Y1549421D01*
G02X1640232Y1548768I-1070J550D01*
G02X1639030Y1549970I0J1202D01*
G01Y1549972D01*
G02X1639179Y1550551I1202J-1D01*
G01X1640745Y1553261D01*
X1640747Y1553264D01*
G37*
G36*
G01X1636023D02*
G02X1637083Y1553900I1060J-565D01*
G02X1638286Y1552698I1J-1202D01*
G02X1638125Y1552098I-1204J1D01*
G01X1636580Y1549425D01*
X1636578Y1549421D01*
G02X1635508Y1548768I-1070J550D01*
G02X1634306Y1549970I0J1202D01*
G01Y1549972D01*
G02X1634455Y1550551I1202J-1D01*
G01X1636021Y1553261D01*
X1636023Y1553264D01*
G37*
G36*
G01X1631298D02*
G02X1632358Y1553900I1060J-565D01*
G02X1633560Y1552698I0J-1202D01*
G02X1633400Y1552098I-1203J0D01*
G01X1631855Y1549425D01*
X1631853Y1549421D01*
G02X1630783Y1548768I-1070J550D01*
G02X1629580Y1549970I-1J1202D01*
G01Y1549972D01*
G02X1629730Y1550551I1203J-3D01*
G01X1631296Y1553261D01*
X1631298Y1553264D01*
G37*
G36*
G01X1626574D02*
G02X1627634Y1553900I1060J-565D01*
G02X1628836Y1552698I0J-1202D01*
G02X1628676Y1552098I-1203J0D01*
G01X1627131Y1549425D01*
X1627129Y1549421D01*
G02X1626059Y1548768I-1070J550D01*
G02X1624856Y1549970I-1J1202D01*
G01Y1549972D01*
G02X1625006Y1550551I1203J-3D01*
G01X1626572Y1553261D01*
X1626574Y1553264D01*
G37*
G36*
G01X1621849D02*
G02X1622909Y1553900I1060J-565D01*
G02X1624112Y1552698I1J-1202D01*
G02X1623951Y1552098I-1204J1D01*
G01X1622406Y1549425D01*
X1622404Y1549421D01*
G02X1621334Y1548768I-1070J550D01*
G02X1620132Y1549970I0J1202D01*
G01Y1549972D01*
G02X1620281Y1550551I1202J-1D01*
G01X1621847Y1553261D01*
X1621849Y1553264D01*
G37*
G36*
G01X1617125D02*
G02X1618185Y1553900I1060J-565D01*
G02X1619388Y1552698I1J-1202D01*
G02X1619227Y1552098I-1204J1D01*
G01X1617682Y1549425D01*
X1617680Y1549421D01*
G02X1616610Y1548768I-1070J550D01*
G02X1615408Y1549970I0J1202D01*
G01Y1549972D01*
G02X1615557Y1550551I1202J-1D01*
G01X1617123Y1553261D01*
X1617125Y1553264D01*
G37*
G36*
G01X1607676D02*
G02X1608736Y1553900I1060J-565D01*
G02X1609938Y1552698I0J-1202D01*
G02X1609778Y1552098I-1203J0D01*
G01X1608233Y1549425D01*
X1608231Y1549421D01*
G02X1607161Y1548768I-1070J550D01*
G02X1605958Y1549970I-1J1202D01*
G01Y1549972D01*
G02X1606108Y1550551I1203J-3D01*
G01X1607674Y1553261D01*
X1607676Y1553264D01*
G37*
G36*
G01X1612401D02*
G02X1613461Y1553900I1060J-565D01*
G02X1614664Y1552698I1J-1202D01*
G02X1614503Y1552098I-1204J1D01*
G01X1612958Y1549425D01*
X1612956Y1549421D01*
G02X1611886Y1548768I-1070J550D01*
G02X1610684Y1549970I0J1202D01*
G01Y1549972D01*
G02X1610833Y1550551I1202J-1D01*
G01X1612399Y1553261D01*
X1612401Y1553264D01*
G37*
G36*
G01X1598227D02*
G02X1599287Y1553900I1060J-565D01*
G02X1600490Y1552698I1J-1202D01*
G02X1600329Y1552098I-1204J1D01*
G01X1598784Y1549425D01*
X1598782Y1549421D01*
G02X1597712Y1548768I-1070J550D01*
G02X1596510Y1549970I0J1202D01*
G01Y1549972D01*
G02X1596659Y1550551I1202J-1D01*
G01X1598225Y1553261D01*
X1598227Y1553264D01*
G37*
G36*
G01X1602952D02*
G02X1604012Y1553900I1060J-565D01*
G02X1605214Y1552698I0J-1202D01*
G02X1605054Y1552098I-1203J0D01*
G01X1603509Y1549425D01*
X1603507Y1549421D01*
G02X1602437Y1548768I-1070J550D01*
G02X1601234Y1549970I-1J1202D01*
G01Y1549972D01*
G02X1601384Y1550551I1203J-3D01*
G01X1602950Y1553261D01*
X1602952Y1553264D01*
G37*
G36*
G01X1593503D02*
G02X1594563Y1553900I1060J-565D01*
G02X1595766Y1552698I1J-1202D01*
G02X1595605Y1552098I-1204J1D01*
G01X1594060Y1549425D01*
X1594058Y1549421D01*
G02X1592988Y1548768I-1070J550D01*
G02X1591786Y1549970I0J1202D01*
G01Y1549972D01*
G02X1591935Y1550551I1202J-1D01*
G01X1593501Y1553261D01*
X1593503Y1553264D01*
G37*
G36*
G01X1588779D02*
G02X1589839Y1553900I1060J-565D01*
G02X1591042Y1552698I1J-1202D01*
G02X1590881Y1552098I-1204J1D01*
G01X1589336Y1549425D01*
X1589334Y1549421D01*
G02X1588264Y1548768I-1070J550D01*
G02X1587062Y1549970I0J1202D01*
G01Y1549972D01*
G02X1587211Y1550551I1202J-1D01*
G01X1588777Y1553261D01*
X1588779Y1553264D01*
G37*
G36*
G01X1526858D02*
G02X1527918Y1553900I1060J-565D01*
G02X1529120Y1552698I0J-1202D01*
G02X1528960Y1552098I-1203J0D01*
G01X1527415Y1549425D01*
X1527413Y1549421D01*
G02X1526343Y1548768I-1070J550D01*
G02X1525140Y1549970I-1J1202D01*
G01Y1549972D01*
G02X1525290Y1550551I1203J-3D01*
G01X1526856Y1553261D01*
X1526858Y1553264D01*
G37*
G36*
G01X1531583D02*
G02X1532643Y1553900I1060J-565D01*
G02X1533846Y1552698I1J-1202D01*
G02X1533685Y1552098I-1204J1D01*
G01X1532140Y1549425D01*
X1532138Y1549421D01*
G02X1531068Y1548768I-1070J550D01*
G02X1529866Y1549970I0J1202D01*
G01Y1549972D01*
G02X1530015Y1550551I1202J-1D01*
G01X1531581Y1553261D01*
X1531583Y1553264D01*
G37*
G36*
G01X1517409D02*
G02X1518469Y1553900I1060J-565D01*
G02X1519672Y1552698I1J-1202D01*
G02X1519511Y1552098I-1204J1D01*
G01X1517966Y1549425D01*
X1517964Y1549421D01*
G02X1516894Y1548768I-1070J550D01*
G02X1515692Y1549970I0J1202D01*
G01Y1549972D01*
G02X1515841Y1550551I1202J-1D01*
G01X1517407Y1553261D01*
X1517409Y1553264D01*
G37*
G36*
G01X1512685D02*
G02X1513745Y1553900I1060J-565D01*
G02X1514948Y1552698I1J-1202D01*
G02X1514787Y1552098I-1204J1D01*
G01X1513242Y1549425D01*
X1513240Y1549421D01*
G02X1512170Y1548768I-1070J550D01*
G02X1510968Y1549970I0J1202D01*
G01Y1549972D01*
G02X1511117Y1550551I1202J-1D01*
G01X1512683Y1553261D01*
X1512685Y1553264D01*
G37*
G36*
G01X1522134D02*
G02X1523194Y1553900I1060J-565D01*
G02X1524396Y1552698I0J-1202D01*
G02X1524236Y1552098I-1203J0D01*
G01X1522691Y1549425D01*
X1522689Y1549421D01*
G02X1521619Y1548768I-1070J550D01*
G02X1520416Y1549970I-1J1202D01*
G01Y1549972D01*
G02X1520566Y1550551I1203J-3D01*
G01X1522132Y1553261D01*
X1522134Y1553264D01*
G37*
G36*
G01X1498512D02*
G02X1499572Y1553900I1060J-565D01*
G02X1500774Y1552698I0J-1202D01*
G02X1500614Y1552098I-1203J0D01*
G01X1499069Y1549425D01*
X1499067Y1549421D01*
G02X1497997Y1548768I-1070J550D01*
G02X1496794Y1549970I-1J1202D01*
G01Y1549972D01*
G02X1496944Y1550551I1203J-3D01*
G01X1498510Y1553261D01*
X1498512Y1553264D01*
G37*
G36*
G01X1507961D02*
G02X1509021Y1553900I1060J-565D01*
G02X1510224Y1552698I1J-1202D01*
G02X1510063Y1552098I-1204J1D01*
G01X1508518Y1549425D01*
X1508516Y1549421D01*
G02X1507446Y1548768I-1070J550D01*
G02X1506244Y1549970I0J1202D01*
G01Y1549972D01*
G02X1506393Y1550551I1202J-1D01*
G01X1507959Y1553261D01*
X1507961Y1553264D01*
G37*
G36*
G01X1503236D02*
G02X1504296Y1553900I1060J-565D01*
G02X1505498Y1552698I0J-1202D01*
G02X1505338Y1552098I-1203J0D01*
G01X1503793Y1549425D01*
X1503791Y1549421D01*
G02X1502721Y1548768I-1070J550D01*
G02X1501518Y1549970I-1J1202D01*
G01Y1549972D01*
G02X1501668Y1550551I1203J-3D01*
G01X1503234Y1553261D01*
X1503236Y1553264D01*
G37*
G36*
G01X1493787D02*
G02X1494847Y1553900I1060J-565D01*
G02X1496050Y1552698I1J-1202D01*
G02X1495889Y1552098I-1204J1D01*
G01X1494344Y1549425D01*
X1494342Y1549421D01*
G02X1493272Y1548768I-1070J550D01*
G02X1492070Y1549970I0J1202D01*
G01Y1549972D01*
G02X1492219Y1550551I1202J-1D01*
G01X1493785Y1553261D01*
X1493787Y1553264D01*
G37*
G36*
G01X1484339D02*
G02X1485399Y1553900I1060J-565D01*
G02X1486602Y1552698I1J-1202D01*
G02X1486441Y1552098I-1204J1D01*
G01X1484896Y1549425D01*
X1484894Y1549421D01*
G02X1483824Y1548768I-1070J550D01*
G02X1482622Y1549970I0J1202D01*
G01Y1549972D01*
G02X1482771Y1550551I1202J-1D01*
G01X1484337Y1553261D01*
X1484339Y1553264D01*
G37*
G36*
G01X1489063D02*
G02X1490123Y1553900I1060J-565D01*
G02X1491326Y1552698I1J-1202D01*
G02X1491165Y1552098I-1204J1D01*
G01X1489620Y1549425D01*
X1489618Y1549421D01*
G02X1488548Y1548768I-1070J550D01*
G02X1487346Y1549970I0J1202D01*
G01Y1549972D01*
G02X1487495Y1550551I1202J-1D01*
G01X1489061Y1553261D01*
X1489063Y1553264D01*
G37*
G36*
G01X1479614D02*
G02X1480674Y1553900I1060J-565D01*
G02X1481876Y1552698I0J-1202D01*
G02X1481716Y1552098I-1203J0D01*
G01X1480171Y1549425D01*
X1480169Y1549421D01*
G02X1479099Y1548768I-1070J550D01*
G02X1477896Y1549970I-1J1202D01*
G01Y1549972D01*
G02X1478046Y1550551I1203J-3D01*
G01X1479612Y1553261D01*
X1479614Y1553264D01*
G37*
G36*
G01X1470165D02*
G02X1471225Y1553900I1060J-565D01*
G02X1472428Y1552698I1J-1202D01*
G02X1472267Y1552098I-1204J1D01*
G01X1470722Y1549425D01*
X1470720Y1549421D01*
G02X1469650Y1548768I-1070J550D01*
G02X1468448Y1549970I0J1202D01*
G01Y1549972D01*
G02X1468597Y1550551I1202J-1D01*
G01X1470163Y1553261D01*
X1470165Y1553264D01*
G37*
G36*
G01X1474890D02*
G02X1475950Y1553900I1060J-565D01*
G02X1477152Y1552698I0J-1202D01*
G02X1476992Y1552098I-1203J0D01*
G01X1475447Y1549425D01*
X1475445Y1549421D01*
G02X1474375Y1548768I-1070J550D01*
G02X1473172Y1549970I-1J1202D01*
G01Y1549972D01*
G02X1473322Y1550551I1203J-3D01*
G01X1474888Y1553261D01*
X1474890Y1553264D01*
G37*
G36*
G01X1465441D02*
G02X1466501Y1553900I1060J-565D01*
G02X1467704Y1552698I1J-1202D01*
G02X1467543Y1552098I-1204J1D01*
G01X1465998Y1549425D01*
X1465996Y1549421D01*
G02X1464926Y1548768I-1070J550D01*
G02X1463724Y1549970I0J1202D01*
G01Y1549972D01*
G02X1463873Y1550551I1202J-1D01*
G01X1465439Y1553261D01*
X1465441Y1553264D01*
G37*
G36*
G01X1460717D02*
G02X1461777Y1553900I1060J-565D01*
G02X1462980Y1552698I1J-1202D01*
G02X1462819Y1552098I-1204J1D01*
G01X1461274Y1549425D01*
X1461272Y1549421D01*
G02X1460202Y1548768I-1070J550D01*
G02X1459000Y1549970I0J1202D01*
G01Y1549972D01*
G02X1459149Y1550551I1202J-1D01*
G01X1460715Y1553261D01*
X1460717Y1553264D01*
G37*
G36*
G01X372126Y1215958D02*
G02Y1212952I0J-1503D01*
G01X368726D01*
G02Y1215958I0J1503D01*
G01X372126D01*
G37*
G36*
G01X613975Y1520264D02*
G02X615035Y1520900I1060J-565D01*
G02X616238Y1519698I1J-1202D01*
G02X616077Y1519098I-1204J1D01*
G01X614532Y1516425D01*
X614530Y1516421D01*
G02X613460Y1515768I-1070J550D01*
G02X612258Y1516970I0J1202D01*
G01Y1516972D01*
G02X612407Y1517551I1202J-1D01*
G01X613973Y1520261D01*
X613975Y1520264D01*
G37*
G36*
G01X642322D02*
G02X643382Y1520900I1060J-565D01*
G02X644584Y1519698I0J-1202D01*
G02X644424Y1519098I-1203J0D01*
G01X642879Y1516425D01*
X642877Y1516421D01*
G02X641807Y1515768I-1070J550D01*
G02X640604Y1516970I-1J1202D01*
G01Y1516972D01*
G02X640754Y1517551I1203J-3D01*
G01X642320Y1520261D01*
X642322Y1520264D01*
G37*
G36*
G01X609251D02*
G02X610311Y1520900I1060J-565D01*
G02X611514Y1519698I1J-1202D01*
G02X611353Y1519098I-1204J1D01*
G01X609808Y1516425D01*
X609806Y1516421D01*
G02X608736Y1515768I-1070J550D01*
G02X607534Y1516970I0J1202D01*
G01Y1516972D01*
G02X607683Y1517551I1202J-1D01*
G01X609249Y1520261D01*
X609251Y1520264D01*
G37*
G36*
G01X637597D02*
G02X638657Y1520900I1060J-565D01*
G02X639860Y1519698I1J-1202D01*
G02X639699Y1519098I-1204J1D01*
G01X638154Y1516425D01*
X638152Y1516421D01*
G02X637082Y1515768I-1070J550D01*
G02X635880Y1516970I0J1202D01*
G01Y1516972D01*
G02X636029Y1517551I1202J-1D01*
G01X637595Y1520261D01*
X637597Y1520264D01*
G37*
G36*
G01X595078D02*
G02X596138Y1520900I1060J-565D01*
G02X597340Y1519698I0J-1202D01*
G02X597180Y1519098I-1203J0D01*
G01X595635Y1516425D01*
X595633Y1516421D01*
G02X594563Y1515768I-1070J550D01*
G02X593360Y1516970I-1J1202D01*
G01Y1516972D01*
G02X593510Y1517551I1203J-3D01*
G01X595076Y1520261D01*
X595078Y1520264D01*
G37*
G36*
G01X647046D02*
G02X648106Y1520900I1060J-565D01*
G02X649308Y1519698I0J-1202D01*
G02X649148Y1519098I-1203J0D01*
G01X647603Y1516425D01*
X647601Y1516421D01*
G02X646531Y1515768I-1070J550D01*
G02X645328Y1516970I-1J1202D01*
G01Y1516972D01*
G02X645478Y1517551I1203J-3D01*
G01X647044Y1520261D01*
X647046Y1520264D01*
G37*
G36*
G01X590353D02*
G02X591413Y1520900I1060J-565D01*
G02X592616Y1519698I1J-1202D01*
G02X592455Y1519098I-1204J1D01*
G01X590910Y1516425D01*
X590908Y1516421D01*
G02X589838Y1515768I-1070J550D01*
G02X588636Y1516970I0J1202D01*
G01Y1516972D01*
G02X588785Y1517551I1202J-1D01*
G01X590351Y1520261D01*
X590353Y1520264D01*
G37*
G36*
G01X604527D02*
G02X605587Y1520900I1060J-565D01*
G02X606790Y1519698I1J-1202D01*
G02X606629Y1519098I-1204J1D01*
G01X605084Y1516425D01*
X605082Y1516421D01*
G02X604012Y1515768I-1070J550D01*
G02X602810Y1516970I0J1202D01*
G01Y1516972D01*
G02X602959Y1517551I1202J-1D01*
G01X604525Y1520261D01*
X604527Y1520264D01*
G37*
G36*
G01X628149D02*
G02X629209Y1520900I1060J-565D01*
G02X630412Y1519698I1J-1202D01*
G02X630251Y1519098I-1204J1D01*
G01X628706Y1516425D01*
X628704Y1516421D01*
G02X627634Y1515768I-1070J550D01*
G02X626432Y1516970I0J1202D01*
G01Y1516972D01*
G02X626581Y1517551I1202J-1D01*
G01X628147Y1520261D01*
X628149Y1520264D01*
G37*
G36*
G01X618700D02*
G02X619760Y1520900I1060J-565D01*
G02X620962Y1519698I0J-1202D01*
G02X620802Y1519098I-1203J0D01*
G01X619257Y1516425D01*
X619255Y1516421D01*
G02X618185Y1515768I-1070J550D01*
G02X616982Y1516970I-1J1202D01*
G01Y1516972D01*
G02X617132Y1517551I1203J-3D01*
G01X618698Y1520261D01*
X618700Y1520264D01*
G37*
G36*
G01X599802D02*
G02X600862Y1520900I1060J-565D01*
G02X602064Y1519698I0J-1202D01*
G02X601904Y1519098I-1203J0D01*
G01X600359Y1516425D01*
X600357Y1516421D01*
G02X599287Y1515768I-1070J550D01*
G02X598084Y1516970I-1J1202D01*
G01Y1516972D01*
G02X598234Y1517551I1203J-3D01*
G01X599800Y1520261D01*
X599802Y1520264D01*
G37*
G36*
G01X623424D02*
G02X624484Y1520900I1060J-565D01*
G02X625686Y1519698I0J-1202D01*
G02X625526Y1519098I-1203J0D01*
G01X623981Y1516425D01*
X623979Y1516421D01*
G02X622909Y1515768I-1070J550D01*
G02X621706Y1516970I-1J1202D01*
G01Y1516972D01*
G02X621856Y1517551I1203J-3D01*
G01X623422Y1520261D01*
X623424Y1520264D01*
G37*
G36*
G01X580905D02*
G02X581965Y1520900I1060J-565D01*
G02X583168Y1519698I1J-1202D01*
G02X583007Y1519098I-1204J1D01*
G01X581462Y1516425D01*
X581460Y1516421D01*
G02X580390Y1515768I-1070J550D01*
G02X579188Y1516970I0J1202D01*
G01Y1516972D01*
G02X579337Y1517551I1202J-1D01*
G01X580903Y1520261D01*
X580905Y1520264D01*
G37*
G36*
G01X632873D02*
G02X633933Y1520900I1060J-565D01*
G02X635136Y1519698I1J-1202D01*
G02X634975Y1519098I-1204J1D01*
G01X633430Y1516425D01*
X633428Y1516421D01*
G02X632358Y1515768I-1070J550D01*
G02X631156Y1516970I0J1202D01*
G01Y1516972D01*
G02X631305Y1517551I1202J-1D01*
G01X632871Y1520261D01*
X632873Y1520264D01*
G37*
G36*
G01X585629D02*
G02X586689Y1520900I1060J-565D01*
G02X587892Y1519698I1J-1202D01*
G02X587731Y1519098I-1204J1D01*
G01X586186Y1516425D01*
X586184Y1516421D01*
G02X585114Y1515768I-1070J550D01*
G02X583912Y1516970I0J1202D01*
G01Y1516972D01*
G02X584061Y1517551I1202J-1D01*
G01X585627Y1520261D01*
X585629Y1520264D01*
G37*
G36*
G01X481189D02*
G02X482249Y1520900I1060J-565D01*
G02X483452Y1519698I1J-1202D01*
G02X483291Y1519098I-1204J1D01*
G01X481746Y1516425D01*
X481744Y1516421D01*
G02X480674Y1515768I-1070J550D01*
G02X479472Y1516970I0J1202D01*
G01Y1516972D01*
G02X479621Y1517551I1202J-1D01*
G01X481187Y1520261D01*
X481189Y1520264D01*
G37*
G36*
G01X518984D02*
G02X520044Y1520900I1060J-565D01*
G02X521246Y1519698I0J-1202D01*
G02X521086Y1519098I-1203J0D01*
G01X519541Y1516425D01*
X519539Y1516421D01*
G02X518469Y1515768I-1070J550D01*
G02X517266Y1516970I-1J1202D01*
G01Y1516972D01*
G02X517416Y1517551I1203J-3D01*
G01X518982Y1520261D01*
X518984Y1520264D01*
G37*
G36*
G01X471740D02*
G02X472800Y1520900I1060J-565D01*
G02X474002Y1519698I0J-1202D01*
G02X473842Y1519098I-1203J0D01*
G01X472297Y1516425D01*
X472295Y1516421D01*
G02X471225Y1515768I-1070J550D01*
G02X470022Y1516970I-1J1202D01*
G01Y1516972D01*
G02X470172Y1517551I1203J-3D01*
G01X471738Y1520261D01*
X471740Y1520264D01*
G37*
G36*
G01X514260D02*
G02X515320Y1520900I1060J-565D01*
G02X516522Y1519698I0J-1202D01*
G02X516362Y1519098I-1203J0D01*
G01X514817Y1516425D01*
X514815Y1516421D01*
G02X513745Y1515768I-1070J550D01*
G02X512542Y1516970I-1J1202D01*
G01Y1516972D01*
G02X512692Y1517551I1203J-3D01*
G01X514258Y1520261D01*
X514260Y1520264D01*
G37*
G36*
G01X476465D02*
G02X477525Y1520900I1060J-565D01*
G02X478728Y1519698I1J-1202D01*
G02X478567Y1519098I-1204J1D01*
G01X477022Y1516425D01*
X477020Y1516421D01*
G02X475950Y1515768I-1070J550D01*
G02X474748Y1516970I0J1202D01*
G01Y1516972D01*
G02X474897Y1517551I1202J-1D01*
G01X476463Y1520261D01*
X476465Y1520264D01*
G37*
G36*
G01X1395471Y1553264D02*
G02X1396531Y1553900I1060J-565D01*
G02X1397734Y1552698I1J-1202D01*
G02X1397573Y1552098I-1204J1D01*
G01X1396028Y1549425D01*
X1396026Y1549421D01*
G02X1394956Y1548768I-1070J550D01*
G02X1393754Y1549970I0J1202D01*
G01Y1549972D01*
G02X1393903Y1550551I1202J-1D01*
G01X1395469Y1553261D01*
X1395471Y1553264D01*
G37*
G36*
G01X1390747D02*
G02X1391807Y1553900I1060J-565D01*
G02X1393010Y1552698I1J-1202D01*
G02X1392849Y1552098I-1204J1D01*
G01X1391304Y1549425D01*
X1391302Y1549421D01*
G02X1390232Y1548768I-1070J550D01*
G02X1389030Y1549970I0J1202D01*
G01Y1549972D01*
G02X1389179Y1550551I1202J-1D01*
G01X1390745Y1553261D01*
X1390747Y1553264D01*
G37*
G36*
G01X1386022D02*
G02X1387082Y1553900I1060J-565D01*
G02X1388284Y1552698I0J-1202D01*
G02X1388124Y1552098I-1203J0D01*
G01X1386579Y1549425D01*
X1386577Y1549421D01*
G02X1385507Y1548768I-1070J550D01*
G02X1384304Y1549970I-1J1202D01*
G01Y1549972D01*
G02X1384454Y1550551I1203J-3D01*
G01X1386020Y1553261D01*
X1386022Y1553264D01*
G37*
G36*
G01X1376573D02*
G02X1377633Y1553900I1060J-565D01*
G02X1378836Y1552698I1J-1202D01*
G02X1378675Y1552098I-1204J1D01*
G01X1377130Y1549425D01*
X1377128Y1549421D01*
G02X1376058Y1548768I-1070J550D01*
G02X1374856Y1549970I0J1202D01*
G01Y1549972D01*
G02X1375005Y1550551I1202J-1D01*
G01X1376571Y1553261D01*
X1376573Y1553264D01*
G37*
G36*
G01X1381298D02*
G02X1382358Y1553900I1060J-565D01*
G02X1383560Y1552698I0J-1202D01*
G02X1383400Y1552098I-1203J0D01*
G01X1381855Y1549425D01*
X1381853Y1549421D01*
G02X1380783Y1548768I-1070J550D01*
G02X1379580Y1549970I-1J1202D01*
G01Y1549972D01*
G02X1379730Y1550551I1203J-3D01*
G01X1381296Y1553261D01*
X1381298Y1553264D01*
G37*
G36*
G01X504811Y1520264D02*
G02X505871Y1520900I1060J-565D01*
G02X507074Y1519698I1J-1202D01*
G02X506913Y1519098I-1204J1D01*
G01X505368Y1516425D01*
X505366Y1516421D01*
G02X504296Y1515768I-1070J550D01*
G02X503094Y1516970I0J1202D01*
G01Y1516972D01*
G02X503243Y1517551I1202J-1D01*
G01X504809Y1520261D01*
X504811Y1520264D01*
G37*
G36*
G01X495362D02*
G02X496422Y1520900I1060J-565D01*
G02X497624Y1519698I0J-1202D01*
G02X497464Y1519098I-1203J0D01*
G01X495919Y1516425D01*
X495917Y1516421D01*
G02X494847Y1515768I-1070J550D01*
G02X493644Y1516970I-1J1202D01*
G01Y1516972D01*
G02X493794Y1517551I1203J-3D01*
G01X495360Y1520261D01*
X495362Y1520264D01*
G37*
G36*
G01X523709D02*
G02X524769Y1520900I1060J-565D01*
G02X525972Y1519698I1J-1202D01*
G02X525811Y1519098I-1204J1D01*
G01X524266Y1516425D01*
X524264Y1516421D01*
G02X523194Y1515768I-1070J550D01*
G02X521992Y1516970I0J1202D01*
G01Y1516972D01*
G02X522141Y1517551I1202J-1D01*
G01X523707Y1520261D01*
X523709Y1520264D01*
G37*
G36*
G01X452843D02*
G02X453903Y1520900I1060J-565D01*
G02X455106Y1519698I1J-1202D01*
G02X454945Y1519098I-1204J1D01*
G01X453400Y1516425D01*
X453398Y1516421D01*
G02X452328Y1515768I-1070J550D01*
G02X451126Y1516970I0J1202D01*
G01Y1516972D01*
G02X451275Y1517551I1202J-1D01*
G01X452841Y1520261D01*
X452843Y1520264D01*
G37*
G36*
G01X457567D02*
G02X458627Y1520900I1060J-565D01*
G02X459830Y1519698I1J-1202D01*
G02X459669Y1519098I-1204J1D01*
G01X458124Y1516425D01*
X458122Y1516421D01*
G02X457052Y1515768I-1070J550D01*
G02X455850Y1516970I0J1202D01*
G01Y1516972D01*
G02X455999Y1517551I1202J-1D01*
G01X457565Y1520261D01*
X457567Y1520264D01*
G37*
G36*
G01X691276Y1453610D02*
G02Y1456614I0J1502D01*
G01X694676D01*
G02Y1453610I0J-1502D01*
G01X691276D01*
G37*
G36*
G01X1338778Y1553264D02*
G02X1339838Y1553900I1060J-565D01*
G02X1341040Y1552698I0J-1202D01*
G02X1340880Y1552098I-1203J0D01*
G01X1339335Y1549425D01*
X1339333Y1549421D01*
G02X1338263Y1548768I-1070J550D01*
G02X1337060Y1549970I-1J1202D01*
G01Y1549972D01*
G02X1337210Y1550551I1203J-3D01*
G01X1338776Y1553261D01*
X1338778Y1553264D01*
G37*
G36*
G01X467016Y1520264D02*
G02X468076Y1520900I1060J-565D01*
G02X469278Y1519698I0J-1202D01*
G02X469118Y1519098I-1203J0D01*
G01X467573Y1516425D01*
X467571Y1516421D01*
G02X466501Y1515768I-1070J550D01*
G02X465298Y1516970I-1J1202D01*
G01Y1516972D01*
G02X465448Y1517551I1203J-3D01*
G01X467014Y1520261D01*
X467016Y1520264D01*
G37*
G36*
G01X485913D02*
G02X486973Y1520900I1060J-565D01*
G02X488176Y1519698I1J-1202D01*
G02X488015Y1519098I-1204J1D01*
G01X486470Y1516425D01*
X486468Y1516421D01*
G02X485398Y1515768I-1070J550D01*
G02X484196Y1516970I0J1202D01*
G01Y1516972D01*
G02X484345Y1517551I1202J-1D01*
G01X485911Y1520261D01*
X485913Y1520264D01*
G37*
G36*
G01X382873D02*
G02X383933Y1520900I1060J-565D01*
G02X385136Y1519698I1J-1202D01*
G02X384975Y1519098I-1204J1D01*
G01X383430Y1516425D01*
X383428Y1516421D01*
G02X382358Y1515768I-1070J550D01*
G02X381156Y1516970I0J1202D01*
G01Y1516972D01*
G02X381305Y1517551I1202J-1D01*
G01X382871Y1520261D01*
X382873Y1520264D01*
G37*
G36*
G01X340354D02*
G02X341414Y1520900I1060J-565D01*
G02X342616Y1519698I0J-1202D01*
G02X342456Y1519098I-1203J0D01*
G01X340911Y1516425D01*
X340909Y1516421D01*
G02X339839Y1515768I-1070J550D01*
G02X338636Y1516970I-1J1202D01*
G01Y1516972D01*
G02X338786Y1517551I1203J-3D01*
G01X340352Y1520261D01*
X340354Y1520264D01*
G37*
G36*
G01X387598D02*
G02X388658Y1520900I1060J-565D01*
G02X389860Y1519698I0J-1202D01*
G02X389700Y1519098I-1203J0D01*
G01X388155Y1516425D01*
X388153Y1516421D01*
G02X387083Y1515768I-1070J550D01*
G02X385880Y1516970I-1J1202D01*
G01Y1516972D01*
G02X386030Y1517551I1203J-3D01*
G01X387596Y1520261D01*
X387598Y1520264D01*
G37*
G36*
G01X462291D02*
G02X463351Y1520900I1060J-565D01*
G02X464554Y1519698I1J-1202D01*
G02X464393Y1519098I-1204J1D01*
G01X462848Y1516425D01*
X462846Y1516421D01*
G02X461776Y1515768I-1070J550D01*
G02X460574Y1516970I0J1202D01*
G01Y1516972D01*
G02X460723Y1517551I1202J-1D01*
G01X462289Y1520261D01*
X462291Y1520264D01*
G37*
G36*
G01X490638D02*
G02X491698Y1520900I1060J-565D01*
G02X492900Y1519698I0J-1202D01*
G02X492740Y1519098I-1203J0D01*
G01X491195Y1516425D01*
X491193Y1516421D01*
G02X490123Y1515768I-1070J550D01*
G02X488920Y1516970I-1J1202D01*
G01Y1516972D01*
G02X489070Y1517551I1203J-3D01*
G01X490636Y1520261D01*
X490638Y1520264D01*
G37*
G36*
G01X1371849Y1553264D02*
G02X1372909Y1553900I1060J-565D01*
G02X1374112Y1552698I1J-1202D01*
G02X1373951Y1552098I-1204J1D01*
G01X1372406Y1549425D01*
X1372404Y1549421D01*
G02X1371334Y1548768I-1070J550D01*
G02X1370132Y1549970I0J1202D01*
G01Y1549972D01*
G02X1370281Y1550551I1202J-1D01*
G01X1371847Y1553261D01*
X1371849Y1553264D01*
G37*
G36*
G01X1362400D02*
G02X1363460Y1553900I1060J-565D01*
G02X1364662Y1552698I0J-1202D01*
G02X1364502Y1552098I-1203J0D01*
G01X1362957Y1549425D01*
X1362955Y1549421D01*
G02X1361885Y1548768I-1070J550D01*
G02X1360682Y1549970I-1J1202D01*
G01Y1549972D01*
G02X1360832Y1550551I1203J-3D01*
G01X1362398Y1553261D01*
X1362400Y1553264D01*
G37*
G36*
G01X1367124D02*
G02X1368184Y1553900I1060J-565D01*
G02X1369386Y1552698I0J-1202D01*
G02X1369226Y1552098I-1203J0D01*
G01X1367681Y1549425D01*
X1367679Y1549421D01*
G02X1366609Y1548768I-1070J550D01*
G02X1365406Y1549970I-1J1202D01*
G01Y1549972D01*
G02X1365556Y1550551I1203J-3D01*
G01X1367122Y1553261D01*
X1367124Y1553264D01*
G37*
G36*
G01X1357676D02*
G02X1358736Y1553900I1060J-565D01*
G02X1359938Y1552698I0J-1202D01*
G02X1359778Y1552098I-1203J0D01*
G01X1358233Y1549425D01*
X1358231Y1549421D01*
G02X1357161Y1548768I-1070J550D01*
G02X1355958Y1549970I-1J1202D01*
G01Y1549972D01*
G02X1356108Y1550551I1203J-3D01*
G01X1357674Y1553261D01*
X1357676Y1553264D01*
G37*
G36*
G01X1343502D02*
G02X1344562Y1553900I1060J-565D01*
G02X1345764Y1552698I0J-1202D01*
G02X1345604Y1552098I-1203J0D01*
G01X1344059Y1549425D01*
X1344057Y1549421D01*
G02X1342987Y1548768I-1070J550D01*
G02X1341784Y1549970I-1J1202D01*
G01Y1549972D01*
G02X1341934Y1550551I1203J-3D01*
G01X1343500Y1553261D01*
X1343502Y1553264D01*
G37*
G36*
G01X1348227D02*
G02X1349287Y1553900I1060J-565D01*
G02X1350490Y1552698I1J-1202D01*
G02X1350329Y1552098I-1204J1D01*
G01X1348784Y1549425D01*
X1348782Y1549421D01*
G02X1347712Y1548768I-1070J550D01*
G02X1346510Y1549970I0J1202D01*
G01Y1549972D01*
G02X1346659Y1550551I1202J-1D01*
G01X1348225Y1553261D01*
X1348227Y1553264D01*
G37*
G36*
G01X1352951D02*
G02X1354011Y1553900I1060J-565D01*
G02X1355214Y1552698I1J-1202D01*
G02X1355053Y1552098I-1204J1D01*
G01X1353508Y1549425D01*
X1353506Y1549421D01*
G02X1352436Y1548768I-1070J550D01*
G02X1351234Y1549970I0J1202D01*
G01Y1549972D01*
G02X1351383Y1550551I1202J-1D01*
G01X1352949Y1553261D01*
X1352951Y1553264D01*
G37*
G36*
G01X188670Y1520264D02*
G02X189730Y1520900I1060J-565D01*
G02X190932Y1519698I0J-1202D01*
G02X190772Y1519098I-1203J0D01*
G01X189227Y1516425D01*
X189225Y1516421D01*
G02X188155Y1515768I-1070J550D01*
G02X186952Y1516970I-1J1202D01*
G01Y1516972D01*
G02X187102Y1517551I1203J-3D01*
G01X188668Y1520261D01*
X188670Y1520264D01*
G37*
G36*
G01X217016D02*
G02X218076Y1520900I1060J-565D01*
G02X219278Y1519698I0J-1202D01*
G02X219118Y1519098I-1203J0D01*
G01X217573Y1516425D01*
X217571Y1516421D01*
G02X216501Y1515768I-1070J550D01*
G02X215298Y1516970I-1J1202D01*
G01Y1516972D01*
G02X215448Y1517551I1203J-3D01*
G01X217014Y1520261D01*
X217016Y1520264D01*
G37*
G36*
G01X1531583Y1566902D02*
G02X1532643Y1567538I1060J-565D01*
G02X1533846Y1566336I1J-1202D01*
G02X1533685Y1565736I-1204J1D01*
G01X1532140Y1563063D01*
X1532138Y1563059D01*
G02X1531068Y1562406I-1070J550D01*
G02X1529866Y1563608I0J1202D01*
G01Y1563610D01*
G02X1530015Y1564189I1202J-1D01*
G01X1531581Y1566899D01*
X1531583Y1566902D01*
G37*
G36*
G01X1526858D02*
G02X1527918Y1567538I1060J-565D01*
G02X1529120Y1566336I0J-1202D01*
G02X1528960Y1565736I-1203J0D01*
G01X1527415Y1563063D01*
X1527413Y1563059D01*
G02X1526343Y1562406I-1070J550D01*
G02X1525140Y1563608I-1J1202D01*
G01Y1563610D01*
G02X1525290Y1564189I1203J-3D01*
G01X1526856Y1566899D01*
X1526858Y1566902D01*
G37*
G36*
G01X1522134D02*
G02X1523194Y1567538I1060J-565D01*
G02X1524396Y1566336I0J-1202D01*
G02X1524236Y1565736I-1203J0D01*
G01X1522691Y1563063D01*
X1522689Y1563059D01*
G02X1521619Y1562406I-1070J550D01*
G02X1520416Y1563608I-1J1202D01*
G01Y1563610D01*
G02X1520566Y1564189I1203J-3D01*
G01X1522132Y1566899D01*
X1522134Y1566902D01*
G37*
G36*
G01X1517409D02*
G02X1518469Y1567538I1060J-565D01*
G02X1519672Y1566336I1J-1202D01*
G02X1519511Y1565736I-1204J1D01*
G01X1517966Y1563063D01*
X1517964Y1563059D01*
G02X1516894Y1562406I-1070J550D01*
G02X1515692Y1563608I0J1202D01*
G01Y1563610D01*
G02X1515841Y1564189I1202J-1D01*
G01X1517407Y1566899D01*
X1517409Y1566902D01*
G37*
G36*
G01X1512685D02*
G02X1513745Y1567538I1060J-565D01*
G02X1514948Y1566336I1J-1202D01*
G02X1514787Y1565736I-1204J1D01*
G01X1513242Y1563063D01*
X1513240Y1563059D01*
G02X1512170Y1562406I-1070J550D01*
G02X1510968Y1563608I0J1202D01*
G01Y1563610D01*
G02X1511117Y1564189I1202J-1D01*
G01X1512683Y1566899D01*
X1512685Y1566902D01*
G37*
G36*
G01X1507961D02*
G02X1509021Y1567538I1060J-565D01*
G02X1510224Y1566336I1J-1202D01*
G02X1510063Y1565736I-1204J1D01*
G01X1508518Y1563063D01*
X1508516Y1563059D01*
G02X1507446Y1562406I-1070J550D01*
G02X1506244Y1563608I0J1202D01*
G01Y1563610D01*
G02X1506393Y1564189I1202J-1D01*
G01X1507959Y1566899D01*
X1507961Y1566902D01*
G37*
G36*
G01X1503236D02*
G02X1504296Y1567538I1060J-565D01*
G02X1505498Y1566336I0J-1202D01*
G02X1505338Y1565736I-1203J0D01*
G01X1503793Y1563063D01*
X1503791Y1563059D01*
G02X1502721Y1562406I-1070J550D01*
G02X1501518Y1563608I-1J1202D01*
G01Y1563610D01*
G02X1501668Y1564189I1203J-3D01*
G01X1503234Y1566899D01*
X1503236Y1566902D01*
G37*
G36*
G01X1498512D02*
G02X1499572Y1567538I1060J-565D01*
G02X1500774Y1566336I0J-1202D01*
G02X1500614Y1565736I-1203J0D01*
G01X1499069Y1563063D01*
X1499067Y1563059D01*
G02X1497997Y1562406I-1070J550D01*
G02X1496794Y1563608I-1J1202D01*
G01Y1563610D01*
G02X1496944Y1564189I1203J-3D01*
G01X1498510Y1566899D01*
X1498512Y1566902D01*
G37*
G36*
G01X1484339D02*
G02X1485399Y1567538I1060J-565D01*
G02X1486602Y1566336I1J-1202D01*
G02X1486441Y1565736I-1204J1D01*
G01X1484896Y1563063D01*
X1484894Y1563059D01*
G02X1483824Y1562406I-1070J550D01*
G02X1482622Y1563608I0J1202D01*
G01Y1563610D01*
G02X1482771Y1564189I1202J-1D01*
G01X1484337Y1566899D01*
X1484339Y1566902D01*
G37*
G36*
G01X1479614D02*
G02X1480674Y1567538I1060J-565D01*
G02X1481876Y1566336I0J-1202D01*
G02X1481716Y1565736I-1203J0D01*
G01X1480171Y1563063D01*
X1480169Y1563059D01*
G02X1479099Y1562406I-1070J550D01*
G02X1477896Y1563608I-1J1202D01*
G01Y1563610D01*
G02X1478046Y1564189I1203J-3D01*
G01X1479612Y1566899D01*
X1479614Y1566902D01*
G37*
G36*
G01X1474890D02*
G02X1475950Y1567538I1060J-565D01*
G02X1477152Y1566336I0J-1202D01*
G02X1476992Y1565736I-1203J0D01*
G01X1475447Y1563063D01*
X1475445Y1563059D01*
G02X1474375Y1562406I-1070J550D01*
G02X1473172Y1563608I-1J1202D01*
G01Y1563610D01*
G02X1473322Y1564189I1203J-3D01*
G01X1474888Y1566899D01*
X1474890Y1566902D01*
G37*
G36*
G01X1470165D02*
G02X1471225Y1567538I1060J-565D01*
G02X1472428Y1566336I1J-1202D01*
G02X1472267Y1565736I-1204J1D01*
G01X1470722Y1563063D01*
X1470720Y1563059D01*
G02X1469650Y1562406I-1070J550D01*
G02X1468448Y1563608I0J1202D01*
G01Y1563610D01*
G02X1468597Y1564189I1202J-1D01*
G01X1470163Y1566899D01*
X1470165Y1566902D01*
G37*
G36*
G01X1465441D02*
G02X1466501Y1567538I1060J-565D01*
G02X1467704Y1566336I1J-1202D01*
G02X1467543Y1565736I-1204J1D01*
G01X1465998Y1563063D01*
X1465996Y1563059D01*
G02X1464926Y1562406I-1070J550D01*
G02X1463724Y1563608I0J1202D01*
G01Y1563610D01*
G02X1463873Y1564189I1202J-1D01*
G01X1465439Y1566899D01*
X1465441Y1566902D01*
G37*
G36*
G01X1460717D02*
G02X1461777Y1567538I1060J-565D01*
G02X1462980Y1566336I1J-1202D01*
G02X1462819Y1565736I-1204J1D01*
G01X1461274Y1563063D01*
X1461272Y1563059D01*
G02X1460202Y1562406I-1070J550D01*
G02X1459000Y1563608I0J1202D01*
G01Y1563610D01*
G02X1459149Y1564189I1202J-1D01*
G01X1460715Y1566899D01*
X1460717Y1566902D01*
G37*
G36*
G01X1493787D02*
G02X1494847Y1567538I1060J-565D01*
G02X1496050Y1566336I1J-1202D01*
G02X1495889Y1565736I-1204J1D01*
G01X1494344Y1563063D01*
X1494342Y1563059D01*
G02X1493272Y1562406I-1070J550D01*
G02X1492070Y1563608I0J1202D01*
G01Y1563610D01*
G02X1492219Y1564189I1202J-1D01*
G01X1493785Y1566899D01*
X1493787Y1566902D01*
G37*
G36*
G01X1489063D02*
G02X1490123Y1567538I1060J-565D01*
G02X1491326Y1566336I1J-1202D01*
G02X1491165Y1565736I-1204J1D01*
G01X1489620Y1563063D01*
X1489618Y1563059D01*
G02X1488548Y1562406I-1070J550D01*
G02X1487346Y1563608I0J1202D01*
G01Y1563610D01*
G02X1487495Y1564189I1202J-1D01*
G01X1489061Y1566899D01*
X1489063Y1566902D01*
G37*
G36*
G01X1267409D02*
G02X1268469Y1567538I1060J-565D01*
G02X1269672Y1566336I1J-1202D01*
G02X1269511Y1565736I-1204J1D01*
G01X1267966Y1563063D01*
X1267964Y1563059D01*
G02X1266894Y1562406I-1070J550D01*
G02X1265692Y1563608I0J1202D01*
G01Y1563610D01*
G02X1265841Y1564189I1202J-1D01*
G01X1267407Y1566899D01*
X1267409Y1566902D01*
G37*
G36*
G01X1262684D02*
G02X1263744Y1567538I1060J-565D01*
G02X1264946Y1566336I0J-1202D01*
G02X1264786Y1565736I-1203J0D01*
G01X1263241Y1563063D01*
X1263239Y1563059D01*
G02X1262169Y1562406I-1070J550D01*
G02X1260966Y1563608I-1J1202D01*
G01Y1563610D01*
G02X1261116Y1564189I1203J-3D01*
G01X1262682Y1566899D01*
X1262684Y1566902D01*
G37*
G36*
G01X1257960D02*
G02X1259020Y1567538I1060J-565D01*
G02X1260222Y1566336I0J-1202D01*
G02X1260062Y1565736I-1203J0D01*
G01X1258517Y1563063D01*
X1258515Y1563059D01*
G02X1257445Y1562406I-1070J550D01*
G02X1256242Y1563608I-1J1202D01*
G01Y1563610D01*
G02X1256392Y1564189I1203J-3D01*
G01X1257958Y1566899D01*
X1257960Y1566902D01*
G37*
G36*
G01X1253235D02*
G02X1254295Y1567538I1060J-565D01*
G02X1255498Y1566336I1J-1202D01*
G02X1255337Y1565736I-1204J1D01*
G01X1253792Y1563063D01*
X1253790Y1563059D01*
G02X1252720Y1562406I-1070J550D01*
G02X1251518Y1563608I0J1202D01*
G01Y1563610D01*
G02X1251667Y1564189I1202J-1D01*
G01X1253233Y1566899D01*
X1253235Y1566902D01*
G37*
G36*
G01X1248511D02*
G02X1249571Y1567538I1060J-565D01*
G02X1250774Y1566336I1J-1202D01*
G02X1250613Y1565736I-1204J1D01*
G01X1249068Y1563063D01*
X1249066Y1563059D01*
G02X1247996Y1562406I-1070J550D01*
G02X1246794Y1563608I0J1202D01*
G01Y1563610D01*
G02X1246943Y1564189I1202J-1D01*
G01X1248509Y1566899D01*
X1248511Y1566902D01*
G37*
G36*
G01X1243787D02*
G02X1244847Y1567538I1060J-565D01*
G02X1246050Y1566336I1J-1202D01*
G02X1245889Y1565736I-1204J1D01*
G01X1244344Y1563063D01*
X1244342Y1563059D01*
G02X1243272Y1562406I-1070J550D01*
G02X1242070Y1563608I0J1202D01*
G01Y1563610D01*
G02X1242219Y1564189I1202J-1D01*
G01X1243785Y1566899D01*
X1243787Y1566902D01*
G37*
G36*
G01X1239062D02*
G02X1240122Y1567538I1060J-565D01*
G02X1241324Y1566336I0J-1202D01*
G02X1241164Y1565736I-1203J0D01*
G01X1239619Y1563063D01*
X1239617Y1563059D01*
G02X1238547Y1562406I-1070J550D01*
G02X1237344Y1563608I-1J1202D01*
G01Y1563610D01*
G02X1237494Y1564189I1203J-3D01*
G01X1239060Y1566899D01*
X1239062Y1566902D01*
G37*
G36*
G01X1234338D02*
G02X1235398Y1567538I1060J-565D01*
G02X1236600Y1566336I0J-1202D01*
G02X1236440Y1565736I-1203J0D01*
G01X1234895Y1563063D01*
X1234893Y1563059D01*
G02X1233823Y1562406I-1070J550D01*
G02X1232620Y1563608I-1J1202D01*
G01Y1563610D01*
G02X1232770Y1564189I1203J-3D01*
G01X1234336Y1566899D01*
X1234338Y1566902D01*
G37*
G36*
G01X1220165D02*
G02X1221225Y1567538I1060J-565D01*
G02X1222428Y1566336I1J-1202D01*
G02X1222267Y1565736I-1204J1D01*
G01X1220722Y1563063D01*
X1220720Y1563059D01*
G02X1219650Y1562406I-1070J550D01*
G02X1218448Y1563608I0J1202D01*
G01Y1563610D01*
G02X1218597Y1564189I1202J-1D01*
G01X1220163Y1566899D01*
X1220165Y1566902D01*
G37*
G36*
G01X1215440D02*
G02X1216500Y1567538I1060J-565D01*
G02X1217702Y1566336I0J-1202D01*
G02X1217542Y1565736I-1203J0D01*
G01X1215997Y1563063D01*
X1215995Y1563059D01*
G02X1214925Y1562406I-1070J550D01*
G02X1213722Y1563608I-1J1202D01*
G01Y1563610D01*
G02X1213872Y1564189I1203J-3D01*
G01X1215438Y1566899D01*
X1215440Y1566902D01*
G37*
G36*
G01X1210716D02*
G02X1211776Y1567538I1060J-565D01*
G02X1212978Y1566336I0J-1202D01*
G02X1212818Y1565736I-1203J0D01*
G01X1211273Y1563063D01*
X1211271Y1563059D01*
G02X1210201Y1562406I-1070J550D01*
G02X1208998Y1563608I-1J1202D01*
G01Y1563610D01*
G02X1209148Y1564189I1203J-3D01*
G01X1210714Y1566899D01*
X1210716Y1566902D01*
G37*
G36*
G01X1205991D02*
G02X1207051Y1567538I1060J-565D01*
G02X1208254Y1566336I1J-1202D01*
G02X1208093Y1565736I-1204J1D01*
G01X1206548Y1563063D01*
X1206546Y1563059D01*
G02X1205476Y1562406I-1070J550D01*
G02X1204274Y1563608I0J1202D01*
G01Y1563610D01*
G02X1204423Y1564189I1202J-1D01*
G01X1205989Y1566899D01*
X1205991Y1566902D01*
G37*
G36*
G01X1201267D02*
G02X1202327Y1567538I1060J-565D01*
G02X1203530Y1566336I1J-1202D01*
G02X1203369Y1565736I-1204J1D01*
G01X1201824Y1563063D01*
X1201822Y1563059D01*
G02X1200752Y1562406I-1070J550D01*
G02X1199550Y1563608I0J1202D01*
G01Y1563610D01*
G02X1199699Y1564189I1202J-1D01*
G01X1201265Y1566899D01*
X1201267Y1566902D01*
G37*
G36*
G01X1196543D02*
G02X1197603Y1567538I1060J-565D01*
G02X1198806Y1566336I1J-1202D01*
G02X1198645Y1565736I-1204J1D01*
G01X1197100Y1563063D01*
X1197098Y1563059D01*
G02X1196028Y1562406I-1070J550D01*
G02X1194826Y1563608I0J1202D01*
G01Y1563610D01*
G02X1194975Y1564189I1202J-1D01*
G01X1196541Y1566899D01*
X1196543Y1566902D01*
G37*
G36*
G01X1229613D02*
G02X1230673Y1567538I1060J-565D01*
G02X1231876Y1566336I1J-1202D01*
G02X1231715Y1565736I-1204J1D01*
G01X1230170Y1563063D01*
X1230168Y1563059D01*
G02X1229098Y1562406I-1070J550D01*
G02X1227896Y1563608I0J1202D01*
G01Y1563610D01*
G02X1228045Y1564189I1202J-1D01*
G01X1229611Y1566899D01*
X1229613Y1566902D01*
G37*
G36*
G01X1224889D02*
G02X1225949Y1567538I1060J-565D01*
G02X1227152Y1566336I1J-1202D01*
G02X1226991Y1565736I-1204J1D01*
G01X1225446Y1563063D01*
X1225444Y1563059D01*
G02X1224374Y1562406I-1070J550D01*
G02X1223172Y1563608I0J1202D01*
G01Y1563610D01*
G02X1223321Y1564189I1202J-1D01*
G01X1224887Y1566899D01*
X1224889Y1566902D01*
G37*
G36*
G01X1395471D02*
G02X1396531Y1567538I1060J-565D01*
G02X1397734Y1566336I1J-1202D01*
G02X1397573Y1565736I-1204J1D01*
G01X1396028Y1563063D01*
X1396026Y1563059D01*
G02X1394956Y1562406I-1070J550D01*
G02X1393754Y1563608I0J1202D01*
G01Y1563610D01*
G02X1393903Y1564189I1202J-1D01*
G01X1395469Y1566899D01*
X1395471Y1566902D01*
G37*
G36*
G01X1390746D02*
G02X1391806Y1567538I1060J-565D01*
G02X1393008Y1566336I0J-1202D01*
G02X1392848Y1565736I-1203J0D01*
G01X1391303Y1563063D01*
X1391301Y1563059D01*
G02X1390231Y1562406I-1070J550D01*
G02X1389028Y1563608I-1J1202D01*
G01Y1563610D01*
G02X1389178Y1564189I1203J-3D01*
G01X1390744Y1566899D01*
X1390746Y1566902D01*
G37*
G36*
G01X1386022D02*
G02X1387082Y1567538I1060J-565D01*
G02X1388284Y1566336I0J-1202D01*
G02X1388124Y1565736I-1203J0D01*
G01X1386579Y1563063D01*
X1386577Y1563059D01*
G02X1385507Y1562406I-1070J550D01*
G02X1384304Y1563608I-1J1202D01*
G01Y1563610D01*
G02X1384454Y1564189I1203J-3D01*
G01X1386020Y1566899D01*
X1386022Y1566902D01*
G37*
G36*
G01X1381297D02*
G02X1382357Y1567538I1060J-565D01*
G02X1383560Y1566336I1J-1202D01*
G02X1383399Y1565736I-1204J1D01*
G01X1381854Y1563063D01*
X1381852Y1563059D01*
G02X1380782Y1562406I-1070J550D01*
G02X1379580Y1563608I0J1202D01*
G01Y1563610D01*
G02X1379729Y1564189I1202J-1D01*
G01X1381295Y1566899D01*
X1381297Y1566902D01*
G37*
G36*
G01X1376573D02*
G02X1377633Y1567538I1060J-565D01*
G02X1378836Y1566336I1J-1202D01*
G02X1378675Y1565736I-1204J1D01*
G01X1377130Y1563063D01*
X1377128Y1563059D01*
G02X1376058Y1562406I-1070J550D01*
G02X1374856Y1563608I0J1202D01*
G01Y1563610D01*
G02X1375005Y1564189I1202J-1D01*
G01X1376571Y1566899D01*
X1376573Y1566902D01*
G37*
G36*
G01X1371849D02*
G02X1372909Y1567538I1060J-565D01*
G02X1374112Y1566336I1J-1202D01*
G02X1373951Y1565736I-1204J1D01*
G01X1372406Y1563063D01*
X1372404Y1563059D01*
G02X1371334Y1562406I-1070J550D01*
G02X1370132Y1563608I0J1202D01*
G01Y1563610D01*
G02X1370281Y1564189I1202J-1D01*
G01X1371847Y1566899D01*
X1371849Y1566902D01*
G37*
G36*
G01X1367124D02*
G02X1368184Y1567538I1060J-565D01*
G02X1369386Y1566336I0J-1202D01*
G02X1369226Y1565736I-1203J0D01*
G01X1367681Y1563063D01*
X1367679Y1563059D01*
G02X1366609Y1562406I-1070J550D01*
G02X1365406Y1563608I-1J1202D01*
G01Y1563610D01*
G02X1365556Y1564189I1203J-3D01*
G01X1367122Y1566899D01*
X1367124Y1566902D01*
G37*
G36*
G01X1362400D02*
G02X1363460Y1567538I1060J-565D01*
G02X1364662Y1566336I0J-1202D01*
G02X1364502Y1565736I-1203J0D01*
G01X1362957Y1563063D01*
X1362955Y1563059D01*
G02X1361885Y1562406I-1070J550D01*
G02X1360682Y1563608I-1J1202D01*
G01Y1563610D01*
G02X1360832Y1564189I1203J-3D01*
G01X1362398Y1566899D01*
X1362400Y1566902D01*
G37*
G36*
G01X1348227D02*
G02X1349287Y1567538I1060J-565D01*
G02X1350490Y1566336I1J-1202D01*
G02X1350329Y1565736I-1204J1D01*
G01X1348784Y1563063D01*
X1348782Y1563059D01*
G02X1347712Y1562406I-1070J550D01*
G02X1346510Y1563608I0J1202D01*
G01Y1563610D01*
G02X1346659Y1564189I1202J-1D01*
G01X1348225Y1566899D01*
X1348227Y1566902D01*
G37*
G36*
G01X1343502D02*
G02X1344562Y1567538I1060J-565D01*
G02X1345764Y1566336I0J-1202D01*
G02X1345604Y1565736I-1203J0D01*
G01X1344059Y1563063D01*
X1344057Y1563059D01*
G02X1342987Y1562406I-1070J550D01*
G02X1341784Y1563608I-1J1202D01*
G01Y1563610D01*
G02X1341934Y1564189I1203J-3D01*
G01X1343500Y1566899D01*
X1343502Y1566902D01*
G37*
G36*
G01X1338778D02*
G02X1339838Y1567538I1060J-565D01*
G02X1341040Y1566336I0J-1202D01*
G02X1340880Y1565736I-1203J0D01*
G01X1339335Y1563063D01*
X1339333Y1563059D01*
G02X1338263Y1562406I-1070J550D01*
G02X1337060Y1563608I-1J1202D01*
G01Y1563610D01*
G02X1337210Y1564189I1203J-3D01*
G01X1338776Y1566899D01*
X1338778Y1566902D01*
G37*
G36*
G01X1334053D02*
G02X1335113Y1567538I1060J-565D01*
G02X1336316Y1566336I1J-1202D01*
G02X1336155Y1565736I-1204J1D01*
G01X1334610Y1563063D01*
X1334608Y1563059D01*
G02X1333538Y1562406I-1070J550D01*
G02X1332336Y1563608I0J1202D01*
G01Y1563610D01*
G02X1332485Y1564189I1202J-1D01*
G01X1334051Y1566899D01*
X1334053Y1566902D01*
G37*
G36*
G01X1329329D02*
G02X1330389Y1567538I1060J-565D01*
G02X1331592Y1566336I1J-1202D01*
G02X1331431Y1565736I-1204J1D01*
G01X1329886Y1563063D01*
X1329884Y1563059D01*
G02X1328814Y1562406I-1070J550D01*
G02X1327612Y1563608I0J1202D01*
G01Y1563610D01*
G02X1327761Y1564189I1202J-1D01*
G01X1329327Y1566899D01*
X1329329Y1566902D01*
G37*
G36*
G01X1324605D02*
G02X1325665Y1567538I1060J-565D01*
G02X1326868Y1566336I1J-1202D01*
G02X1326707Y1565736I-1204J1D01*
G01X1325162Y1563063D01*
X1325160Y1563059D01*
G02X1324090Y1562406I-1070J550D01*
G02X1322888Y1563608I0J1202D01*
G01Y1563610D01*
G02X1323037Y1564189I1202J-1D01*
G01X1324603Y1566899D01*
X1324605Y1566902D01*
G37*
G36*
G01X1357675D02*
G02X1358735Y1567538I1060J-565D01*
G02X1359938Y1566336I1J-1202D01*
G02X1359777Y1565736I-1204J1D01*
G01X1358232Y1563063D01*
X1358230Y1563059D01*
G02X1357160Y1562406I-1070J550D01*
G02X1355958Y1563608I0J1202D01*
G01Y1563610D01*
G02X1356107Y1564189I1202J-1D01*
G01X1357673Y1566899D01*
X1357675Y1566902D01*
G37*
G36*
G01X1352951D02*
G02X1354011Y1567538I1060J-565D01*
G02X1355214Y1566336I1J-1202D01*
G02X1355053Y1565736I-1204J1D01*
G01X1353508Y1563063D01*
X1353506Y1563059D01*
G02X1352436Y1562406I-1070J550D01*
G02X1351234Y1563608I0J1202D01*
G01Y1563610D01*
G02X1351383Y1564189I1202J-1D01*
G01X1352949Y1566899D01*
X1352951Y1566902D01*
G37*
G36*
G01X193394Y1520264D02*
G02X194454Y1520900I1060J-565D01*
G02X195656Y1519698I0J-1202D01*
G02X195496Y1519098I-1203J0D01*
G01X193951Y1516425D01*
X193949Y1516421D01*
G02X192879Y1515768I-1070J550D01*
G02X191676Y1516970I-1J1202D01*
G01Y1516972D01*
G02X191826Y1517551I1203J-3D01*
G01X193392Y1520261D01*
X193394Y1520264D01*
G37*
G36*
G01X523709Y1533902D02*
G02X524769Y1534538I1060J-565D01*
G02X525972Y1533336I1J-1202D01*
G02X525811Y1532736I-1204J1D01*
G01X524266Y1530063D01*
X524264Y1530059D01*
G02X523194Y1529406I-1070J550D01*
G02X521992Y1530608I0J1202D01*
G01Y1530610D01*
G02X522141Y1531189I1202J-1D01*
G01X523707Y1533899D01*
X523709Y1533902D01*
G37*
G36*
G01X514260D02*
G02X515320Y1534538I1060J-565D01*
G02X516522Y1533336I0J-1202D01*
G02X516362Y1532736I-1203J0D01*
G01X514817Y1530063D01*
X514815Y1530059D01*
G02X513745Y1529406I-1070J550D01*
G02X512542Y1530608I-1J1202D01*
G01Y1530610D01*
G02X512692Y1531189I1203J-3D01*
G01X514258Y1533899D01*
X514260Y1533902D01*
G37*
G36*
G01X509535D02*
G02X510595Y1534538I1060J-565D01*
G02X511798Y1533336I1J-1202D01*
G02X511637Y1532736I-1204J1D01*
G01X510092Y1530063D01*
X510090Y1530059D01*
G02X509020Y1529406I-1070J550D01*
G02X507818Y1530608I0J1202D01*
G01Y1530610D01*
G02X507967Y1531189I1202J-1D01*
G01X509533Y1533899D01*
X509535Y1533902D01*
G37*
G36*
G01X504811D02*
G02X505871Y1534538I1060J-565D01*
G02X507074Y1533336I1J-1202D01*
G02X506913Y1532736I-1204J1D01*
G01X505368Y1530063D01*
X505366Y1530059D01*
G02X504296Y1529406I-1070J550D01*
G02X503094Y1530608I0J1202D01*
G01Y1530610D01*
G02X503243Y1531189I1202J-1D01*
G01X504809Y1533899D01*
X504811Y1533902D01*
G37*
G36*
G01X500087D02*
G02X501147Y1534538I1060J-565D01*
G02X502350Y1533336I1J-1202D01*
G02X502189Y1532736I-1204J1D01*
G01X500644Y1530063D01*
X500642Y1530059D01*
G02X499572Y1529406I-1070J550D01*
G02X498370Y1530608I0J1202D01*
G01Y1530610D01*
G02X498519Y1531189I1202J-1D01*
G01X500085Y1533899D01*
X500087Y1533902D01*
G37*
G36*
G01X495362D02*
G02X496422Y1534538I1060J-565D01*
G02X497624Y1533336I0J-1202D01*
G02X497464Y1532736I-1203J0D01*
G01X495919Y1530063D01*
X495917Y1530059D01*
G02X494847Y1529406I-1070J550D01*
G02X493644Y1530608I-1J1202D01*
G01Y1530610D01*
G02X493794Y1531189I1203J-3D01*
G01X495360Y1533899D01*
X495362Y1533902D01*
G37*
G36*
G01X490638D02*
G02X491698Y1534538I1060J-565D01*
G02X492900Y1533336I0J-1202D01*
G02X492740Y1532736I-1203J0D01*
G01X491195Y1530063D01*
X491193Y1530059D01*
G02X490123Y1529406I-1070J550D01*
G02X488920Y1530608I-1J1202D01*
G01Y1530610D01*
G02X489070Y1531189I1203J-3D01*
G01X490636Y1533899D01*
X490638Y1533902D01*
G37*
G36*
G01X476465D02*
G02X477525Y1534538I1060J-565D01*
G02X478728Y1533336I1J-1202D01*
G02X478567Y1532736I-1204J1D01*
G01X477022Y1530063D01*
X477020Y1530059D01*
G02X475950Y1529406I-1070J550D01*
G02X474748Y1530608I0J1202D01*
G01Y1530610D01*
G02X474897Y1531189I1202J-1D01*
G01X476463Y1533899D01*
X476465Y1533902D01*
G37*
G36*
G01X471740D02*
G02X472800Y1534538I1060J-565D01*
G02X474002Y1533336I0J-1202D01*
G02X473842Y1532736I-1203J0D01*
G01X472297Y1530063D01*
X472295Y1530059D01*
G02X471225Y1529406I-1070J550D01*
G02X470022Y1530608I-1J1202D01*
G01Y1530610D01*
G02X470172Y1531189I1203J-3D01*
G01X471738Y1533899D01*
X471740Y1533902D01*
G37*
G36*
G01X467016D02*
G02X468076Y1534538I1060J-565D01*
G02X469278Y1533336I0J-1202D01*
G02X469118Y1532736I-1203J0D01*
G01X467573Y1530063D01*
X467571Y1530059D01*
G02X466501Y1529406I-1070J550D01*
G02X465298Y1530608I-1J1202D01*
G01Y1530610D01*
G02X465448Y1531189I1203J-3D01*
G01X467014Y1533899D01*
X467016Y1533902D01*
G37*
G36*
G01X462291D02*
G02X463351Y1534538I1060J-565D01*
G02X464554Y1533336I1J-1202D01*
G02X464393Y1532736I-1204J1D01*
G01X462848Y1530063D01*
X462846Y1530059D01*
G02X461776Y1529406I-1070J550D01*
G02X460574Y1530608I0J1202D01*
G01Y1530610D01*
G02X460723Y1531189I1202J-1D01*
G01X462289Y1533899D01*
X462291Y1533902D01*
G37*
G36*
G01X457567D02*
G02X458627Y1534538I1060J-565D01*
G02X459830Y1533336I1J-1202D01*
G02X459669Y1532736I-1204J1D01*
G01X458124Y1530063D01*
X458122Y1530059D01*
G02X457052Y1529406I-1070J550D01*
G02X455850Y1530608I0J1202D01*
G01Y1530610D01*
G02X455999Y1531189I1202J-1D01*
G01X457565Y1533899D01*
X457567Y1533902D01*
G37*
G36*
G01X452843D02*
G02X453903Y1534538I1060J-565D01*
G02X455106Y1533336I1J-1202D01*
G02X454945Y1532736I-1204J1D01*
G01X453400Y1530063D01*
X453398Y1530059D01*
G02X452328Y1529406I-1070J550D01*
G02X451126Y1530608I0J1202D01*
G01Y1530610D01*
G02X451275Y1531189I1202J-1D01*
G01X452841Y1533899D01*
X452843Y1533902D01*
G37*
G36*
G01X485913D02*
G02X486973Y1534538I1060J-565D01*
G02X488176Y1533336I1J-1202D01*
G02X488015Y1532736I-1204J1D01*
G01X486470Y1530063D01*
X486468Y1530059D01*
G02X485398Y1529406I-1070J550D01*
G02X484196Y1530608I0J1202D01*
G01Y1530610D01*
G02X484345Y1531189I1202J-1D01*
G01X485911Y1533899D01*
X485913Y1533902D01*
G37*
G36*
G01X481189D02*
G02X482249Y1534538I1060J-565D01*
G02X483452Y1533336I1J-1202D01*
G02X483291Y1532736I-1204J1D01*
G01X481746Y1530063D01*
X481744Y1530059D01*
G02X480674Y1529406I-1070J550D01*
G02X479472Y1530608I0J1202D01*
G01Y1530610D01*
G02X479621Y1531189I1202J-1D01*
G01X481187Y1533899D01*
X481189Y1533902D01*
G37*
G36*
G01X1210716Y1553264D02*
G02X1211776Y1553900I1060J-565D01*
G02X1212978Y1552698I0J-1202D01*
G02X1212818Y1552098I-1203J0D01*
G01X1211273Y1549425D01*
X1211271Y1549421D01*
G02X1210201Y1548768I-1070J550D01*
G02X1208998Y1549970I-1J1202D01*
G01Y1549972D01*
G02X1209148Y1550551I1203J-3D01*
G01X1210714Y1553261D01*
X1210716Y1553264D01*
G37*
G36*
G01X1205992D02*
G02X1207052Y1553900I1060J-565D01*
G02X1208254Y1552698I0J-1202D01*
G02X1208094Y1552098I-1203J0D01*
G01X1206549Y1549425D01*
X1206547Y1549421D01*
G02X1205477Y1548768I-1070J550D01*
G02X1204274Y1549970I-1J1202D01*
G01Y1549972D01*
G02X1204424Y1550551I1203J-3D01*
G01X1205990Y1553261D01*
X1205992Y1553264D01*
G37*
G36*
G01X632873Y1533902D02*
G02X633933Y1534538I1060J-565D01*
G02X635136Y1533336I1J-1202D01*
G02X634975Y1532736I-1204J1D01*
G01X633430Y1530063D01*
X633428Y1530059D01*
G02X632358Y1529406I-1070J550D01*
G02X631156Y1530608I0J1202D01*
G01Y1530610D01*
G02X631305Y1531189I1202J-1D01*
G01X632871Y1533899D01*
X632873Y1533902D01*
G37*
G36*
G01X628149D02*
G02X629209Y1534538I1060J-565D01*
G02X630412Y1533336I1J-1202D01*
G02X630251Y1532736I-1204J1D01*
G01X628706Y1530063D01*
X628704Y1530059D01*
G02X627634Y1529406I-1070J550D01*
G02X626432Y1530608I0J1202D01*
G01Y1530610D01*
G02X626581Y1531189I1202J-1D01*
G01X628147Y1533899D01*
X628149Y1533902D01*
G37*
G36*
G01X623424D02*
G02X624484Y1534538I1060J-565D01*
G02X625686Y1533336I0J-1202D01*
G02X625526Y1532736I-1203J0D01*
G01X623981Y1530063D01*
X623979Y1530059D01*
G02X622909Y1529406I-1070J550D01*
G02X621706Y1530608I-1J1202D01*
G01Y1530610D01*
G02X621856Y1531189I1203J-3D01*
G01X623422Y1533899D01*
X623424Y1533902D01*
G37*
G36*
G01X618700D02*
G02X619760Y1534538I1060J-565D01*
G02X620962Y1533336I0J-1202D01*
G02X620802Y1532736I-1203J0D01*
G01X619257Y1530063D01*
X619255Y1530059D01*
G02X618185Y1529406I-1070J550D01*
G02X616982Y1530608I-1J1202D01*
G01Y1530610D01*
G02X617132Y1531189I1203J-3D01*
G01X618698Y1533899D01*
X618700Y1533902D01*
G37*
G36*
G01X604527D02*
G02X605587Y1534538I1060J-565D01*
G02X606790Y1533336I1J-1202D01*
G02X606629Y1532736I-1204J1D01*
G01X605084Y1530063D01*
X605082Y1530059D01*
G02X604012Y1529406I-1070J550D01*
G02X602810Y1530608I0J1202D01*
G01Y1530610D01*
G02X602959Y1531189I1202J-1D01*
G01X604525Y1533899D01*
X604527Y1533902D01*
G37*
G36*
G01X585629D02*
G02X586689Y1534538I1060J-565D01*
G02X587892Y1533336I1J-1202D01*
G02X587731Y1532736I-1204J1D01*
G01X586186Y1530063D01*
X586184Y1530059D01*
G02X585114Y1529406I-1070J550D01*
G02X583912Y1530608I0J1202D01*
G01Y1530610D01*
G02X584061Y1531189I1202J-1D01*
G01X585627Y1533899D01*
X585629Y1533902D01*
G37*
G36*
G01X580905D02*
G02X581965Y1534538I1060J-565D01*
G02X583168Y1533336I1J-1202D01*
G02X583007Y1532736I-1204J1D01*
G01X581462Y1530063D01*
X581460Y1530059D01*
G02X580390Y1529406I-1070J550D01*
G02X579188Y1530608I0J1202D01*
G01Y1530610D01*
G02X579337Y1531189I1202J-1D01*
G01X580903Y1533899D01*
X580905Y1533902D01*
G37*
G36*
G01X613975D02*
G02X615035Y1534538I1060J-565D01*
G02X616238Y1533336I1J-1202D01*
G02X616077Y1532736I-1204J1D01*
G01X614532Y1530063D01*
X614530Y1530059D01*
G02X613460Y1529406I-1070J550D01*
G02X612258Y1530608I0J1202D01*
G01Y1530610D01*
G02X612407Y1531189I1202J-1D01*
G01X613973Y1533899D01*
X613975Y1533902D01*
G37*
G36*
G01X609251D02*
G02X610311Y1534538I1060J-565D01*
G02X611514Y1533336I1J-1202D01*
G02X611353Y1532736I-1204J1D01*
G01X609808Y1530063D01*
X609806Y1530059D01*
G02X608736Y1529406I-1070J550D01*
G02X607534Y1530608I0J1202D01*
G01Y1530610D01*
G02X607683Y1531189I1202J-1D01*
G01X609249Y1533899D01*
X609251Y1533902D01*
G37*
G36*
G01X1659645Y1566902D02*
G02X1660705Y1567538I1060J-565D01*
G02X1661908Y1566336I1J-1202D01*
G02X1661747Y1565736I-1204J1D01*
G01X1660202Y1563063D01*
X1660200Y1563059D01*
G02X1659130Y1562406I-1070J550D01*
G02X1657928Y1563608I0J1202D01*
G01Y1563610D01*
G02X1658077Y1564189I1202J-1D01*
G01X1659643Y1566899D01*
X1659645Y1566902D01*
G37*
G36*
G01X1654920D02*
G02X1655980Y1567538I1060J-565D01*
G02X1657182Y1566336I0J-1202D01*
G02X1657022Y1565736I-1203J0D01*
G01X1655477Y1563063D01*
X1655475Y1563059D01*
G02X1654405Y1562406I-1070J550D01*
G02X1653202Y1563608I-1J1202D01*
G01Y1563610D01*
G02X1653352Y1564189I1203J-3D01*
G01X1654918Y1566899D01*
X1654920Y1566902D01*
G37*
G36*
G01X1650196D02*
G02X1651256Y1567538I1060J-565D01*
G02X1652458Y1566336I0J-1202D01*
G02X1652298Y1565736I-1203J0D01*
G01X1650753Y1563063D01*
X1650751Y1563059D01*
G02X1649681Y1562406I-1070J550D01*
G02X1648478Y1563608I-1J1202D01*
G01Y1563610D01*
G02X1648628Y1564189I1203J-3D01*
G01X1650194Y1566899D01*
X1650196Y1566902D01*
G37*
G36*
G01X1645471D02*
G02X1646531Y1567538I1060J-565D01*
G02X1647734Y1566336I1J-1202D01*
G02X1647573Y1565736I-1204J1D01*
G01X1646028Y1563063D01*
X1646026Y1563059D01*
G02X1644956Y1562406I-1070J550D01*
G02X1643754Y1563608I0J1202D01*
G01Y1563610D01*
G02X1643903Y1564189I1202J-1D01*
G01X1645469Y1566899D01*
X1645471Y1566902D01*
G37*
G36*
G01X1640747D02*
G02X1641807Y1567538I1060J-565D01*
G02X1643010Y1566336I1J-1202D01*
G02X1642849Y1565736I-1204J1D01*
G01X1641304Y1563063D01*
X1641302Y1563059D01*
G02X1640232Y1562406I-1070J550D01*
G02X1639030Y1563608I0J1202D01*
G01Y1563610D01*
G02X1639179Y1564189I1202J-1D01*
G01X1640745Y1566899D01*
X1640747Y1566902D01*
G37*
G36*
G01X1636023D02*
G02X1637083Y1567538I1060J-565D01*
G02X1638286Y1566336I1J-1202D01*
G02X1638125Y1565736I-1204J1D01*
G01X1636580Y1563063D01*
X1636578Y1563059D01*
G02X1635508Y1562406I-1070J550D01*
G02X1634306Y1563608I0J1202D01*
G01Y1563610D01*
G02X1634455Y1564189I1202J-1D01*
G01X1636021Y1566899D01*
X1636023Y1566902D01*
G37*
G36*
G01X1631298D02*
G02X1632358Y1567538I1060J-565D01*
G02X1633560Y1566336I0J-1202D01*
G02X1633400Y1565736I-1203J0D01*
G01X1631855Y1563063D01*
X1631853Y1563059D01*
G02X1630783Y1562406I-1070J550D01*
G02X1629580Y1563608I-1J1202D01*
G01Y1563610D01*
G02X1629730Y1564189I1203J-3D01*
G01X1631296Y1566899D01*
X1631298Y1566902D01*
G37*
G36*
G01X1626574D02*
G02X1627634Y1567538I1060J-565D01*
G02X1628836Y1566336I0J-1202D01*
G02X1628676Y1565736I-1203J0D01*
G01X1627131Y1563063D01*
X1627129Y1563059D01*
G02X1626059Y1562406I-1070J550D01*
G02X1624856Y1563608I-1J1202D01*
G01Y1563610D01*
G02X1625006Y1564189I1203J-3D01*
G01X1626572Y1566899D01*
X1626574Y1566902D01*
G37*
G36*
G01X1612401D02*
G02X1613461Y1567538I1060J-565D01*
G02X1614664Y1566336I1J-1202D01*
G02X1614503Y1565736I-1204J1D01*
G01X1612958Y1563063D01*
X1612956Y1563059D01*
G02X1611886Y1562406I-1070J550D01*
G02X1610684Y1563608I0J1202D01*
G01Y1563610D01*
G02X1610833Y1564189I1202J-1D01*
G01X1612399Y1566899D01*
X1612401Y1566902D01*
G37*
G36*
G01X1607676D02*
G02X1608736Y1567538I1060J-565D01*
G02X1609938Y1566336I0J-1202D01*
G02X1609778Y1565736I-1203J0D01*
G01X1608233Y1563063D01*
X1608231Y1563059D01*
G02X1607161Y1562406I-1070J550D01*
G02X1605958Y1563608I-1J1202D01*
G01Y1563610D01*
G02X1606108Y1564189I1203J-3D01*
G01X1607674Y1566899D01*
X1607676Y1566902D01*
G37*
G36*
G01X1602952D02*
G02X1604012Y1567538I1060J-565D01*
G02X1605214Y1566336I0J-1202D01*
G02X1605054Y1565736I-1203J0D01*
G01X1603509Y1563063D01*
X1603507Y1563059D01*
G02X1602437Y1562406I-1070J550D01*
G02X1601234Y1563608I-1J1202D01*
G01Y1563610D01*
G02X1601384Y1564189I1203J-3D01*
G01X1602950Y1566899D01*
X1602952Y1566902D01*
G37*
G36*
G01X1598227D02*
G02X1599287Y1567538I1060J-565D01*
G02X1600490Y1566336I1J-1202D01*
G02X1600329Y1565736I-1204J1D01*
G01X1598784Y1563063D01*
X1598782Y1563059D01*
G02X1597712Y1562406I-1070J550D01*
G02X1596510Y1563608I0J1202D01*
G01Y1563610D01*
G02X1596659Y1564189I1202J-1D01*
G01X1598225Y1566899D01*
X1598227Y1566902D01*
G37*
G36*
G01X1593503D02*
G02X1594563Y1567538I1060J-565D01*
G02X1595766Y1566336I1J-1202D01*
G02X1595605Y1565736I-1204J1D01*
G01X1594060Y1563063D01*
X1594058Y1563059D01*
G02X1592988Y1562406I-1070J550D01*
G02X1591786Y1563608I0J1202D01*
G01Y1563610D01*
G02X1591935Y1564189I1202J-1D01*
G01X1593501Y1566899D01*
X1593503Y1566902D01*
G37*
G36*
G01X1588779D02*
G02X1589839Y1567538I1060J-565D01*
G02X1591042Y1566336I1J-1202D01*
G02X1590881Y1565736I-1204J1D01*
G01X1589336Y1563063D01*
X1589334Y1563059D01*
G02X1588264Y1562406I-1070J550D01*
G02X1587062Y1563608I0J1202D01*
G01Y1563610D01*
G02X1587211Y1564189I1202J-1D01*
G01X1588777Y1566899D01*
X1588779Y1566902D01*
G37*
G36*
G01X1621849D02*
G02X1622909Y1567538I1060J-565D01*
G02X1624112Y1566336I1J-1202D01*
G02X1623951Y1565736I-1204J1D01*
G01X1622406Y1563063D01*
X1622404Y1563059D01*
G02X1621334Y1562406I-1070J550D01*
G02X1620132Y1563608I0J1202D01*
G01Y1563610D01*
G02X1620281Y1564189I1202J-1D01*
G01X1621847Y1566899D01*
X1621849Y1566902D01*
G37*
G36*
G01X1617125D02*
G02X1618185Y1567538I1060J-565D01*
G02X1619388Y1566336I1J-1202D01*
G02X1619227Y1565736I-1204J1D01*
G01X1617682Y1563063D01*
X1617680Y1563059D01*
G02X1616610Y1562406I-1070J550D01*
G02X1615408Y1563608I0J1202D01*
G01Y1563610D01*
G02X1615557Y1564189I1202J-1D01*
G01X1617123Y1566899D01*
X1617125Y1566902D01*
G37*
G36*
G01X518984Y1533902D02*
G02X520044Y1534538I1060J-565D01*
G02X521246Y1533336I0J-1202D01*
G02X521086Y1532736I-1203J0D01*
G01X519541Y1530063D01*
X519539Y1530059D01*
G02X518469Y1529406I-1070J550D01*
G02X517266Y1530608I-1J1202D01*
G01Y1530610D01*
G02X517416Y1531189I1203J-3D01*
G01X518982Y1533899D01*
X518984Y1533902D01*
G37*
G36*
G01X651771D02*
G02X652831Y1534538I1060J-565D01*
G02X654034Y1533336I1J-1202D01*
G02X653873Y1532736I-1204J1D01*
G01X652328Y1530063D01*
X652326Y1530059D01*
G02X651256Y1529406I-1070J550D01*
G02X650054Y1530608I0J1202D01*
G01Y1530610D01*
G02X650203Y1531189I1202J-1D01*
G01X651769Y1533899D01*
X651771Y1533902D01*
G37*
G36*
G01X647046D02*
G02X648106Y1534538I1060J-565D01*
G02X649308Y1533336I0J-1202D01*
G02X649148Y1532736I-1203J0D01*
G01X647603Y1530063D01*
X647601Y1530059D01*
G02X646531Y1529406I-1070J550D01*
G02X645328Y1530608I-1J1202D01*
G01Y1530610D01*
G02X645478Y1531189I1203J-3D01*
G01X647044Y1533899D01*
X647046Y1533902D01*
G37*
G36*
G01X642322D02*
G02X643382Y1534538I1060J-565D01*
G02X644584Y1533336I0J-1202D01*
G02X644424Y1532736I-1203J0D01*
G01X642879Y1530063D01*
X642877Y1530059D01*
G02X641807Y1529406I-1070J550D01*
G02X640604Y1530608I-1J1202D01*
G01Y1530610D01*
G02X640754Y1531189I1203J-3D01*
G01X642320Y1533899D01*
X642322Y1533902D01*
G37*
G36*
G01X637597D02*
G02X638657Y1534538I1060J-565D01*
G02X639860Y1533336I1J-1202D01*
G02X639699Y1532736I-1204J1D01*
G01X638154Y1530063D01*
X638152Y1530059D01*
G02X637082Y1529406I-1070J550D01*
G02X635880Y1530608I0J1202D01*
G01Y1530610D01*
G02X636029Y1531189I1202J-1D01*
G01X637595Y1533899D01*
X637597Y1533902D01*
G37*
G36*
G01X599802D02*
G02X600862Y1534538I1060J-565D01*
G02X602064Y1533336I0J-1202D01*
G02X601904Y1532736I-1203J0D01*
G01X600359Y1530063D01*
X600357Y1530059D01*
G02X599287Y1529406I-1070J550D01*
G02X598084Y1530608I-1J1202D01*
G01Y1530610D01*
G02X598234Y1531189I1203J-3D01*
G01X599800Y1533899D01*
X599802Y1533902D01*
G37*
G36*
G01X595078D02*
G02X596138Y1534538I1060J-565D01*
G02X597340Y1533336I0J-1202D01*
G02X597180Y1532736I-1203J0D01*
G01X595635Y1530063D01*
X595633Y1530059D01*
G02X594563Y1529406I-1070J550D01*
G02X593360Y1530608I-1J1202D01*
G01Y1530610D01*
G02X593510Y1531189I1203J-3D01*
G01X595076Y1533899D01*
X595078Y1533902D01*
G37*
G36*
G01X590353D02*
G02X591413Y1534538I1060J-565D01*
G02X592616Y1533336I1J-1202D01*
G02X592455Y1532736I-1204J1D01*
G01X590910Y1530063D01*
X590908Y1530059D01*
G02X589838Y1529406I-1070J550D01*
G02X588636Y1530608I0J1202D01*
G01Y1530610D01*
G02X588785Y1531189I1202J-1D01*
G01X590351Y1533899D01*
X590353Y1533902D01*
G37*
G36*
G01X1196543Y1553264D02*
G02X1197603Y1553900I1060J-565D01*
G02X1198806Y1552698I1J-1202D01*
G02X1198645Y1552098I-1204J1D01*
G01X1197100Y1549425D01*
X1197098Y1549421D01*
G02X1196028Y1548768I-1070J550D01*
G02X1194826Y1549970I0J1202D01*
G01Y1549972D01*
G02X1194975Y1550551I1202J-1D01*
G01X1196541Y1553261D01*
X1196543Y1553264D01*
G37*
G36*
G01X198118Y1520264D02*
G02X199178Y1520900I1060J-565D01*
G02X200380Y1519698I0J-1202D01*
G02X200220Y1519098I-1203J0D01*
G01X198675Y1516425D01*
X198673Y1516421D01*
G02X197603Y1515768I-1070J550D01*
G02X196400Y1516970I-1J1202D01*
G01Y1516972D01*
G02X196550Y1517551I1203J-3D01*
G01X198116Y1520261D01*
X198118Y1520264D01*
G37*
G36*
G01X1201267Y1553264D02*
G02X1202327Y1553900I1060J-565D01*
G02X1203530Y1552698I1J-1202D01*
G02X1203369Y1552098I-1204J1D01*
G01X1201824Y1549425D01*
X1201822Y1549421D01*
G02X1200752Y1548768I-1070J550D01*
G02X1199550Y1549970I0J1202D01*
G01Y1549972D01*
G02X1199699Y1550551I1202J-1D01*
G01X1201265Y1553261D01*
X1201267Y1553264D01*
G37*
G36*
G01X651771Y1520264D02*
G02X652831Y1520900I1060J-565D01*
G02X654034Y1519698I1J-1202D01*
G02X653873Y1519098I-1204J1D01*
G01X652328Y1516425D01*
X652326Y1516421D01*
G02X651256Y1515768I-1070J550D01*
G02X650054Y1516970I0J1202D01*
G01Y1516972D01*
G02X650203Y1517551I1202J-1D01*
G01X651769Y1520261D01*
X651771Y1520264D01*
G37*
G36*
G01X509535D02*
G02X510595Y1520900I1060J-565D01*
G02X511798Y1519698I1J-1202D01*
G02X511637Y1519098I-1204J1D01*
G01X510092Y1516425D01*
X510090Y1516421D01*
G02X509020Y1515768I-1070J550D01*
G02X507818Y1516970I0J1202D01*
G01Y1516972D01*
G02X507967Y1517551I1202J-1D01*
G01X509533Y1520261D01*
X509535Y1520264D01*
G37*
G36*
G01X1385686Y1494092D02*
G02Y1497098I0J1503D01*
G01X1389086D01*
G02Y1494092I0J-1503D01*
G01X1385686D01*
G37*
G36*
G01X269851Y1451392D02*
G02Y1454398I0J1503D01*
G01X273251D01*
G02Y1451392I0J-1503D01*
G01X269851D01*
G37*
G36*
G01X256451D02*
G02Y1454398I0J1503D01*
G01X259851D01*
G02Y1451392I0J-1503D01*
G01X256451D01*
G37*
G36*
G01X249751Y1461092D02*
G02Y1464098I0J1503D01*
G01X253151D01*
G02Y1461092I0J-1503D01*
G01X249751D01*
G37*
G36*
G01X243051Y1470792D02*
G02Y1473798I0J1503D01*
G01X246451D01*
G02Y1470792I0J-1503D01*
G01X243051D01*
G37*
G36*
G01X229651Y1451392D02*
G02Y1454398I0J1503D01*
G01X233051D01*
G02Y1451392I0J-1503D01*
G01X229651D01*
G37*
G36*
G01X222951Y1461092D02*
G02Y1464098I0J1503D01*
G01X226351D01*
G02Y1461092I0J-1503D01*
G01X222951D01*
G37*
G36*
G01X216251Y1470792D02*
G02Y1473798I0J1503D01*
G01X219651D01*
G02Y1470792I0J-1503D01*
G01X216251D01*
G37*
G36*
G01X202851Y1451392D02*
G02Y1454398I0J1503D01*
G01X206251D01*
G02Y1451392I0J-1503D01*
G01X202851D01*
G37*
G36*
G01X196151Y1461092D02*
G02Y1464098I0J1503D01*
G01X199551D01*
G02Y1461092I0J-1503D01*
G01X196151D01*
G37*
G36*
G01X189451Y1470792D02*
G02Y1473798I0J1503D01*
G01X192851D01*
G02Y1470792I0J-1503D01*
G01X189451D01*
G37*
G36*
G01X176051Y1451392D02*
G02Y1454398I0J1503D01*
G01X179451D01*
G02Y1451392I0J-1503D01*
G01X176051D01*
G37*
G36*
G01X212286Y1590878D02*
G02Y1593882I0J1502D01*
G01X215686D01*
G02Y1590878I0J-1502D01*
G01X212286D01*
G37*
G36*
G01X200226D02*
G02Y1593882I0J1502D01*
G01X203626D01*
G02Y1590878I0J-1502D01*
G01X200226D01*
G37*
G36*
G01X1310609Y1633878D02*
G02Y1636882I0J1502D01*
G01X1314009D01*
G02Y1633878I0J-1502D01*
G01X1310609D01*
G37*
G36*
G01X1490363D02*
G02Y1636882I0J1502D01*
G01X1493763D01*
G02Y1633878I0J-1502D01*
G01X1490363D01*
G37*
G36*
G01X491919Y1593882D02*
G02Y1590878I0J-1502D01*
G01X488519D01*
G02Y1593882I0J1502D01*
G01X491919D01*
G37*
G36*
G01X500579Y1590878D02*
G02Y1593882I0J1502D01*
G01X503979D01*
G02Y1590878I0J-1502D01*
G01X500579D01*
G37*
G36*
G01X194196Y1600878D02*
G02Y1603882I0J1502D01*
G01X197596D01*
G02Y1600878I0J-1502D01*
G01X194196D01*
G37*
G36*
G01X350976D02*
G02Y1603882I0J1502D01*
G01X354376D01*
G02Y1600878I0J-1502D01*
G01X350976D01*
G37*
G36*
G01X194196Y1612790D02*
G02Y1615794I0J1502D01*
G01X197596D01*
G02Y1612790I0J-1502D01*
G01X194196D01*
G37*
G36*
G01X330913Y1451392D02*
G02Y1454398I0J1503D01*
G01X334313D01*
G02Y1451392I0J-1503D01*
G01X330913D01*
G37*
G36*
G01X1376939Y1655790D02*
G02Y1658794I0J1502D01*
G01X1380339D01*
G02Y1655790I0J-1502D01*
G01X1376939D01*
G37*
G36*
G01Y1623878D02*
G02Y1626882I0J1502D01*
G01X1380339D01*
G02Y1623878I0J-1502D01*
G01X1376939D01*
G37*
G36*
G01X1220159D02*
G02Y1626882I0J1502D01*
G01X1223559D01*
G02Y1623878I0J-1502D01*
G01X1220159D01*
G37*
G36*
G01X572939Y1590878D02*
G02Y1593882I0J1502D01*
G01X576339D01*
G02Y1590878I0J-1502D01*
G01X572939D01*
G37*
G36*
G01X536759D02*
G02Y1593882I0J1502D01*
G01X540159D01*
G02Y1590878I0J-1502D01*
G01X536759D01*
G37*
G36*
G01X344946D02*
G02Y1593882I0J1502D01*
G01X348346D01*
G02Y1590878I0J-1502D01*
G01X344946D01*
G37*
G36*
G01X248466D02*
G02Y1593882I0J1502D01*
G01X251866D01*
G02Y1590878I0J-1502D01*
G01X248466D01*
G37*
G36*
G01X230376Y1600878D02*
G02Y1603882I0J1502D01*
G01X233776D01*
G02Y1600878I0J-1502D01*
G01X230376D01*
G37*
G36*
G01X206256D02*
G02Y1603882I0J1502D01*
G01X209656D01*
G02Y1600878I0J-1502D01*
G01X206256D01*
G37*
G36*
G01X236406Y1590878D02*
G02Y1593882I0J1502D01*
G01X239806D01*
G02Y1590878I0J-1502D01*
G01X236406D01*
G37*
G36*
G01X554849Y1600878D02*
G02Y1603882I0J1502D01*
G01X558249D01*
G02Y1600878I0J-1502D01*
G01X554849D01*
G37*
G36*
G01X470429D02*
G02Y1603882I0J1502D01*
G01X473829D01*
G02Y1600878I0J-1502D01*
G01X470429D01*
G37*
G36*
G01X482489D02*
G02Y1603882I0J1502D01*
G01X485889D01*
G02Y1600878I0J-1502D01*
G01X482489D01*
G37*
G36*
G01X1370909Y1633878D02*
G02Y1636882I0J1502D01*
G01X1374309D01*
G02Y1633878I0J-1502D01*
G01X1370909D01*
G37*
G36*
G01X1358849D02*
G02Y1636882I0J1502D01*
G01X1362249D01*
G02Y1633878I0J-1502D01*
G01X1358849D01*
G37*
G36*
G01X1346789D02*
G02Y1636882I0J1502D01*
G01X1350189D01*
G02Y1633878I0J-1502D01*
G01X1346789D01*
G37*
G36*
G01X1528498Y1484392D02*
G02Y1487398I0J1503D01*
G01X1531898D01*
G02Y1484392I0J-1503D01*
G01X1528498D01*
G37*
G36*
G01X1468198Y1494092D02*
G02Y1497098I0J1503D01*
G01X1471598D01*
G02Y1494092I0J-1503D01*
G01X1468198D01*
G37*
G36*
G01X615186Y1461092D02*
G02Y1464098I0J1503D01*
G01X618586D01*
G02Y1461092I0J-1503D01*
G01X615186D01*
G37*
G36*
G01X453624Y1470792D02*
G02Y1473798I0J1503D01*
G01X457024D01*
G02Y1470792I0J-1503D01*
G01X453624D01*
G37*
G36*
G01X1673360Y1487398D02*
G02Y1484392I0J-1503D01*
G01X1669960D01*
G02Y1487398I0J1503D01*
G01X1673360D01*
G37*
G36*
G01X1629760Y1484392D02*
G02Y1487398I0J1503D01*
G01X1633160D01*
G02Y1484392I0J-1503D01*
G01X1629760D01*
G37*
G36*
G01X1541898D02*
G02Y1487398I0J1503D01*
G01X1545298D01*
G02Y1484392I0J-1503D01*
G01X1541898D01*
G37*
G36*
G01X1501698D02*
G02Y1487398I0J1503D01*
G01X1505098D01*
G02Y1484392I0J-1503D01*
G01X1501698D01*
G37*
G36*
G01X1405786D02*
G02Y1487398I0J1503D01*
G01X1409186D01*
G02Y1484392I0J-1503D01*
G01X1405786D01*
G37*
G36*
G01X1365586D02*
G02Y1487398I0J1503D01*
G01X1368986D01*
G02Y1484392I0J-1503D01*
G01X1365586D01*
G37*
G36*
G01X1305286Y1494092D02*
G02Y1497098I0J1503D01*
G01X1308686D01*
G02Y1494092I0J-1503D01*
G01X1305286D01*
G37*
G36*
G01X1277724Y1484392D02*
G02Y1487398I0J1503D01*
G01X1281124D01*
G02Y1484392I0J-1503D01*
G01X1277724D01*
G37*
G36*
G01X1264324D02*
G02Y1487398I0J1503D01*
G01X1267724D01*
G02Y1484392I0J-1503D01*
G01X1264324D01*
G37*
G36*
G01X662086Y1451392D02*
G02Y1454398I0J1503D01*
G01X665486D01*
G02Y1451392I0J-1503D01*
G01X662086D01*
G37*
G36*
G01X621886D02*
G02Y1454398I0J1503D01*
G01X625286D01*
G02Y1451392I0J-1503D01*
G01X621886D01*
G37*
G36*
G01X534024D02*
G02Y1454398I0J1503D01*
G01X537424D01*
G02Y1451392I0J-1503D01*
G01X534024D01*
G37*
G36*
G01X520624D02*
G02Y1454398I0J1503D01*
G01X524024D01*
G02Y1451392I0J-1503D01*
G01X520624D01*
G37*
G36*
G01X397913D02*
G02Y1454398I0J1503D01*
G01X401313D01*
G02Y1451392I0J-1503D01*
G01X397913D01*
G37*
G36*
G01X371113Y1470792D02*
G02Y1473798I0J1503D01*
G01X374513D01*
G02Y1470792I0J-1503D01*
G01X371113D01*
G37*
G36*
G01X317513D02*
G02Y1473798I0J1503D01*
G01X320913D01*
G02Y1470792I0J-1503D01*
G01X317513D01*
G37*
G36*
G01X357713Y1451392D02*
G02Y1454398I0J1503D01*
G01X361113D01*
G02Y1451392I0J-1503D01*
G01X357713D01*
G37*
G36*
G01X1496393Y1623878D02*
G02Y1626882I0J1502D01*
G01X1499793D01*
G02Y1623878I0J-1502D01*
G01X1496393D01*
G37*
G36*
G01X1508453D02*
G02Y1626882I0J1502D01*
G01X1511853D01*
G02Y1623878I0J-1502D01*
G01X1508453D01*
G37*
G36*
G01X1322669Y1633878D02*
G02Y1636882I0J1502D01*
G01X1326069D01*
G02Y1633878I0J-1502D01*
G01X1322669D01*
G37*
G36*
G01X597059Y1590878D02*
G02Y1593882I0J1502D01*
G01X600459D01*
G02Y1590878I0J-1502D01*
G01X597059D01*
G37*
G36*
G01X476459Y1622790D02*
G02Y1625794I0J1502D01*
G01X479859D01*
G02Y1622790I0J-1502D01*
G01X476459D01*
G37*
G36*
G01X387598Y1533902D02*
G02X388658Y1534538I1060J-565D01*
G02X389860Y1533336I0J-1202D01*
G02X389700Y1532736I-1203J0D01*
G01X388155Y1530063D01*
X388153Y1530059D01*
G02X387083Y1529406I-1070J550D01*
G02X385880Y1530608I-1J1202D01*
G01Y1530610D01*
G02X386030Y1531189I1203J-3D01*
G01X387596Y1533899D01*
X387598Y1533902D01*
G37*
G36*
G01X382873D02*
G02X383933Y1534538I1060J-565D01*
G02X385136Y1533336I1J-1202D01*
G02X384975Y1532736I-1204J1D01*
G01X383430Y1530063D01*
X383428Y1530059D01*
G02X382358Y1529406I-1070J550D01*
G02X381156Y1530608I0J1202D01*
G01Y1530610D01*
G02X381305Y1531189I1202J-1D01*
G01X382871Y1533899D01*
X382873Y1533902D01*
G37*
G36*
G01X1215440Y1553264D02*
G02X1216500Y1553900I1060J-565D01*
G02X1217702Y1552698I0J-1202D01*
G02X1217542Y1552098I-1203J0D01*
G01X1215997Y1549425D01*
X1215995Y1549421D01*
G02X1214925Y1548768I-1070J550D01*
G02X1213722Y1549970I-1J1202D01*
G01Y1549972D01*
G02X1213872Y1550551I1203J-3D01*
G01X1215438Y1553261D01*
X1215440Y1553264D01*
G37*
G36*
G01X1220165D02*
G02X1221225Y1553900I1060J-565D01*
G02X1222428Y1552698I1J-1202D01*
G02X1222267Y1552098I-1204J1D01*
G01X1220722Y1549425D01*
X1220720Y1549421D01*
G02X1219650Y1548768I-1070J550D01*
G02X1218448Y1549970I0J1202D01*
G01Y1549972D01*
G02X1218597Y1550551I1202J-1D01*
G01X1220163Y1553261D01*
X1220165Y1553264D01*
G37*
G36*
G01X378149Y1533902D02*
G02X379209Y1534538I1060J-565D01*
G02X380412Y1533336I1J-1202D01*
G02X380251Y1532736I-1204J1D01*
G01X378706Y1530063D01*
X378704Y1530059D01*
G02X377634Y1529406I-1070J550D01*
G02X376432Y1530608I0J1202D01*
G01Y1530610D01*
G02X376581Y1531189I1202J-1D01*
G01X378147Y1533899D01*
X378149Y1533902D01*
G37*
G36*
G01X373424D02*
G02X374484Y1534538I1060J-565D01*
G02X375686Y1533336I0J-1202D01*
G02X375526Y1532736I-1203J0D01*
G01X373981Y1530063D01*
X373979Y1530059D01*
G02X372909Y1529406I-1070J550D01*
G02X371706Y1530608I-1J1202D01*
G01Y1530610D01*
G02X371856Y1531189I1203J-3D01*
G01X373422Y1533899D01*
X373424Y1533902D01*
G37*
G36*
G01X368700D02*
G02X369760Y1534538I1060J-565D01*
G02X370962Y1533336I0J-1202D01*
G02X370802Y1532736I-1203J0D01*
G01X369257Y1530063D01*
X369255Y1530059D01*
G02X368185Y1529406I-1070J550D01*
G02X366982Y1530608I-1J1202D01*
G01Y1530610D01*
G02X367132Y1531189I1203J-3D01*
G01X368698Y1533899D01*
X368700Y1533902D01*
G37*
G36*
G01X1224889Y1553264D02*
G02X1225949Y1553900I1060J-565D01*
G02X1227152Y1552698I1J-1202D01*
G02X1226991Y1552098I-1204J1D01*
G01X1225446Y1549425D01*
X1225444Y1549421D01*
G02X1224374Y1548768I-1070J550D01*
G02X1223172Y1549970I0J1202D01*
G01Y1549972D01*
G02X1223321Y1550551I1202J-1D01*
G01X1224887Y1553261D01*
X1224889Y1553264D01*
G37*
G36*
G01X1229614D02*
G02X1230674Y1553900I1060J-565D01*
G02X1231876Y1552698I0J-1202D01*
G02X1231716Y1552098I-1203J0D01*
G01X1230171Y1549425D01*
X1230169Y1549421D01*
G02X1229099Y1548768I-1070J550D01*
G02X1227896Y1549970I-1J1202D01*
G01Y1549972D01*
G02X1228046Y1550551I1203J-3D01*
G01X1229612Y1553261D01*
X1229614Y1553264D01*
G37*
G36*
G01X359251Y1533902D02*
G02X360311Y1534538I1060J-565D01*
G02X361514Y1533336I1J-1202D01*
G02X361353Y1532736I-1204J1D01*
G01X359808Y1530063D01*
X359806Y1530059D01*
G02X358736Y1529406I-1070J550D01*
G02X357534Y1530608I0J1202D01*
G01Y1530610D01*
G02X357683Y1531189I1202J-1D01*
G01X359249Y1533899D01*
X359251Y1533902D01*
G37*
G36*
G01X354527D02*
G02X355587Y1534538I1060J-565D01*
G02X356790Y1533336I1J-1202D01*
G02X356629Y1532736I-1204J1D01*
G01X355084Y1530063D01*
X355082Y1530059D01*
G02X354012Y1529406I-1070J550D01*
G02X352810Y1530608I0J1202D01*
G01Y1530610D01*
G02X352959Y1531189I1202J-1D01*
G01X354525Y1533899D01*
X354527Y1533902D01*
G37*
G36*
G01X363976D02*
G02X365036Y1534538I1060J-565D01*
G02X366238Y1533336I0J-1202D01*
G02X366078Y1532736I-1203J0D01*
G01X364533Y1530063D01*
X364531Y1530059D01*
G02X363461Y1529406I-1070J550D01*
G02X362258Y1530608I-1J1202D01*
G01Y1530610D01*
G02X362408Y1531189I1203J-3D01*
G01X363974Y1533899D01*
X363976Y1533902D01*
G37*
G36*
G01X1253236Y1553264D02*
G02X1254296Y1553900I1060J-565D01*
G02X1255498Y1552698I0J-1202D01*
G02X1255338Y1552098I-1203J0D01*
G01X1253793Y1549425D01*
X1253791Y1549421D01*
G02X1252721Y1548768I-1070J550D01*
G02X1251518Y1549970I-1J1202D01*
G01Y1549972D01*
G02X1251668Y1550551I1203J-3D01*
G01X1253234Y1553261D01*
X1253236Y1553264D01*
G37*
G36*
G01X349802Y1533902D02*
G02X350862Y1534538I1060J-565D01*
G02X352064Y1533336I0J-1202D01*
G02X351904Y1532736I-1203J0D01*
G01X350359Y1530063D01*
X350357Y1530059D01*
G02X349287Y1529406I-1070J550D01*
G02X348084Y1530608I-1J1202D01*
G01Y1530610D01*
G02X348234Y1531189I1203J-3D01*
G01X349800Y1533899D01*
X349802Y1533902D01*
G37*
G36*
G01X345078D02*
G02X346138Y1534538I1060J-565D01*
G02X347340Y1533336I0J-1202D01*
G02X347180Y1532736I-1203J0D01*
G01X345635Y1530063D01*
X345633Y1530059D01*
G02X344563Y1529406I-1070J550D01*
G02X343360Y1530608I-1J1202D01*
G01Y1530610D01*
G02X343510Y1531189I1203J-3D01*
G01X345076Y1533899D01*
X345078Y1533902D01*
G37*
G36*
G01X340354D02*
G02X341414Y1534538I1060J-565D01*
G02X342616Y1533336I0J-1202D01*
G02X342456Y1532736I-1203J0D01*
G01X340911Y1530063D01*
X340909Y1530059D01*
G02X339839Y1529406I-1070J550D01*
G02X338636Y1530608I-1J1202D01*
G01Y1530610D01*
G02X338786Y1531189I1203J-3D01*
G01X340352Y1533899D01*
X340354Y1533902D01*
G37*
G36*
G01X1262685Y1553264D02*
G02X1263745Y1553900I1060J-565D01*
G02X1264948Y1552698I1J-1202D01*
G02X1264787Y1552098I-1204J1D01*
G01X1263242Y1549425D01*
X1263240Y1549421D01*
G02X1262170Y1548768I-1070J550D01*
G02X1260968Y1549970I0J1202D01*
G01Y1549972D01*
G02X1261117Y1550551I1202J-1D01*
G01X1262683Y1553261D01*
X1262685Y1553264D01*
G37*
G36*
G01X335629Y1533902D02*
G02X336689Y1534538I1060J-565D01*
G02X337892Y1533336I1J-1202D01*
G02X337731Y1532736I-1204J1D01*
G01X336186Y1530063D01*
X336184Y1530059D01*
G02X335114Y1529406I-1070J550D01*
G02X333912Y1530608I0J1202D01*
G01Y1530610D01*
G02X334061Y1531189I1202J-1D01*
G01X335627Y1533899D01*
X335629Y1533902D01*
G37*
G36*
G01X330905D02*
G02X331965Y1534538I1060J-565D01*
G02X333168Y1533336I1J-1202D01*
G02X333007Y1532736I-1204J1D01*
G01X331462Y1530063D01*
X331460Y1530059D01*
G02X330390Y1529406I-1070J550D01*
G02X329188Y1530608I0J1202D01*
G01Y1530610D01*
G02X329337Y1531189I1202J-1D01*
G01X330903Y1533899D01*
X330905Y1533902D01*
G37*
G36*
G01X326180D02*
G02X327240Y1534538I1060J-565D01*
G02X328442Y1533336I0J-1202D01*
G02X328282Y1532736I-1203J0D01*
G01X326737Y1530063D01*
X326735Y1530059D01*
G02X325665Y1529406I-1070J550D01*
G02X324462Y1530608I-1J1202D01*
G01Y1530610D01*
G02X324612Y1531189I1203J-3D01*
G01X326178Y1533899D01*
X326180Y1533902D01*
G37*
G36*
G01X321456D02*
G02X322516Y1534538I1060J-565D01*
G02X323718Y1533336I0J-1202D01*
G02X323558Y1532736I-1203J0D01*
G01X322013Y1530063D01*
X322011Y1530059D01*
G02X320941Y1529406I-1070J550D01*
G02X319738Y1530608I-1J1202D01*
G01Y1530610D01*
G02X319888Y1531189I1203J-3D01*
G01X321454Y1533899D01*
X321456Y1533902D01*
G37*
G36*
G01X1329329Y1553264D02*
G02X1330389Y1553900I1060J-565D01*
G02X1331592Y1552698I1J-1202D01*
G02X1331431Y1552098I-1204J1D01*
G01X1329886Y1549425D01*
X1329884Y1549421D01*
G02X1328814Y1548768I-1070J550D01*
G02X1327612Y1549970I0J1202D01*
G01Y1549972D01*
G02X1327761Y1550551I1202J-1D01*
G01X1329327Y1553261D01*
X1329329Y1553264D01*
G37*
G36*
G01X316732Y1533902D02*
G02X317792Y1534538I1060J-565D01*
G02X318994Y1533336I0J-1202D01*
G02X318834Y1532736I-1203J0D01*
G01X317289Y1530063D01*
X317287Y1530059D01*
G02X316217Y1529406I-1070J550D01*
G02X315014Y1530608I-1J1202D01*
G01Y1530610D01*
G02X315164Y1531189I1203J-3D01*
G01X316730Y1533899D01*
X316732Y1533902D01*
G37*
G36*
G01X259536D02*
G02X260596Y1534538I1060J-565D01*
G02X261798Y1533336I0J-1202D01*
G02X261638Y1532736I-1203J0D01*
G01X260093Y1530063D01*
X260091Y1530059D01*
G02X259021Y1529406I-1070J550D01*
G02X257818Y1530608I-1J1202D01*
G01Y1530610D01*
G02X257968Y1531189I1203J-3D01*
G01X259534Y1533899D01*
X259536Y1533902D01*
G37*
G36*
G01X254811D02*
G02X255871Y1534538I1060J-565D01*
G02X257074Y1533336I1J-1202D01*
G02X256913Y1532736I-1204J1D01*
G01X255368Y1530063D01*
X255366Y1530059D01*
G02X254296Y1529406I-1070J550D01*
G02X253094Y1530608I0J1202D01*
G01Y1530610D01*
G02X253243Y1531189I1202J-1D01*
G01X254809Y1533899D01*
X254811Y1533902D01*
G37*
G36*
G01X250087D02*
G02X251147Y1534538I1060J-565D01*
G02X252350Y1533336I1J-1202D01*
G02X252189Y1532736I-1204J1D01*
G01X250644Y1530063D01*
X250642Y1530059D01*
G02X249572Y1529406I-1070J550D01*
G02X248370Y1530608I0J1202D01*
G01Y1530610D01*
G02X248519Y1531189I1202J-1D01*
G01X250085Y1533899D01*
X250087Y1533902D01*
G37*
G36*
G01X245362D02*
G02X246422Y1534538I1060J-565D01*
G02X247624Y1533336I0J-1202D01*
G02X247464Y1532736I-1203J0D01*
G01X245919Y1530063D01*
X245917Y1530059D01*
G02X244847Y1529406I-1070J550D01*
G02X243644Y1530608I-1J1202D01*
G01Y1530610D01*
G02X243794Y1531189I1203J-3D01*
G01X245360Y1533899D01*
X245362Y1533902D01*
G37*
G36*
G01X240638D02*
G02X241698Y1534538I1060J-565D01*
G02X242900Y1533336I0J-1202D01*
G02X242740Y1532736I-1203J0D01*
G01X241195Y1530063D01*
X241193Y1530059D01*
G02X240123Y1529406I-1070J550D01*
G02X238920Y1530608I-1J1202D01*
G01Y1530610D01*
G02X239070Y1531189I1203J-3D01*
G01X240636Y1533899D01*
X240638Y1533902D01*
G37*
G36*
G01X235914D02*
G02X236974Y1534538I1060J-565D01*
G02X238176Y1533336I0J-1202D01*
G02X238016Y1532736I-1203J0D01*
G01X236471Y1530063D01*
X236469Y1530059D01*
G02X235399Y1529406I-1070J550D01*
G02X234196Y1530608I-1J1202D01*
G01Y1530610D01*
G02X234346Y1531189I1203J-3D01*
G01X235912Y1533899D01*
X235914Y1533902D01*
G37*
G36*
G01X231189D02*
G02X232249Y1534538I1060J-565D01*
G02X233452Y1533336I1J-1202D01*
G02X233291Y1532736I-1204J1D01*
G01X231746Y1530063D01*
X231744Y1530059D01*
G02X230674Y1529406I-1070J550D01*
G02X229472Y1530608I0J1202D01*
G01Y1530610D01*
G02X229621Y1531189I1202J-1D01*
G01X231187Y1533899D01*
X231189Y1533902D01*
G37*
G36*
G01X226465D02*
G02X227525Y1534538I1060J-565D01*
G02X228728Y1533336I1J-1202D01*
G02X228567Y1532736I-1204J1D01*
G01X227022Y1530063D01*
X227020Y1530059D01*
G02X225950Y1529406I-1070J550D01*
G02X224748Y1530608I0J1202D01*
G01Y1530610D01*
G02X224897Y1531189I1202J-1D01*
G01X226463Y1533899D01*
X226465Y1533902D01*
G37*
G36*
G01X221740D02*
G02X222800Y1534538I1060J-565D01*
G02X224002Y1533336I0J-1202D01*
G02X223842Y1532736I-1203J0D01*
G01X222297Y1530063D01*
X222295Y1530059D01*
G02X221225Y1529406I-1070J550D01*
G02X220022Y1530608I-1J1202D01*
G01Y1530610D01*
G02X220172Y1531189I1203J-3D01*
G01X221738Y1533899D01*
X221740Y1533902D01*
G37*
G36*
G01X1324605Y1553264D02*
G02X1325665Y1553900I1060J-565D01*
G02X1326868Y1552698I1J-1202D01*
G02X1326707Y1552098I-1204J1D01*
G01X1325162Y1549425D01*
X1325160Y1549421D01*
G02X1324090Y1548768I-1070J550D01*
G02X1322888Y1549970I0J1202D01*
G01Y1549972D01*
G02X1323037Y1550551I1202J-1D01*
G01X1324603Y1553261D01*
X1324605Y1553264D01*
G37*
G36*
G01X217016Y1533902D02*
G02X218076Y1534538I1060J-565D01*
G02X219278Y1533336I0J-1202D01*
G02X219118Y1532736I-1203J0D01*
G01X217573Y1530063D01*
X217571Y1530059D01*
G02X216501Y1529406I-1070J550D01*
G02X215298Y1530608I-1J1202D01*
G01Y1530610D01*
G02X215448Y1531189I1203J-3D01*
G01X217014Y1533899D01*
X217016Y1533902D01*
G37*
G36*
G01X212292D02*
G02X213352Y1534538I1060J-565D01*
G02X214554Y1533336I0J-1202D01*
G02X214394Y1532736I-1203J0D01*
G01X212849Y1530063D01*
X212847Y1530059D01*
G02X211777Y1529406I-1070J550D01*
G02X210574Y1530608I-1J1202D01*
G01Y1530610D01*
G02X210724Y1531189I1203J-3D01*
G01X212290Y1533899D01*
X212292Y1533902D01*
G37*
G36*
G01X207567D02*
G02X208627Y1534538I1060J-565D01*
G02X209830Y1533336I1J-1202D01*
G02X209669Y1532736I-1204J1D01*
G01X208124Y1530063D01*
X208122Y1530059D01*
G02X207052Y1529406I-1070J550D01*
G02X205850Y1530608I0J1202D01*
G01Y1530610D01*
G02X205999Y1531189I1202J-1D01*
G01X207565Y1533899D01*
X207567Y1533902D01*
G37*
G36*
G01X202843D02*
G02X203903Y1534538I1060J-565D01*
G02X205106Y1533336I1J-1202D01*
G02X204945Y1532736I-1204J1D01*
G01X203400Y1530063D01*
X203398Y1530059D01*
G02X202328Y1529406I-1070J550D01*
G02X201126Y1530608I0J1202D01*
G01Y1530610D01*
G02X201275Y1531189I1202J-1D01*
G01X202841Y1533899D01*
X202843Y1533902D01*
G37*
G36*
G01X198118D02*
G02X199178Y1534538I1060J-565D01*
G02X200380Y1533336I0J-1202D01*
G02X200220Y1532736I-1203J0D01*
G01X198675Y1530063D01*
X198673Y1530059D01*
G02X197603Y1529406I-1070J550D01*
G02X196400Y1530608I-1J1202D01*
G01Y1530610D01*
G02X196550Y1531189I1203J-3D01*
G01X198116Y1533899D01*
X198118Y1533902D01*
G37*
G36*
G01X193394D02*
G02X194454Y1534538I1060J-565D01*
G02X195656Y1533336I0J-1202D01*
G02X195496Y1532736I-1203J0D01*
G01X193951Y1530063D01*
X193949Y1530059D01*
G02X192879Y1529406I-1070J550D01*
G02X191676Y1530608I-1J1202D01*
G01Y1530610D01*
G02X191826Y1531189I1203J-3D01*
G01X193392Y1533899D01*
X193394Y1533902D01*
G37*
G36*
G01X188670D02*
G02X189730Y1534538I1060J-565D01*
G02X190932Y1533336I0J-1202D01*
G02X190772Y1532736I-1203J0D01*
G01X189227Y1530063D01*
X189225Y1530059D01*
G02X188155Y1529406I-1070J550D01*
G02X186952Y1530608I-1J1202D01*
G01Y1530610D01*
G02X187102Y1531189I1203J-3D01*
G01X188668Y1533899D01*
X188670Y1533902D01*
G37*
G36*
G01X1334054Y1553264D02*
G02X1335114Y1553900I1060J-565D01*
G02X1336316Y1552698I0J-1202D01*
G02X1336156Y1552098I-1203J0D01*
G01X1334611Y1549425D01*
X1334609Y1549421D01*
G02X1333539Y1548768I-1070J550D01*
G02X1332336Y1549970I-1J1202D01*
G01Y1549972D01*
G02X1332486Y1550551I1203J-3D01*
G01X1334052Y1553261D01*
X1334054Y1553264D01*
G37*
G36*
G01X1610963Y1633878D02*
G02Y1636882I0J1502D01*
G01X1614363D01*
G02Y1633878I0J-1502D01*
G01X1610963D01*
G37*
G36*
G01X1598903D02*
G02Y1636882I0J1502D01*
G01X1602303D01*
G02Y1633878I0J-1502D01*
G01X1598903D01*
G37*
G36*
G01X1586843D02*
G02Y1636882I0J1502D01*
G01X1590243D01*
G02Y1633878I0J-1502D01*
G01X1586843D01*
G37*
G36*
G01X1641113Y1655790D02*
G02Y1658794I0J1502D01*
G01X1644513D01*
G02Y1655790I0J-1502D01*
G01X1641113D01*
G37*
G36*
G01X1574783Y1633878D02*
G02Y1636882I0J1502D01*
G01X1578183D01*
G02Y1633878I0J-1502D01*
G01X1574783D01*
G37*
G36*
G01X1562723D02*
G02Y1636882I0J1502D01*
G01X1566123D01*
G02Y1633878I0J-1502D01*
G01X1562723D01*
G37*
G36*
G01X1592873Y1623878D02*
G02Y1626882I0J1502D01*
G01X1596273D01*
G02Y1623878I0J-1502D01*
G01X1592873D01*
G37*
G36*
G01X1550663Y1633878D02*
G02Y1636882I0J1502D01*
G01X1554063D01*
G02Y1633878I0J-1502D01*
G01X1550663D01*
G37*
G36*
G01X1580813Y1623878D02*
G02Y1626882I0J1502D01*
G01X1584213D01*
G02Y1623878I0J-1502D01*
G01X1580813D01*
G37*
G36*
G01X1538603Y1633878D02*
G02Y1636882I0J1502D01*
G01X1542003D01*
G02Y1633878I0J-1502D01*
G01X1538603D01*
G37*
G36*
G01X1568753Y1623878D02*
G02Y1626882I0J1502D01*
G01X1572153D01*
G02Y1623878I0J-1502D01*
G01X1568753D01*
G37*
G36*
G01X1526543Y1633878D02*
G02Y1636882I0J1502D01*
G01X1529943D01*
G02Y1633878I0J-1502D01*
G01X1526543D01*
G37*
G36*
G01X1514483D02*
G02Y1636882I0J1502D01*
G01X1517883D01*
G02Y1633878I0J-1502D01*
G01X1514483D01*
G37*
G36*
G01X1478303D02*
G02Y1636882I0J1502D01*
G01X1481703D01*
G02Y1633878I0J-1502D01*
G01X1478303D01*
G37*
G36*
G01X1466243D02*
G02Y1636882I0J1502D01*
G01X1469643D01*
G02Y1633878I0J-1502D01*
G01X1466243D01*
G37*
G36*
G01X1370909Y1645790D02*
G02Y1648794I0J1502D01*
G01X1374309D01*
G02Y1645790I0J-1502D01*
G01X1370909D01*
G37*
G36*
G01X1352819Y1655790D02*
G02Y1658794I0J1502D01*
G01X1356219D01*
G02Y1655790I0J-1502D01*
G01X1352819D01*
G37*
G36*
G01X1298549Y1633878D02*
G02Y1636882I0J1502D01*
G01X1301949D01*
G02Y1633878I0J-1502D01*
G01X1298549D01*
G37*
G36*
G01X1286489D02*
G02Y1636882I0J1502D01*
G01X1289889D01*
G02Y1633878I0J-1502D01*
G01X1286489D01*
G37*
G36*
G01X1238249D02*
G02Y1636882I0J1502D01*
G01X1241649D01*
G02Y1633878I0J-1502D01*
G01X1238249D01*
G37*
G36*
G01X1250309D02*
G02Y1636882I0J1502D01*
G01X1253709D01*
G02Y1633878I0J-1502D01*
G01X1250309D01*
G37*
G36*
G01X1280459Y1655790D02*
G02Y1658794I0J1502D01*
G01X1283859D01*
G02Y1655790I0J-1502D01*
G01X1280459D01*
G37*
G36*
G01X1214129Y1633878D02*
G02Y1636882I0J1502D01*
G01X1217529D01*
G02Y1633878I0J-1502D01*
G01X1214129D01*
G37*
G36*
G01X1226189Y1645790D02*
G02Y1648794I0J1502D01*
G01X1229589D01*
G02Y1645790I0J-1502D01*
G01X1226189D01*
G37*
G36*
G01Y1633878D02*
G02Y1636882I0J1502D01*
G01X1229589D01*
G02Y1633878I0J-1502D01*
G01X1226189D01*
G37*
G36*
G01X1202069Y1645790D02*
G02Y1648794I0J1502D01*
G01X1205469D01*
G02Y1645790I0J-1502D01*
G01X1202069D01*
G37*
G36*
G01X1220159Y1655790D02*
G02Y1658794I0J1502D01*
G01X1223559D01*
G02Y1655790I0J-1502D01*
G01X1220159D01*
G37*
G36*
G01X1208099D02*
G02Y1658794I0J1502D01*
G01X1211499D01*
G02Y1655790I0J-1502D01*
G01X1208099D01*
G37*
G36*
G01Y1623878D02*
G02Y1626882I0J1502D01*
G01X1211499D01*
G02Y1623878I0J-1502D01*
G01X1208099D01*
G37*
G36*
G01X1256339D02*
G02Y1626882I0J1502D01*
G01X1259739D01*
G02Y1623878I0J-1502D01*
G01X1256339D01*
G37*
G36*
G01X591029Y1600878D02*
G02Y1603882I0J1502D01*
G01X594429D01*
G02Y1600878I0J-1502D01*
G01X591029D01*
G37*
G36*
G01X1196039Y1623878D02*
G02Y1626882I0J1502D01*
G01X1199439D01*
G02Y1623878I0J-1502D01*
G01X1196039D01*
G37*
G36*
G01X554849Y1612790D02*
G02Y1615794I0J1502D01*
G01X558249D01*
G02Y1612790I0J-1502D01*
G01X554849D01*
G37*
G36*
G01X584999Y1622790D02*
G02Y1625794I0J1502D01*
G01X588399D01*
G02Y1622790I0J-1502D01*
G01X584999D01*
G37*
G36*
G01X542789Y1600878D02*
G02Y1603882I0J1502D01*
G01X546189D01*
G02Y1600878I0J-1502D01*
G01X542789D01*
G37*
G36*
G01X494549D02*
G02Y1603882I0J1502D01*
G01X497949D01*
G02Y1600878I0J-1502D01*
G01X494549D01*
G37*
G36*
G01Y1612790D02*
G02Y1615794I0J1502D01*
G01X497949D01*
G02Y1612790I0J-1502D01*
G01X494549D01*
G37*
G36*
G01X482489D02*
G02Y1615794I0J1502D01*
G01X485889D01*
G02Y1612790I0J-1502D01*
G01X482489D01*
G37*
G36*
G01X461769Y1603882D02*
G02Y1600878I0J-1502D01*
G01X458369D01*
G02Y1603882I0J1502D01*
G01X461769D01*
G37*
G36*
G01X476459Y1590878D02*
G02Y1593882I0J1502D01*
G01X479859D01*
G02Y1590878I0J-1502D01*
G01X476459D01*
G37*
G36*
G01X464399Y1622790D02*
G02Y1625794I0J1502D01*
G01X467799D01*
G02Y1622790I0J-1502D01*
G01X464399D01*
G37*
G36*
G01X452339Y1590878D02*
G02Y1593882I0J1502D01*
G01X455739D01*
G02Y1590878I0J-1502D01*
G01X452339D01*
G37*
G36*
G01X375096Y1600878D02*
G02Y1603882I0J1502D01*
G01X378496D01*
G02Y1600878I0J-1502D01*
G01X375096D01*
G37*
G36*
G01X357006Y1590878D02*
G02Y1593882I0J1502D01*
G01X360406D01*
G02Y1590878I0J-1502D01*
G01X357006D01*
G37*
G36*
G01X314796Y1612790D02*
G02Y1615794I0J1502D01*
G01X318196D01*
G02Y1612790I0J-1502D01*
G01X314796D01*
G37*
G36*
G01X302736Y1600878D02*
G02Y1603882I0J1502D01*
G01X306136D01*
G02Y1600878I0J-1502D01*
G01X302736D01*
G37*
G36*
G01X272586Y1590878D02*
G02Y1593882I0J1502D01*
G01X275986D01*
G02Y1590878I0J-1502D01*
G01X272586D01*
G37*
G36*
G01X266556Y1612790D02*
G02Y1615794I0J1502D01*
G01X269956D01*
G02Y1612790I0J-1502D01*
G01X266556D01*
G37*
G36*
G01X254496D02*
G02Y1615794I0J1502D01*
G01X257896D01*
G02Y1612790I0J-1502D01*
G01X254496D01*
G37*
G36*
G01X218316D02*
G02Y1615794I0J1502D01*
G01X221716D01*
G02Y1612790I0J-1502D01*
G01X218316D01*
G37*
G36*
G01X212286Y1622790D02*
G02Y1625794I0J1502D01*
G01X215686D01*
G02Y1622790I0J-1502D01*
G01X212286D01*
G37*
G36*
G01X578969Y1612790D02*
G02Y1615794I0J1502D01*
G01X582369D01*
G02Y1612790I0J-1502D01*
G01X578969D01*
G37*
G36*
G01X1340759Y1655790D02*
G02Y1658794I0J1502D01*
G01X1344159D01*
G02Y1655790I0J-1502D01*
G01X1340759D01*
G37*
G36*
G01X1328699D02*
G02Y1658794I0J1502D01*
G01X1332099D01*
G02Y1655790I0J-1502D01*
G01X1328699D01*
G37*
G36*
G01X304113Y1451392D02*
G02Y1454398I0J1503D01*
G01X307513D01*
G02Y1451392I0J-1503D01*
G01X304113D01*
G37*
G36*
G01X324213Y1461092D02*
G02Y1464098I0J1503D01*
G01X327613D01*
G02Y1461092I0J-1503D01*
G01X324213D01*
G37*
G36*
G01X338916Y1612790D02*
G02Y1615794I0J1502D01*
G01X342316D01*
G02Y1612790I0J-1502D01*
G01X338916D01*
G37*
G36*
G01X169351Y1461092D02*
G02Y1464098I0J1503D01*
G01X172751D01*
G02Y1461092I0J-1503D01*
G01X169351D01*
G37*
G36*
G01X350976Y1612790D02*
G02Y1615794I0J1502D01*
G01X354376D01*
G02Y1612790I0J-1502D01*
G01X350976D01*
G37*
G36*
G01X641986Y1461092D02*
G02Y1464098I0J1503D01*
G01X645386D01*
G02Y1461092I0J-1503D01*
G01X641986D01*
G37*
G36*
G01X230376Y1612790D02*
G02Y1615794I0J1502D01*
G01X233776D01*
G02Y1612790I0J-1502D01*
G01X230376D01*
G37*
G36*
G01X344313Y1470792D02*
G02Y1473798I0J1503D01*
G01X347713D01*
G02Y1470792I0J-1503D01*
G01X344313D01*
G37*
G36*
G01X1232219Y1623878D02*
G02Y1626882I0J1502D01*
G01X1235619D01*
G02Y1623878I0J-1502D01*
G01X1232219D01*
G37*
G36*
G01X1629053D02*
G02Y1626882I0J1502D01*
G01X1632453D01*
G02Y1623878I0J-1502D01*
G01X1629053D01*
G37*
G36*
G01X1364879D02*
G02Y1626882I0J1502D01*
G01X1368279D01*
G02Y1623878I0J-1502D01*
G01X1364879D01*
G37*
G36*
G01X363036Y1612790D02*
G02Y1615794I0J1502D01*
G01X366436D01*
G02Y1612790I0J-1502D01*
G01X363036D01*
G37*
G36*
G01X648686Y1451392D02*
G02Y1454398I0J1503D01*
G01X652086D01*
G02Y1451392I0J-1503D01*
G01X648686D01*
G37*
G36*
G01X221740Y1520264D02*
G02X222800Y1520900I1060J-565D01*
G02X224002Y1519698I0J-1202D01*
G02X223842Y1519098I-1203J0D01*
G01X222297Y1516425D01*
X222295Y1516421D01*
G02X221225Y1515768I-1070J550D01*
G02X220022Y1516970I-1J1202D01*
G01Y1516972D01*
G02X220172Y1517551I1203J-3D01*
G01X221738Y1520261D01*
X221740Y1520264D01*
G37*
G36*
G01X1392386Y1484392D02*
G02Y1487398I0J1503D01*
G01X1395786D01*
G02Y1484392I0J-1503D01*
G01X1392386D01*
G37*
G36*
G01X480424Y1470792D02*
G02Y1473798I0J1503D01*
G01X483824D01*
G02Y1470792I0J-1503D01*
G01X480424D01*
G37*
G36*
G01X1334729Y1645790D02*
G02Y1648794I0J1502D01*
G01X1338129D01*
G02Y1645790I0J-1502D01*
G01X1334729D01*
G37*
G36*
G01X1322669D02*
G02Y1648794I0J1502D01*
G01X1326069D01*
G02Y1645790I0J-1502D01*
G01X1322669D01*
G37*
G36*
G01X1310609D02*
G02Y1648794I0J1502D01*
G01X1314009D01*
G02Y1645790I0J-1502D01*
G01X1310609D01*
G37*
G36*
G01X1316639Y1655790D02*
G02Y1658794I0J1502D01*
G01X1320039D01*
G02Y1655790I0J-1502D01*
G01X1316639D01*
G37*
G36*
G01X1304579D02*
G02Y1658794I0J1502D01*
G01X1307979D01*
G02Y1655790I0J-1502D01*
G01X1304579D01*
G37*
G36*
G01X1292519Y1623878D02*
G02Y1626882I0J1502D01*
G01X1295919D01*
G02Y1623878I0J-1502D01*
G01X1292519D01*
G37*
G36*
G01X1280459D02*
G02Y1626882I0J1502D01*
G01X1283859D01*
G02Y1623878I0J-1502D01*
G01X1280459D01*
G37*
G36*
G01X1268399Y1655790D02*
G02Y1658794I0J1502D01*
G01X1271799D01*
G02Y1655790I0J-1502D01*
G01X1268399D01*
G37*
G36*
G01X1256339D02*
G02Y1658794I0J1502D01*
G01X1259739D01*
G02Y1655790I0J-1502D01*
G01X1256339D01*
G37*
G36*
G01X1244279D02*
G02Y1658794I0J1502D01*
G01X1247679D01*
G02Y1655790I0J-1502D01*
G01X1244279D01*
G37*
G36*
G01X1232219D02*
G02Y1658794I0J1502D01*
G01X1235619D01*
G02Y1655790I0J-1502D01*
G01X1232219D01*
G37*
G36*
G01X1460213D02*
G02Y1658794I0J1502D01*
G01X1463613D01*
G02Y1655790I0J-1502D01*
G01X1460213D01*
G37*
G36*
G01X357006Y1622790D02*
G02Y1625794I0J1502D01*
G01X360406D01*
G02Y1622790I0J-1502D01*
G01X357006D01*
G37*
G36*
G01X1616993Y1623878D02*
G02Y1626882I0J1502D01*
G01X1620393D01*
G02Y1623878I0J-1502D01*
G01X1616993D01*
G37*
G36*
G01X1515098Y1503792D02*
G02Y1506798I0J1503D01*
G01X1518498D01*
G02Y1503792I0J-1503D01*
G01X1515098D01*
G37*
G36*
G01X588386Y1461092D02*
G02Y1464098I0J1503D01*
G01X591786D01*
G02Y1461092I0J-1503D01*
G01X588386D01*
G37*
G36*
G01X561586D02*
G02Y1464098I0J1503D01*
G01X564986D01*
G02Y1461092I0J-1503D01*
G01X561586D01*
G37*
G36*
G01X1340759Y1623878D02*
G02Y1626882I0J1502D01*
G01X1344159D01*
G02Y1623878I0J-1502D01*
G01X1340759D01*
G37*
G36*
G01X1659960Y1487398D02*
G02Y1484392I0J-1503D01*
G01X1656560D01*
G02Y1487398I0J1503D01*
G01X1659960D01*
G37*
G36*
G01X1488298Y1503792D02*
G02Y1506798I0J1503D01*
G01X1491698D01*
G02Y1503792I0J-1503D01*
G01X1488298D01*
G37*
G36*
G01X635286Y1470792D02*
G02Y1473798I0J1503D01*
G01X638686D01*
G02Y1470792I0J-1503D01*
G01X635286D01*
G37*
G36*
G01X1647143Y1633878D02*
G02Y1636882I0J1502D01*
G01X1650543D01*
G02Y1633878I0J-1502D01*
G01X1647143D01*
G37*
G36*
G01X1352819Y1623878D02*
G02Y1626882I0J1502D01*
G01X1356219D01*
G02Y1623878I0J-1502D01*
G01X1352819D01*
G37*
G36*
G01X536759Y1622790D02*
G02Y1625794I0J1502D01*
G01X540159D01*
G02Y1622790I0J-1502D01*
G01X536759D01*
G37*
G36*
G01X332886Y1590878D02*
G02Y1593882I0J1502D01*
G01X336286D01*
G02Y1590878I0J-1502D01*
G01X332886D01*
G37*
G36*
G01X512639D02*
G02Y1593882I0J1502D01*
G01X516039D01*
G02Y1590878I0J-1502D01*
G01X512639D01*
G37*
G36*
G01X522069Y1603882D02*
G02Y1600878I0J-1502D01*
G01X518669D01*
G02Y1603882I0J1502D01*
G01X522069D01*
G37*
G36*
G01X603089Y1600878D02*
G02Y1603882I0J1502D01*
G01X606489D01*
G02Y1600878I0J-1502D01*
G01X603089D01*
G37*
G36*
G01X1472273Y1623878D02*
G02Y1626882I0J1502D01*
G01X1475673D01*
G02Y1623878I0J-1502D01*
G01X1472273D01*
G37*
G36*
G01X1304579D02*
G02Y1626882I0J1502D01*
G01X1307979D01*
G02Y1623878I0J-1502D01*
G01X1304579D01*
G37*
G36*
G01X297413Y1461092D02*
G02Y1464098I0J1503D01*
G01X300813D01*
G02Y1461092I0J-1503D01*
G01X297413D01*
G37*
G36*
G01X493824Y1451392D02*
G02Y1454398I0J1503D01*
G01X497224D01*
G02Y1451392I0J-1503D01*
G01X493824D01*
G37*
G36*
G01X1544633Y1623878D02*
G02Y1626882I0J1502D01*
G01X1548033D01*
G02Y1623878I0J-1502D01*
G01X1544633D01*
G37*
G36*
G01X530729Y1600878D02*
G02Y1603882I0J1502D01*
G01X534129D01*
G02Y1600878I0J-1502D01*
G01X530729D01*
G37*
G36*
G01X1177224Y1494092D02*
G02Y1497098I0J1503D01*
G01X1180624D01*
G02Y1494092I0J-1503D01*
G01X1177224D01*
G37*
G36*
G01X440224Y1451392D02*
G02Y1454398I0J1503D01*
G01X443624D01*
G02Y1451392I0J-1503D01*
G01X440224D01*
G37*
G36*
G01X1520513Y1623878D02*
G02Y1626882I0J1502D01*
G01X1523913D01*
G02Y1623878I0J-1502D01*
G01X1520513D01*
G37*
G36*
G01X1316639D02*
G02Y1626882I0J1502D01*
G01X1320039D01*
G02Y1623878I0J-1502D01*
G01X1316639D01*
G37*
G36*
G01X595086Y1451392D02*
G02Y1454398I0J1503D01*
G01X598486D01*
G02Y1451392I0J-1503D01*
G01X595086D01*
G37*
G36*
G01X568286D02*
G02Y1454398I0J1503D01*
G01X571686D01*
G02Y1451392I0J-1503D01*
G01X568286D01*
G37*
G36*
G01X581686Y1470792D02*
G02Y1473798I0J1503D01*
G01X585086D01*
G02Y1470792I0J-1503D01*
G01X581686D01*
G37*
G36*
G01X1604933Y1623878D02*
G02Y1626882I0J1502D01*
G01X1608333D01*
G02Y1623878I0J-1502D01*
G01X1604933D01*
G37*
G36*
G01X296706Y1590878D02*
G02Y1593882I0J1502D01*
G01X300106D01*
G02Y1590878I0J-1502D01*
G01X296706D01*
G37*
G36*
G01X218316Y1600878D02*
G02Y1603882I0J1502D01*
G01X221716D01*
G02Y1600878I0J-1502D01*
G01X218316D01*
G37*
G36*
G01X278616D02*
G02Y1603882I0J1502D01*
G01X282016D01*
G02Y1600878I0J-1502D01*
G01X278616D01*
G37*
G36*
G01X326856D02*
G02Y1603882I0J1502D01*
G01X330256D01*
G02Y1600878I0J-1502D01*
G01X326856D01*
G37*
G36*
G01X338916D02*
G02Y1603882I0J1502D01*
G01X342316D01*
G02Y1600878I0J-1502D01*
G01X338916D01*
G37*
G36*
G01X363036D02*
G02Y1603882I0J1502D01*
G01X366436D01*
G02Y1600878I0J-1502D01*
G01X363036D01*
G37*
G36*
G01X578969D02*
G02Y1603882I0J1502D01*
G01X582369D01*
G02Y1600878I0J-1502D01*
G01X578969D01*
G37*
G36*
G01X1382969Y1633878D02*
G02Y1636882I0J1502D01*
G01X1386369D01*
G02Y1633878I0J-1502D01*
G01X1382969D01*
G37*
G36*
G01X1224124Y1503792D02*
G02Y1506798I0J1503D01*
G01X1227524D01*
G02Y1503792I0J-1503D01*
G01X1224124D01*
G37*
G36*
G01X460324Y1461092D02*
G02Y1464098I0J1503D01*
G01X463724D01*
G02Y1461092I0J-1503D01*
G01X460324D01*
G37*
G36*
G01X1484333Y1623878D02*
G02Y1626882I0J1502D01*
G01X1487733D01*
G02Y1623878I0J-1502D01*
G01X1484333D01*
G37*
G36*
G01X560879Y1590878D02*
G02Y1593882I0J1502D01*
G01X564279D01*
G02Y1590878I0J-1502D01*
G01X560879D01*
G37*
G36*
G01X1325386Y1503792D02*
G02Y1506798I0J1503D01*
G01X1328786D01*
G02Y1503792I0J-1503D01*
G01X1325386D01*
G37*
G36*
G01X1257624Y1494092D02*
G02Y1497098I0J1503D01*
G01X1261024D01*
G02Y1494092I0J-1503D01*
G01X1257624D01*
G37*
G36*
G01X1596260D02*
G02Y1497098I0J1503D01*
G01X1599660D01*
G02Y1494092I0J-1503D01*
G01X1596260D01*
G37*
G36*
G01X1328699Y1623878D02*
G02Y1626882I0J1502D01*
G01X1332099D01*
G02Y1623878I0J-1502D01*
G01X1328699D01*
G37*
G36*
G01X1202069Y1633878D02*
G02Y1636882I0J1502D01*
G01X1205469D01*
G02Y1633878I0J-1502D01*
G01X1202069D01*
G37*
G36*
G01X464399Y1590878D02*
G02Y1593882I0J1502D01*
G01X467799D01*
G02Y1590878I0J-1502D01*
G01X464399D01*
G37*
G36*
G01X1441398Y1494092D02*
G02Y1497098I0J1503D01*
G01X1444798D01*
G02Y1494092I0J-1503D01*
G01X1441398D01*
G37*
G36*
G01X1623060D02*
G02Y1497098I0J1503D01*
G01X1626460D01*
G02Y1494092I0J-1503D01*
G01X1623060D01*
G37*
G36*
G01X1646560Y1506798D02*
G02Y1503792I0J-1503D01*
G01X1643160D01*
G02Y1506798I0J1503D01*
G01X1646560D01*
G37*
G36*
G01X1576160Y1484392D02*
G02Y1487398I0J1503D01*
G01X1579560D01*
G02Y1484392I0J-1503D01*
G01X1576160D01*
G37*
G36*
G01X1268399Y1623878D02*
G02Y1626882I0J1502D01*
G01X1271799D01*
G02Y1623878I0J-1502D01*
G01X1268399D01*
G37*
G36*
G01X1292519Y1655790D02*
G02Y1658794I0J1502D01*
G01X1295919D01*
G02Y1655790I0J-1502D01*
G01X1292519D01*
G37*
G36*
G01X513924Y1461092D02*
G02Y1464098I0J1503D01*
G01X517324D01*
G02Y1461092I0J-1503D01*
G01X513924D01*
G37*
G36*
G01X1197324Y1503792D02*
G02Y1506798I0J1503D01*
G01X1200724D01*
G02Y1503792I0J-1503D01*
G01X1197324D01*
G37*
G36*
G01X608486Y1470792D02*
G02Y1473798I0J1503D01*
G01X611886D01*
G02Y1470792I0J-1503D01*
G01X608486D01*
G37*
G36*
G01X1358886Y1494092D02*
G02Y1497098I0J1503D01*
G01X1362286D01*
G02Y1494092I0J-1503D01*
G01X1358886D01*
G37*
G36*
G01X1448098Y1484392D02*
G02Y1487398I0J1503D01*
G01X1451498D01*
G02Y1484392I0J-1503D01*
G01X1448098D01*
G37*
G36*
G01X1244279Y1623878D02*
G02Y1626882I0J1502D01*
G01X1247679D01*
G02Y1623878I0J-1502D01*
G01X1244279D01*
G37*
G36*
G01X1250924Y1503792D02*
G02Y1506798I0J1503D01*
G01X1254324D01*
G02Y1503792I0J-1503D01*
G01X1250924D01*
G37*
G36*
G01X500087Y1520264D02*
G02X501147Y1520900I1060J-565D01*
G02X502350Y1519698I1J-1202D01*
G02X502189Y1519098I-1204J1D01*
G01X500644Y1516425D01*
X500642Y1516421D01*
G02X499572Y1515768I-1070J550D01*
G02X498370Y1516970I0J1202D01*
G01Y1516972D01*
G02X498519Y1517551I1202J-1D01*
G01X500085Y1520261D01*
X500087Y1520264D01*
G37*
G36*
G01X1653260Y1497098D02*
G02Y1494092I0J-1503D01*
G01X1649860D01*
G02Y1497098I0J1503D01*
G01X1653260D01*
G37*
G36*
G01X1230824Y1494092D02*
G02Y1497098I0J1503D01*
G01X1234224D01*
G02Y1494092I0J-1503D01*
G01X1230824D01*
G37*
G36*
G01X202843Y1520264D02*
G02X203903Y1520900I1060J-565D01*
G02X205106Y1519698I1J-1202D01*
G02X204945Y1519098I-1204J1D01*
G01X203400Y1516425D01*
X203398Y1516421D01*
G02X202328Y1515768I-1070J550D01*
G02X201126Y1516970I0J1202D01*
G01Y1516972D01*
G02X201275Y1517551I1202J-1D01*
G01X202841Y1520261D01*
X202843Y1520264D01*
G37*
G36*
G01X467024Y1451392D02*
G02Y1454398I0J1503D01*
G01X470424D01*
G02Y1451392I0J-1503D01*
G01X467024D01*
G37*
G36*
G01X1589560Y1503792D02*
G02Y1506798I0J1503D01*
G01X1592960D01*
G02Y1503792I0J-1503D01*
G01X1589560D01*
G37*
G36*
G01X1616360D02*
G02Y1506798I0J1503D01*
G01X1619760D01*
G02Y1503792I0J-1503D01*
G01X1616360D01*
G37*
G36*
G01X1460213Y1623878D02*
G02Y1626882I0J1502D01*
G01X1463613D01*
G02Y1623878I0J-1502D01*
G01X1460213D01*
G37*
G36*
G01X1521798Y1494092D02*
G02Y1497098I0J1503D01*
G01X1525198D01*
G02Y1494092I0J-1503D01*
G01X1521798D01*
G37*
G36*
G01X487124Y1461092D02*
G02Y1464098I0J1503D01*
G01X490524D01*
G02Y1461092I0J-1503D01*
G01X487124D01*
G37*
G36*
G01X1352186Y1503792D02*
G02Y1506798I0J1503D01*
G01X1355586D01*
G02Y1503792I0J-1503D01*
G01X1352186D01*
G37*
G36*
G01X375096Y1612790D02*
G02Y1615794I0J1502D01*
G01X378496D01*
G02Y1612790I0J-1502D01*
G01X375096D01*
G37*
G36*
G01X1332086Y1494092D02*
G02Y1497098I0J1503D01*
G01X1335486D01*
G02Y1494092I0J-1503D01*
G01X1332086D01*
G37*
G36*
G01X207567Y1520264D02*
G02X208627Y1520900I1060J-565D01*
G02X209830Y1519698I1J-1202D01*
G02X209669Y1519098I-1204J1D01*
G01X208124Y1516425D01*
X208122Y1516421D01*
G02X207052Y1515768I-1070J550D01*
G02X205850Y1516970I0J1202D01*
G01Y1516972D01*
G02X205999Y1517551I1202J-1D01*
G01X207565Y1520261D01*
X207567Y1520264D01*
G37*
G36*
G01X212292D02*
G02X213352Y1520900I1060J-565D01*
G02X214554Y1519698I0J-1202D01*
G02X214394Y1519098I-1203J0D01*
G01X212849Y1516425D01*
X212847Y1516421D01*
G02X211777Y1515768I-1070J550D01*
G02X210574Y1516970I-1J1202D01*
G01Y1516972D01*
G02X210724Y1517551I1203J-3D01*
G01X212290Y1520261D01*
X212292Y1520264D01*
G37*
G36*
G01X1338786Y1484392D02*
G02Y1487398I0J1503D01*
G01X1342186D01*
G02Y1484392I0J-1503D01*
G01X1338786D01*
G37*
G36*
G01X345078Y1520264D02*
G02X346138Y1520900I1060J-565D01*
G02X347340Y1519698I0J-1202D01*
G02X347180Y1519098I-1203J0D01*
G01X345635Y1516425D01*
X345633Y1516421D01*
G02X344563Y1515768I-1070J550D01*
G02X343360Y1516970I-1J1202D01*
G01Y1516972D01*
G02X343510Y1517551I1203J-3D01*
G01X345076Y1520261D01*
X345078Y1520264D01*
G37*
G36*
G01X368700D02*
G02X369760Y1520900I1060J-565D01*
G02X370962Y1519698I0J-1202D01*
G02X370802Y1519098I-1203J0D01*
G01X369257Y1516425D01*
X369255Y1516421D01*
G02X368185Y1515768I-1070J550D01*
G02X366982Y1516970I-1J1202D01*
G01Y1516972D01*
G02X367132Y1517551I1203J-3D01*
G01X368698Y1520261D01*
X368700Y1520264D01*
G37*
G36*
G01X326180D02*
G02X327240Y1520900I1060J-565D01*
G02X328442Y1519698I0J-1202D01*
G02X328282Y1519098I-1203J0D01*
G01X326737Y1516425D01*
X326735Y1516421D01*
G02X325665Y1515768I-1070J550D01*
G02X324462Y1516970I-1J1202D01*
G01Y1516972D01*
G02X324612Y1517551I1203J-3D01*
G01X326178Y1520261D01*
X326180Y1520264D01*
G37*
G36*
G01X378149D02*
G02X379209Y1520900I1060J-565D01*
G02X380412Y1519698I1J-1202D01*
G02X380251Y1519098I-1204J1D01*
G01X378706Y1516425D01*
X378704Y1516421D01*
G02X377634Y1515768I-1070J550D01*
G02X376432Y1516970I0J1202D01*
G01Y1516972D01*
G02X376581Y1517551I1202J-1D01*
G01X378147Y1520261D01*
X378149Y1520264D01*
G37*
G36*
G01X112473Y1661738D02*
G02Y1658732I0J-1503D01*
G01X109073D01*
G02Y1661738I0J1503D01*
G01X112473D01*
G37*
G36*
G01X157410Y1678314D02*
G02Y1675308I0J-1503D01*
G01X154010D01*
G02Y1678314I0J1503D01*
G01X157410D01*
G37*
G36*
G01X157511Y1665436D02*
G02Y1662430I0J-1503D01*
G01X154111D01*
G02Y1665436I0J1503D01*
G01X157511D01*
G37*
G36*
G01X110969Y1687266D02*
G02Y1684260I0J-1503D01*
G01X107569D01*
G02Y1687266I0J1503D01*
G01X110969D01*
G37*
G36*
G01X359251Y1520264D02*
G02X360311Y1520900I1060J-565D01*
G02X361514Y1519698I1J-1202D01*
G02X361353Y1519098I-1204J1D01*
G01X359808Y1516425D01*
X359806Y1516421D01*
G02X358736Y1515768I-1070J550D01*
G02X357534Y1516970I0J1202D01*
G01Y1516972D01*
G02X357683Y1517551I1202J-1D01*
G01X359249Y1520261D01*
X359251Y1520264D01*
G37*
G36*
G01X1592873Y1655790D02*
G02Y1658794I0J1502D01*
G01X1596273D01*
G02Y1655790I0J-1502D01*
G01X1592873D01*
G37*
G36*
G01X1616993D02*
G02Y1658794I0J1502D01*
G01X1620393D01*
G02Y1655790I0J-1502D01*
G01X1616993D01*
G37*
G36*
G01X1274429Y1645790D02*
G02Y1648794I0J1502D01*
G01X1277829D01*
G02Y1645790I0J-1502D01*
G01X1274429D01*
G37*
G36*
G01X1286489D02*
G02Y1648794I0J1502D01*
G01X1289889D01*
G02Y1645790I0J-1502D01*
G01X1286489D01*
G37*
G36*
G01X1494998Y1494092D02*
G02Y1497098I0J1503D01*
G01X1498398D01*
G02Y1494092I0J-1503D01*
G01X1494998D01*
G37*
G36*
G01X507224Y1470792D02*
G02Y1473798I0J1503D01*
G01X510624D01*
G02Y1470792I0J-1503D01*
G01X507224D01*
G37*
G36*
G01X335629Y1520264D02*
G02X336689Y1520900I1060J-565D01*
G02X337892Y1519698I1J-1202D01*
G02X337731Y1519098I-1204J1D01*
G01X336186Y1516425D01*
X336184Y1516421D01*
G02X335114Y1515768I-1070J550D01*
G02X333912Y1516970I0J1202D01*
G01Y1516972D01*
G02X334061Y1517551I1202J-1D01*
G01X335627Y1520261D01*
X335629Y1520264D01*
G37*
G36*
G01X433524Y1461092D02*
G02Y1464098I0J1503D01*
G01X436924D01*
G02Y1461092I0J-1503D01*
G01X433524D01*
G37*
G36*
G01X384513Y1451392D02*
G02Y1454398I0J1503D01*
G01X387913D01*
G02Y1451392I0J-1503D01*
G01X384513D01*
G37*
G36*
G01X1204024Y1494092D02*
G02Y1497098I0J1503D01*
G01X1207424D01*
G02Y1494092I0J-1503D01*
G01X1204024D01*
G37*
G36*
G01X242436Y1600878D02*
G02Y1603882I0J1502D01*
G01X245836D01*
G02Y1600878I0J-1502D01*
G01X242436D01*
G37*
G36*
G01Y1612790D02*
G02Y1615794I0J1502D01*
G01X245836D01*
G02Y1612790I0J-1502D01*
G01X242436D01*
G37*
G36*
G01X266556Y1600878D02*
G02Y1603882I0J1502D01*
G01X269956D01*
G02Y1600878I0J-1502D01*
G01X266556D01*
G37*
G36*
G01X254496D02*
G02Y1603882I0J1502D01*
G01X257896D01*
G02Y1600878I0J-1502D01*
G01X254496D01*
G37*
G36*
G01X278616Y1612790D02*
G02Y1615794I0J1502D01*
G01X282016D01*
G02Y1612790I0J-1502D01*
G01X278616D01*
G37*
G36*
G01X290676Y1600878D02*
G02Y1603882I0J1502D01*
G01X294076D01*
G02Y1600878I0J-1502D01*
G01X290676D01*
G37*
G36*
G01Y1612790D02*
G02Y1615794I0J1502D01*
G01X294076D01*
G02Y1612790I0J-1502D01*
G01X290676D01*
G37*
G36*
G01X302736D02*
G02Y1615794I0J1502D01*
G01X306136D01*
G02Y1612790I0J-1502D01*
G01X302736D01*
G37*
G36*
G01X314796Y1600878D02*
G02Y1603882I0J1502D01*
G01X318196D01*
G02Y1600878I0J-1502D01*
G01X314796D01*
G37*
G36*
G01X584999Y1590878D02*
G02Y1593882I0J1502D01*
G01X588399D01*
G02Y1590878I0J-1502D01*
G01X584999D01*
G37*
G36*
G01X597059Y1622790D02*
G02Y1625794I0J1502D01*
G01X600459D01*
G02Y1622790I0J-1502D01*
G01X597059D01*
G37*
G36*
G01X1196039Y1655790D02*
G02Y1658794I0J1502D01*
G01X1199439D01*
G02Y1655790I0J-1502D01*
G01X1196039D01*
G37*
G36*
G01X491919Y1625794D02*
G02Y1622790I0J-1502D01*
G01X488519D01*
G02Y1625794I0J1502D01*
G01X491919D01*
G37*
G36*
G01X500579Y1622790D02*
G02Y1625794I0J1502D01*
G01X503979D01*
G02Y1622790I0J-1502D01*
G01X500579D01*
G37*
G36*
G01X512639D02*
G02Y1625794I0J1502D01*
G01X516039D01*
G02Y1622790I0J-1502D01*
G01X512639D01*
G37*
G36*
G01X524699Y1590878D02*
G02Y1593882I0J1502D01*
G01X528099D01*
G02Y1590878I0J-1502D01*
G01X524699D01*
G37*
G36*
G01Y1622790D02*
G02Y1625794I0J1502D01*
G01X528099D01*
G02Y1622790I0J-1502D01*
G01X524699D01*
G37*
G36*
G01X548819Y1590878D02*
G02Y1593882I0J1502D01*
G01X552219D01*
G02Y1590878I0J-1502D01*
G01X548819D01*
G37*
G36*
G01Y1622790D02*
G02Y1625794I0J1502D01*
G01X552219D01*
G02Y1622790I0J-1502D01*
G01X548819D01*
G37*
G36*
G01X560879D02*
G02Y1625794I0J1502D01*
G01X564279D01*
G02Y1622790I0J-1502D01*
G01X560879D01*
G37*
G36*
G01X572939D02*
G02Y1625794I0J1502D01*
G01X576339D01*
G02Y1622790I0J-1502D01*
G01X572939D01*
G37*
G36*
G01X566909Y1600878D02*
G02Y1603882I0J1502D01*
G01X570309D01*
G02Y1600878I0J-1502D01*
G01X566909D01*
G37*
G36*
G01Y1612790D02*
G02Y1615794I0J1502D01*
G01X570309D01*
G02Y1612790I0J-1502D01*
G01X566909D01*
G37*
G36*
G01X591029D02*
G02Y1615794I0J1502D01*
G01X594429D01*
G02Y1612790I0J-1502D01*
G01X591029D01*
G37*
G36*
G01X603089D02*
G02Y1615794I0J1502D01*
G01X606489D01*
G02Y1612790I0J-1502D01*
G01X603089D01*
G37*
G36*
G01X461769Y1615794D02*
G02Y1612790I0J-1502D01*
G01X458369D01*
G02Y1615794I0J1502D01*
G01X461769D01*
G37*
G36*
G01X470429Y1612790D02*
G02Y1615794I0J1502D01*
G01X473829D01*
G02Y1612790I0J-1502D01*
G01X470429D01*
G37*
G36*
G01X506609Y1600878D02*
G02Y1603882I0J1502D01*
G01X510009D01*
G02Y1600878I0J-1502D01*
G01X506609D01*
G37*
G36*
G01Y1612790D02*
G02Y1615794I0J1502D01*
G01X510009D01*
G02Y1612790I0J-1502D01*
G01X506609D01*
G37*
G36*
G01X522069Y1615794D02*
G02Y1612790I0J-1502D01*
G01X518669D01*
G02Y1615794I0J1502D01*
G01X522069D01*
G37*
G36*
G01X530729Y1612790D02*
G02Y1615794I0J1502D01*
G01X534129D01*
G02Y1612790I0J-1502D01*
G01X530729D01*
G37*
G36*
G01X542789D02*
G02Y1615794I0J1502D01*
G01X546189D01*
G02Y1612790I0J-1502D01*
G01X542789D01*
G37*
G36*
G01X188166Y1622790D02*
G02Y1625794I0J1502D01*
G01X191566D01*
G02Y1622790I0J-1502D01*
G01X188166D01*
G37*
G36*
G01Y1590878D02*
G02Y1593882I0J1502D01*
G01X191566D01*
G02Y1590878I0J-1502D01*
G01X188166D01*
G37*
G36*
G01X326856Y1612790D02*
G02Y1615794I0J1502D01*
G01X330256D01*
G02Y1612790I0J-1502D01*
G01X326856D01*
G37*
G36*
G01X377813Y1461092D02*
G02Y1464098I0J1503D01*
G01X381213D01*
G02Y1461092I0J-1503D01*
G01X377813D01*
G37*
G36*
G01X206256Y1612790D02*
G02Y1615794I0J1502D01*
G01X209656D01*
G02Y1612790I0J-1502D01*
G01X206256D01*
G37*
G36*
G01X308766Y1622790D02*
G02Y1625794I0J1502D01*
G01X312166D01*
G02Y1622790I0J-1502D01*
G01X308766D01*
G37*
G36*
G01Y1590878D02*
G02Y1593882I0J1502D01*
G01X312166D01*
G02Y1590878I0J-1502D01*
G01X308766D01*
G37*
G36*
G01X296706Y1622790D02*
G02Y1625794I0J1502D01*
G01X300106D01*
G02Y1622790I0J-1502D01*
G01X296706D01*
G37*
G36*
G01X284646Y1590878D02*
G02Y1593882I0J1502D01*
G01X288046D01*
G02Y1590878I0J-1502D01*
G01X284646D01*
G37*
G36*
G01Y1622790D02*
G02Y1625794I0J1502D01*
G01X288046D01*
G02Y1622790I0J-1502D01*
G01X284646D01*
G37*
G36*
G01X272586D02*
G02Y1625794I0J1502D01*
G01X275986D01*
G02Y1622790I0J-1502D01*
G01X272586D01*
G37*
G36*
G01X1183924Y1484392D02*
G02Y1487398I0J1503D01*
G01X1187324D01*
G02Y1484392I0J-1503D01*
G01X1183924D01*
G37*
G36*
G01X260526Y1590878D02*
G02Y1593882I0J1502D01*
G01X263926D01*
G02Y1590878I0J-1502D01*
G01X260526D01*
G37*
G36*
G01Y1622790D02*
G02Y1625794I0J1502D01*
G01X263926D01*
G02Y1622790I0J-1502D01*
G01X260526D01*
G37*
G36*
G01X248466D02*
G02Y1625794I0J1502D01*
G01X251866D01*
G02Y1622790I0J-1502D01*
G01X248466D01*
G37*
G36*
G01X236406D02*
G02Y1625794I0J1502D01*
G01X239806D01*
G02Y1622790I0J-1502D01*
G01X236406D01*
G37*
G36*
G01X224346D02*
G02Y1625794I0J1502D01*
G01X227746D01*
G02Y1622790I0J-1502D01*
G01X224346D01*
G37*
G36*
G01Y1590878D02*
G02Y1593882I0J1502D01*
G01X227746D01*
G02Y1590878I0J-1502D01*
G01X224346D01*
G37*
G36*
G01X1237524Y1484392D02*
G02Y1487398I0J1503D01*
G01X1240924D01*
G02Y1484392I0J-1503D01*
G01X1237524D01*
G37*
G36*
G01X1210724D02*
G02Y1487398I0J1503D01*
G01X1214124D01*
G02Y1484392I0J-1503D01*
G01X1210724D01*
G37*
G36*
G01X351013Y1461092D02*
G02Y1464098I0J1503D01*
G01X354413D01*
G02Y1461092I0J-1503D01*
G01X351013D01*
G37*
G36*
G01X1378986Y1503792D02*
G02Y1506798I0J1503D01*
G01X1382386D01*
G02Y1503792I0J-1503D01*
G01X1378986D01*
G37*
G36*
G01X320826Y1622790D02*
G02Y1625794I0J1502D01*
G01X324226D01*
G02Y1622790I0J-1502D01*
G01X320826D01*
G37*
G36*
G01X332886D02*
G02Y1625794I0J1502D01*
G01X336286D01*
G02Y1622790I0J-1502D01*
G01X332886D01*
G37*
G36*
G01X344946D02*
G02Y1625794I0J1502D01*
G01X348346D01*
G02Y1622790I0J-1502D01*
G01X344946D01*
G37*
G36*
G01X369066Y1590878D02*
G02Y1593882I0J1502D01*
G01X372466D01*
G02Y1590878I0J-1502D01*
G01X369066D01*
G37*
G36*
G01X452339Y1622790D02*
G02Y1625794I0J1502D01*
G01X455739D01*
G02Y1622790I0J-1502D01*
G01X452339D01*
G37*
G36*
G01X369066D02*
G02Y1625794I0J1502D01*
G01X372466D01*
G02Y1622790I0J-1502D01*
G01X369066D01*
G37*
G36*
G01X1538603Y1645790D02*
G02Y1648794I0J1502D01*
G01X1542003D01*
G02Y1645790I0J-1502D01*
G01X1538603D01*
G37*
G36*
G01X1550663D02*
G02Y1648794I0J1502D01*
G01X1554063D01*
G02Y1645790I0J-1502D01*
G01X1550663D01*
G37*
G36*
G01X1562723D02*
G02Y1648794I0J1502D01*
G01X1566123D01*
G02Y1645790I0J-1502D01*
G01X1562723D01*
G37*
G36*
G01X200226Y1622790D02*
G02Y1625794I0J1502D01*
G01X203626D01*
G02Y1622790I0J-1502D01*
G01X200226D01*
G37*
G36*
G01X320826Y1590878D02*
G02Y1593882I0J1502D01*
G01X324226D01*
G02Y1590878I0J-1502D01*
G01X320826D01*
G37*
G36*
G01X1568753Y1655790D02*
G02Y1658794I0J1502D01*
G01X1572153D01*
G02Y1655790I0J-1502D01*
G01X1568753D01*
G37*
G36*
G01X1580813D02*
G02Y1658794I0J1502D01*
G01X1584213D01*
G02Y1655790I0J-1502D01*
G01X1580813D01*
G37*
G36*
G01X1382969Y1645790D02*
G02Y1648794I0J1502D01*
G01X1386369D01*
G02Y1645790I0J-1502D01*
G01X1382969D01*
G37*
G36*
G01X1586843D02*
G02Y1648794I0J1502D01*
G01X1590243D01*
G02Y1645790I0J-1502D01*
G01X1586843D01*
G37*
G36*
G01X1610963D02*
G02Y1648794I0J1502D01*
G01X1614363D01*
G02Y1645790I0J-1502D01*
G01X1610963D01*
G37*
G36*
G01X1623023Y1633878D02*
G02Y1636882I0J1502D01*
G01X1626423D01*
G02Y1633878I0J-1502D01*
G01X1623023D01*
G37*
G36*
G01Y1645790D02*
G02Y1648794I0J1502D01*
G01X1626423D01*
G02Y1645790I0J-1502D01*
G01X1623023D01*
G37*
G36*
G01X1635083D02*
G02Y1648794I0J1502D01*
G01X1638483D01*
G02Y1645790I0J-1502D01*
G01X1635083D01*
G37*
G36*
G01X1466243D02*
G02Y1648794I0J1502D01*
G01X1469643D01*
G02Y1645790I0J-1502D01*
G01X1466243D01*
G37*
G36*
G01X1478303D02*
G02Y1648794I0J1502D01*
G01X1481703D01*
G02Y1645790I0J-1502D01*
G01X1478303D01*
G37*
G36*
G01X1490363D02*
G02Y1648794I0J1502D01*
G01X1493763D01*
G02Y1645790I0J-1502D01*
G01X1490363D01*
G37*
G36*
G01X1502423Y1633878D02*
G02Y1636882I0J1502D01*
G01X1505823D01*
G02Y1633878I0J-1502D01*
G01X1502423D01*
G37*
G36*
G01Y1645790D02*
G02Y1648794I0J1502D01*
G01X1505823D01*
G02Y1645790I0J-1502D01*
G01X1502423D01*
G37*
G36*
G01X1514483D02*
G02Y1648794I0J1502D01*
G01X1517883D01*
G02Y1645790I0J-1502D01*
G01X1514483D01*
G37*
G36*
G01X1526543D02*
G02Y1648794I0J1502D01*
G01X1529943D01*
G02Y1645790I0J-1502D01*
G01X1526543D01*
G37*
G36*
G01X1461498Y1503792D02*
G02Y1506798I0J1503D01*
G01X1464898D01*
G02Y1503792I0J-1503D01*
G01X1461498D01*
G37*
G36*
G01X1569460Y1494092D02*
G02Y1497098I0J1503D01*
G01X1572860D01*
G02Y1494092I0J-1503D01*
G01X1569460D01*
G37*
G36*
G01X1602960Y1484392D02*
G02Y1487398I0J1503D01*
G01X1606360D01*
G02Y1484392I0J-1503D01*
G01X1602960D01*
G37*
G36*
G01X1474898D02*
G02Y1487398I0J1503D01*
G01X1478298D01*
G02Y1484392I0J-1503D01*
G01X1474898D01*
G37*
G36*
G01X1556693Y1623878D02*
G02Y1626882I0J1502D01*
G01X1560093D01*
G02Y1623878I0J-1502D01*
G01X1556693D01*
G37*
G36*
G01Y1655790D02*
G02Y1658794I0J1502D01*
G01X1560093D01*
G02Y1655790I0J-1502D01*
G01X1556693D01*
G37*
G36*
G01X1496393D02*
G02Y1658794I0J1502D01*
G01X1499793D01*
G02Y1655790I0J-1502D01*
G01X1496393D01*
G37*
G36*
G01X1508453D02*
G02Y1658794I0J1502D01*
G01X1511853D01*
G02Y1655790I0J-1502D01*
G01X1508453D01*
G37*
G36*
G01X1532573Y1623878D02*
G02Y1626882I0J1502D01*
G01X1535973D01*
G02Y1623878I0J-1502D01*
G01X1532573D01*
G37*
G36*
G01X1520513Y1655790D02*
G02Y1658794I0J1502D01*
G01X1523913D01*
G02Y1655790I0J-1502D01*
G01X1520513D01*
G37*
G36*
G01X1532573D02*
G02Y1658794I0J1502D01*
G01X1535973D01*
G02Y1655790I0J-1502D01*
G01X1532573D01*
G37*
G36*
G01X1544633D02*
G02Y1658794I0J1502D01*
G01X1548033D01*
G02Y1655790I0J-1502D01*
G01X1544633D01*
G37*
G36*
G01X1484333D02*
G02Y1658794I0J1502D01*
G01X1487733D01*
G02Y1655790I0J-1502D01*
G01X1484333D01*
G37*
G36*
G01X1262369Y1645790D02*
G02Y1648794I0J1502D01*
G01X1265769D01*
G02Y1645790I0J-1502D01*
G01X1262369D01*
G37*
G36*
G01Y1633878D02*
G02Y1636882I0J1502D01*
G01X1265769D01*
G02Y1633878I0J-1502D01*
G01X1262369D01*
G37*
G36*
G01X1274429D02*
G02Y1636882I0J1502D01*
G01X1277829D01*
G02Y1633878I0J-1502D01*
G01X1274429D01*
G37*
G36*
G01X1214129Y1645790D02*
G02Y1648794I0J1502D01*
G01X1217529D01*
G02Y1645790I0J-1502D01*
G01X1214129D01*
G37*
G36*
G01X1238249D02*
G02Y1648794I0J1502D01*
G01X1241649D01*
G02Y1645790I0J-1502D01*
G01X1238249D01*
G37*
G36*
G01X1250309D02*
G02Y1648794I0J1502D01*
G01X1253709D01*
G02Y1645790I0J-1502D01*
G01X1250309D01*
G37*
G36*
G01X1364879Y1655790D02*
G02Y1658794I0J1502D01*
G01X1368279D01*
G02Y1655790I0J-1502D01*
G01X1364879D01*
G37*
G36*
G01X354527Y1520264D02*
G02X355587Y1520900I1060J-565D01*
G02X356790Y1519698I1J-1202D01*
G02X356629Y1519098I-1204J1D01*
G01X355084Y1516425D01*
X355082Y1516421D01*
G02X354012Y1515768I-1070J550D01*
G02X352810Y1516970I0J1202D01*
G01Y1516972D01*
G02X352959Y1517551I1202J-1D01*
G01X354525Y1520261D01*
X354527Y1520264D01*
G37*
G36*
G01X482380Y140440D02*
G02Y143444I0J1502D01*
G01X485780D01*
G02Y140440I0J-1502D01*
G01X482380D01*
G37*
G36*
G01X537148Y89555D02*
G02X539273Y91680I1062J1062D01*
G01X541678Y89276D01*
G02X542118Y88214I-1063J-1063D01*
G01Y88213D01*
G02X540615Y86710I-1503J0D01*
G01X540614D01*
G02X539552Y87150I1J1503D01*
G01X537148Y89555D01*
G37*
G36*
G01X472895Y128518D02*
G02Y131522I0J1502D01*
G01X476295D01*
G02Y128518I0J-1502D01*
G01X472895D01*
G37*
G36*
G01X445014Y93182D02*
G02Y96186I0J1502D01*
G01X448414D01*
G02Y93182I0J-1502D01*
G01X445014D01*
G37*
G36*
G01X514240Y95644D02*
G02Y98648I0J1502D01*
G01X517640D01*
G02Y95644I0J-1502D01*
G01X514240D01*
G37*
G36*
G01X552105Y110700D02*
G02Y113706I0J1503D01*
G01X555505D01*
G02Y110700I0J-1503D01*
G01X552105D01*
G37*
G36*
G01X330905Y1520264D02*
G02X331965Y1520900I1060J-565D01*
G02X333168Y1519698I1J-1202D01*
G02X333007Y1519098I-1204J1D01*
G01X331462Y1516425D01*
X331460Y1516421D01*
G02X330390Y1515768I-1070J550D01*
G02X329188Y1516970I0J1202D01*
G01Y1516972D01*
G02X329337Y1517551I1202J-1D01*
G01X330903Y1520261D01*
X330905Y1520264D01*
G37*
G36*
G01X452102Y87208D02*
G02Y90214I0J1503D01*
G01X455502D01*
G02Y87208I0J-1503D01*
G01X452102D01*
G37*
G36*
G01X321456Y1520264D02*
G02X322516Y1520900I1060J-565D01*
G02X323718Y1519698I0J-1202D01*
G02X323558Y1519098I-1203J0D01*
G01X322013Y1516425D01*
X322011Y1516421D01*
G02X320941Y1515768I-1070J550D01*
G02X319738Y1516970I-1J1202D01*
G01Y1516972D01*
G02X319888Y1517551I1203J-3D01*
G01X321454Y1520261D01*
X321456Y1520264D01*
G37*
G36*
G01X316732D02*
G02X317792Y1520900I1060J-565D01*
G02X318994Y1519698I0J-1202D01*
G02X318834Y1519098I-1203J0D01*
G01X317289Y1516425D01*
X317287Y1516421D01*
G02X316217Y1515768I-1070J550D01*
G02X315014Y1516970I-1J1202D01*
G01Y1516972D01*
G02X315164Y1517551I1203J-3D01*
G01X316730Y1520261D01*
X316732Y1520264D01*
G37*
G36*
G01X459056Y93598D02*
G02Y96604I0J1503D01*
G01X462456D01*
G02Y93598I0J-1503D01*
G01X459056D01*
G37*
G36*
G01X363976Y1520264D02*
G02X365036Y1520900I1060J-565D01*
G02X366238Y1519698I0J-1202D01*
G02X366078Y1519098I-1203J0D01*
G01X364533Y1516425D01*
X364531Y1516421D01*
G02X363461Y1515768I-1070J550D01*
G02X362258Y1516970I-1J1202D01*
G01Y1516972D01*
G02X362408Y1517551I1203J-3D01*
G01X363974Y1520261D01*
X363976Y1520264D01*
G37*
G36*
G01X490380Y129940D02*
G02Y132944I0J1502D01*
G01X493780D01*
G02Y129940I0J-1502D01*
G01X490380D01*
G37*
G36*
G01X349802Y1520264D02*
G02X350862Y1520900I1060J-565D01*
G02X352064Y1519698I0J-1202D01*
G02X351904Y1519098I-1203J0D01*
G01X350359Y1516425D01*
X350357Y1516421D01*
G02X349287Y1515768I-1070J550D01*
G02X348084Y1516970I-1J1202D01*
G01Y1516972D01*
G02X348234Y1517551I1203J-3D01*
G01X349800Y1520261D01*
X349802Y1520264D01*
G37*
G36*
G01X533918Y45564D02*
G02Y48570I0J1503D01*
G01X537318D01*
G02Y45564I0J-1503D01*
G01X533918D01*
G37*
G36*
G01X1549274Y24974D02*
G02Y27980I0J1503D01*
G01X1552674D01*
G02Y24974I0J-1503D01*
G01X1549274D01*
G37*
G36*
G01X1685967D02*
G02Y27980I0J1503D01*
G01X1689367D01*
G02Y24974I0J-1503D01*
G01X1685967D01*
G37*
G36*
G01X1612566Y73838D02*
G02Y76842I0J1502D01*
G01X1615966D01*
G02Y73838I0J-1502D01*
G01X1612566D01*
G37*
G36*
G01X1623562Y67840D02*
G02Y70846I0J1503D01*
G01X1626962D01*
G02Y67840I0J-1503D01*
G01X1623562D01*
G37*
G36*
G01X1563447Y24974D02*
G02Y27980I0J1503D01*
G01X1566847D01*
G02Y24974I0J-1503D01*
G01X1563447D01*
G37*
G36*
G01X1627660D02*
G02Y27980I0J1503D01*
G01X1631060D01*
G02Y24974I0J-1503D01*
G01X1627660D01*
G37*
G36*
G01X1598899Y18038D02*
G02Y21044I0J1503D01*
G01X1602299D01*
G02Y18038I0J-1503D01*
G01X1598899D01*
G37*
G36*
G01X1570552D02*
G02Y21044I0J1503D01*
G01X1573952D01*
G02Y18038I0J-1503D01*
G01X1570552D01*
G37*
G36*
G01X1591794Y24974D02*
G02Y27980I0J1503D01*
G01X1595194D01*
G02Y24974I0J-1503D01*
G01X1591794D01*
G37*
G36*
G01X1648938Y18038D02*
G02Y21044I0J1503D01*
G01X1652338D01*
G02Y18038I0J-1503D01*
G01X1648938D01*
G37*
G36*
G01X1601562Y67840D02*
G02Y70846I0J1503D01*
G01X1604962D01*
G02Y67840I0J-1503D01*
G01X1601562D01*
G37*
G36*
G01X1701904Y73838D02*
G02Y76842I0J1502D01*
G01X1705304D01*
G02Y73838I0J-1502D01*
G01X1701904D01*
G37*
G36*
G01X1679904D02*
G02Y76842I0J1502D01*
G01X1683304D01*
G02Y73838I0J-1502D01*
G01X1679904D01*
G37*
G36*
G01X1668770Y67838D02*
G02Y70842I0J1502D01*
G01X1672170D01*
G02Y67838I0J-1502D01*
G01X1668770D01*
G37*
G36*
G01X1657766Y73840D02*
G02Y76846I0J1503D01*
G01X1661166D01*
G02Y73840I0J-1503D01*
G01X1657766D01*
G37*
G36*
G01X1646770Y67838D02*
G02Y70842I0J1502D01*
G01X1650170D01*
G02Y67838I0J-1502D01*
G01X1646770D01*
G37*
G36*
G01X1635770Y73838D02*
G02Y76842I0J1502D01*
G01X1639170D01*
G02Y73838I0J-1502D01*
G01X1635770D01*
G37*
G36*
G01X1584725Y18038D02*
G02Y21044I0J1503D01*
G01X1588125D01*
G02Y18038I0J-1503D01*
G01X1584725D01*
G37*
G36*
G01X1671794Y24974D02*
G02Y27980I0J1503D01*
G01X1675194D01*
G02Y24974I0J-1503D01*
G01X1671794D01*
G37*
G36*
G01X1590566Y73838D02*
G02Y76842I0J1502D01*
G01X1593966D01*
G02Y73838I0J-1502D01*
G01X1590566D01*
G37*
G36*
G01X1546562Y73840D02*
G02Y76846I0J1503D01*
G01X1549962D01*
G02Y73840I0J-1503D01*
G01X1546562D01*
G37*
G36*
G01X1579566Y67838D02*
G02Y70842I0J1502D01*
G01X1582966D01*
G02Y67838I0J-1502D01*
G01X1579566D01*
G37*
G36*
G01X1557566D02*
G02Y70842I0J1502D01*
G01X1560966D01*
G02Y67838I0J-1502D01*
G01X1557566D01*
G37*
G36*
G01X1535566D02*
G02Y70842I0J1502D01*
G01X1538966D01*
G02Y67838I0J-1502D01*
G01X1535566D01*
G37*
G36*
G01X1568566Y73838D02*
G02Y76842I0J1502D01*
G01X1571966D01*
G02Y73838I0J-1502D01*
G01X1568566D01*
G37*
G36*
G01X218663Y18038D02*
G02Y21044I0J1503D01*
G01X222063D01*
G02Y18038I0J-1503D01*
G01X218663D01*
G37*
G36*
G01X211558Y24974D02*
G02Y27980I0J1503D01*
G01X214958D01*
G02Y24974I0J-1503D01*
G01X211558D01*
G37*
G36*
G01X204490Y18038D02*
G02Y21044I0J1503D01*
G01X207890D01*
G02Y18038I0J-1503D01*
G01X204490D01*
G37*
G36*
G01X197385Y24974D02*
G02Y27980I0J1503D01*
G01X200785D01*
G02Y24974I0J-1503D01*
G01X197385D01*
G37*
G36*
G01X174529Y18038D02*
G02Y21044I0J1503D01*
G01X177929D01*
G02Y18038I0J-1503D01*
G01X174529D01*
G37*
G36*
G01X160356D02*
G02Y21044I0J1503D01*
G01X163756D01*
G02Y18038I0J-1503D01*
G01X160356D01*
G37*
G36*
G01X167424Y24974D02*
G02Y27980I0J1503D01*
G01X170824D01*
G02Y24974I0J-1503D01*
G01X167424D01*
G37*
G36*
G01X153251D02*
G02Y27980I0J1503D01*
G01X156651D01*
G02Y24974I0J-1503D01*
G01X153251D01*
G37*
G36*
G01X124490Y18038D02*
G02Y21044I0J1503D01*
G01X127890D01*
G02Y18038I0J-1503D01*
G01X124490D01*
G37*
G36*
G01X117385Y24974D02*
G02Y27980I0J1503D01*
G01X120785D01*
G02Y24974I0J-1503D01*
G01X117385D01*
G37*
G36*
G01X110316Y18038D02*
G02Y21044I0J1503D01*
G01X113716D01*
G02Y18038I0J-1503D01*
G01X110316D01*
G37*
G36*
G01X103211Y24974D02*
G02Y27980I0J1503D01*
G01X106611D01*
G02Y24974I0J-1503D01*
G01X103211D01*
G37*
G36*
G01X96143Y18038D02*
G02Y21044I0J1503D01*
G01X99543D01*
G02Y18038I0J-1503D01*
G01X96143D01*
G37*
G36*
G01X89038Y24974D02*
G02Y27980I0J1503D01*
G01X92438D01*
G02Y24974I0J-1503D01*
G01X89038D01*
G37*
G36*
G01X74865D02*
G02Y27980I0J1503D01*
G01X78265D01*
G02Y24974I0J-1503D01*
G01X74865D01*
G37*
G36*
G01X81970Y18038D02*
G02Y21044I0J1503D01*
G01X85370D01*
G02Y18038I0J-1503D01*
G01X81970D01*
G37*
G36*
G01X227495Y73838D02*
G02Y76842I0J1502D01*
G01X230895D01*
G02Y73838I0J-1502D01*
G01X227495D01*
G37*
G36*
G01X216491Y67840D02*
G02Y70846I0J1503D01*
G01X219891D01*
G02Y67840I0J-1503D01*
G01X216491D01*
G37*
G36*
G01X205495Y73838D02*
G02Y76842I0J1502D01*
G01X208895D01*
G02Y73838I0J-1502D01*
G01X205495D01*
G37*
G36*
G01X194361Y67838D02*
G02Y70842I0J1502D01*
G01X197761D01*
G02Y67838I0J-1502D01*
G01X194361D01*
G37*
G36*
G01X172361D02*
G02Y70842I0J1502D01*
G01X175761D01*
G02Y67838I0J-1502D01*
G01X172361D01*
G37*
G36*
G01X183357Y73840D02*
G02Y76846I0J1503D01*
G01X186757D01*
G02Y73840I0J-1503D01*
G01X183357D01*
G37*
G36*
G01X161361Y73838D02*
G02Y76842I0J1502D01*
G01X164761D01*
G02Y73838I0J-1502D01*
G01X161361D01*
G37*
G36*
G01X149153Y67840D02*
G02Y70846I0J1503D01*
G01X152553D01*
G02Y67840I0J-1503D01*
G01X149153D01*
G37*
G36*
G01X138157Y73838D02*
G02Y76842I0J1502D01*
G01X141557D01*
G02Y73838I0J-1502D01*
G01X138157D01*
G37*
G36*
G01X127153Y67840D02*
G02Y70846I0J1503D01*
G01X130553D01*
G02Y67840I0J-1503D01*
G01X127153D01*
G37*
G36*
G01X116157Y73838D02*
G02Y76842I0J1502D01*
G01X119557D01*
G02Y73838I0J-1502D01*
G01X116157D01*
G37*
G36*
G01X105157Y67838D02*
G02Y70842I0J1502D01*
G01X108557D01*
G02Y67838I0J-1502D01*
G01X105157D01*
G37*
G36*
G01X83157D02*
G02Y70842I0J1502D01*
G01X86557D01*
G02Y67838I0J-1502D01*
G01X83157D01*
G37*
G36*
G01X94157Y73838D02*
G02Y76842I0J1502D01*
G01X97557D01*
G02Y73838I0J-1502D01*
G01X94157D01*
G37*
G36*
G01X72153Y73840D02*
G02Y76846I0J1503D01*
G01X75553D01*
G02Y73840I0J-1503D01*
G01X72153D01*
G37*
G36*
G01X61157Y67838D02*
G02Y70842I0J1502D01*
G01X64557D01*
G02Y67838I0J-1502D01*
G01X61157D01*
G37*
G36*
G01X1690900Y67840D02*
G02Y70846I0J1503D01*
G01X1694300D01*
G02Y67840I0J-1503D01*
G01X1690900D01*
G37*
G36*
G01X1693072Y18038D02*
G02Y21044I0J1503D01*
G01X1696472D01*
G02Y18038I0J-1503D01*
G01X1693072D01*
G37*
G36*
G01X1641833Y24974D02*
G02Y27980I0J1503D01*
G01X1645233D01*
G02Y24974I0J-1503D01*
G01X1641833D01*
G37*
G36*
G01X1634765Y18038D02*
G02Y21044I0J1503D01*
G01X1638165D01*
G02Y18038I0J-1503D01*
G01X1634765D01*
G37*
G36*
G01X1678899D02*
G02Y21044I0J1503D01*
G01X1682299D01*
G02Y18038I0J-1503D01*
G01X1678899D01*
G37*
G36*
G01X1577620Y24974D02*
G02Y27980I0J1503D01*
G01X1581020D01*
G02Y24974I0J-1503D01*
G01X1577620D01*
G37*
G36*
G01X1556379Y18038D02*
G02Y21044I0J1503D01*
G01X1559779D01*
G02Y18038I0J-1503D01*
G01X1556379D01*
G37*
G36*
G01X373424Y1520264D02*
G02X374484Y1520900I1060J-565D01*
G02X375686Y1519698I0J-1202D01*
G02X375526Y1519098I-1203J0D01*
G01X373981Y1516425D01*
X373979Y1516421D01*
G02X372909Y1515768I-1070J550D01*
G02X371706Y1516970I-1J1202D01*
G01Y1516972D01*
G02X371856Y1517551I1203J-3D01*
G01X373422Y1520261D01*
X373424Y1520264D01*
G37*
G36*
G01X555176Y69934D02*
G02Y72938I0J1502D01*
G01X558576D01*
G02Y69934I0J-1502D01*
G01X555176D01*
G37*
G36*
G01X45812Y450100D02*
G02Y453104I0J1502D01*
G01X49212D01*
G02Y450100I0J-1502D01*
G01X45812D01*
G37*
G36*
G01X519765Y38826D02*
G02Y41830I0J1502D01*
G01X523165D01*
G02Y38826I0J-1502D01*
G01X519765D01*
G37*
G36*
G01X519743Y69934D02*
G02Y72938I0J1502D01*
G01X523143D01*
G02Y69934I0J-1502D01*
G01X519743D01*
G37*
G36*
G01X1311986Y1484392D02*
G02Y1487398I0J1503D01*
G01X1315386D01*
G02Y1484392I0J-1503D01*
G01X1311986D01*
G37*
G36*
G01X1358849Y1645790D02*
G02Y1648794I0J1502D01*
G01X1362249D01*
G02Y1645790I0J-1502D01*
G01X1358849D01*
G37*
G36*
G01X1334729Y1633878D02*
G02Y1636882I0J1502D01*
G01X1338129D01*
G02Y1633878I0J-1502D01*
G01X1334729D01*
G37*
G36*
G01X1298549Y1645790D02*
G02Y1648794I0J1502D01*
G01X1301949D01*
G02Y1645790I0J-1502D01*
G01X1298549D01*
G37*
G36*
G01X1472273Y1655790D02*
G02Y1658794I0J1502D01*
G01X1475673D01*
G02Y1655790I0J-1502D01*
G01X1472273D01*
G37*
G36*
G01X1604933D02*
G02Y1658794I0J1502D01*
G01X1608333D01*
G02Y1655790I0J-1502D01*
G01X1604933D01*
G37*
G36*
G01X1635083Y1633878D02*
G02Y1636882I0J1502D01*
G01X1638483D01*
G02Y1633878I0J-1502D01*
G01X1635083D01*
G37*
G36*
G01X1629053Y1655790D02*
G02Y1658794I0J1502D01*
G01X1632453D01*
G02Y1655790I0J-1502D01*
G01X1629053D01*
G37*
G36*
G01X1647143Y1645790D02*
G02Y1648794I0J1502D01*
G01X1650543D01*
G02Y1645790I0J-1502D01*
G01X1647143D01*
G37*
G36*
G01X1598903D02*
G02Y1648794I0J1502D01*
G01X1602303D01*
G02Y1645790I0J-1502D01*
G01X1598903D01*
G37*
G36*
G01X1574783D02*
G02Y1648794I0J1502D01*
G01X1578183D01*
G02Y1645790I0J-1502D01*
G01X1574783D01*
G37*
G36*
G01X1346789D02*
G02Y1648794I0J1502D01*
G01X1350189D01*
G02Y1645790I0J-1502D01*
G01X1346789D01*
G37*
G36*
G01X1641113Y1623878D02*
G02Y1626882I0J1502D01*
G01X1644513D01*
G02Y1623878I0J-1502D01*
G01X1641113D01*
G37*
G36*
G01X1607250Y1728479D02*
Y1731341D01*
G02X1607552Y1731644I302J1D01*
G01X1611252D01*
G02X1611554Y1731341I-1J-303D01*
G01Y1721335D01*
G02X1611252Y1721032I-302J-1D01*
G01X1607552D01*
G02X1607250Y1721335I1J303D01*
G01Y1724199D01*
G02X1607281Y1724333I302J1D01*
G01X1608200Y1726208D01*
G03Y1726470I-267J131D01*
G01X1607281Y1728345D01*
G02X1607250Y1728479I271J133D01*
G37*
G36*
G01X1622998D02*
Y1731341D01*
G02X1623300Y1731644I302J1D01*
G01X1627000D01*
G02X1627302Y1731341I-1J-303D01*
G01Y1721335D01*
G02X1627000Y1721032I-302J-1D01*
G01X1623300D01*
G02X1622998Y1721335I1J303D01*
G01Y1724199D01*
G02X1623029Y1724333I302J1D01*
G01X1623948Y1726208D01*
G03Y1726470I-267J131D01*
G01X1623029Y1728345D01*
G02X1622998Y1728479I271J133D01*
G37*
G36*
G01X1599376Y1724542D02*
Y1727404D01*
G02X1599678Y1727706I302J0D01*
G01X1603378D01*
G02X1603680Y1727404I0J-302D01*
G01Y1717398D01*
G02X1603378Y1717096I-302J0D01*
G01X1599678D01*
G02X1599376Y1717398I0J302D01*
G01Y1720262D01*
G02X1599407Y1720396I302J1D01*
G01X1600326Y1722271D01*
G03Y1722533I-267J131D01*
G01X1599407Y1724408D01*
G02X1599376Y1724542I271J133D01*
G37*
G36*
G01X1615124D02*
Y1727404D01*
G02X1615426Y1727706I302J0D01*
G01X1619126D01*
G02X1619428Y1727404I0J-302D01*
G01Y1717398D01*
G02X1619126Y1717096I-302J0D01*
G01X1615426D01*
G02X1615124Y1717398I0J302D01*
G01Y1720262D01*
G02X1615155Y1720396I302J1D01*
G01X1616074Y1722271D01*
G03Y1722533I-267J131D01*
G01X1615155Y1724408D01*
G02X1615124Y1724542I271J133D01*
G37*
G36*
G01X1607250Y1714306D02*
Y1717168D01*
G02X1607552Y1717470I302J0D01*
G01X1611252D01*
G02X1611554Y1717168I0J-302D01*
G01Y1707162D01*
G02X1611252Y1706860I-302J0D01*
G01X1607552D01*
G02X1607250Y1707162I0J302D01*
G01Y1710026D01*
G02X1607281Y1710160I302J1D01*
G01X1608200Y1712035D01*
G03Y1712297I-267J131D01*
G01X1607281Y1714172D01*
G02X1607250Y1714306I271J133D01*
G37*
G36*
G01X1622998D02*
Y1717168D01*
G02X1623300Y1717470I302J0D01*
G01X1627000D01*
G02X1627302Y1717168I0J-302D01*
G01Y1707162D01*
G02X1627000Y1706860I-302J0D01*
G01X1623300D01*
G02X1622998Y1707162I0J302D01*
G01Y1710026D01*
G02X1623029Y1710160I302J1D01*
G01X1623948Y1712035D01*
G03Y1712297I-267J131D01*
G01X1623029Y1714172D01*
G02X1622998Y1714306I271J133D01*
G37*
G36*
G01X1599376Y1710369D02*
Y1713231D01*
G02X1599678Y1713534I302J1D01*
G01X1603378D01*
G02X1603680Y1713231I-1J-303D01*
G01Y1703225D01*
G02X1603378Y1702922I-302J-1D01*
G01X1599678D01*
G02X1599376Y1703225I1J303D01*
G01Y1706089D01*
G02X1599407Y1706223I302J1D01*
G01X1600326Y1708098D01*
G03Y1708360I-267J131D01*
G01X1599407Y1710235D01*
G02X1599376Y1710369I271J133D01*
G37*
G36*
G01X1615124D02*
Y1713231D01*
G02X1615426Y1713534I302J1D01*
G01X1619126D01*
G02X1619428Y1713231I-1J-303D01*
G01Y1703225D01*
G02X1619126Y1702922I-302J-1D01*
G01X1615426D01*
G02X1615124Y1703225I1J303D01*
G01Y1706089D01*
G02X1615155Y1706223I302J1D01*
G01X1616074Y1708098D01*
G03Y1708360I-267J131D01*
G01X1615155Y1710235D01*
G02X1615124Y1710369I271J133D01*
G37*
G36*
G01X1607248Y1702994D02*
G02X1607551Y1703296I303J-1D01*
G01X1611251D01*
G02X1611554Y1702994I1J-302D01*
G01Y1692988D01*
G02X1611251Y1692686I-303J1D01*
G01X1607551D01*
G02X1607248Y1692988I-1J302D01*
G01Y1702994D01*
G37*
G36*
G01X1622996D02*
G02X1623299Y1703296I303J-1D01*
G01X1626999D01*
G02X1627302Y1702994I1J-302D01*
G01Y1692988D01*
G02X1626999Y1692686I-303J1D01*
G01X1623299D01*
G02X1622996Y1692988I-1J302D01*
G01Y1702994D01*
G37*
G36*
G01X1599374Y1699057D02*
G02X1599677Y1699360I303J0D01*
G01X1603377D01*
G02X1603680Y1699057I0J-303D01*
G01Y1689051D01*
G02X1603377Y1688748I-303J0D01*
G01X1599677D01*
G02X1599374Y1689051I0J303D01*
G01Y1699057D01*
G37*
G36*
G01X1615122D02*
G02X1615425Y1699360I303J0D01*
G01X1619125D01*
G02X1619428Y1699057I0J-303D01*
G01Y1689051D01*
G02X1619125Y1688748I-303J0D01*
G01X1615425D01*
G02X1615122Y1689051I0J303D01*
G01Y1699057D01*
G37*
G36*
G01X1607248Y1688821D02*
G02X1607551Y1689124I303J0D01*
G01X1611251D01*
G02X1611554Y1688821I0J-303D01*
G01Y1678815D01*
G02X1611251Y1678512I-303J0D01*
G01X1607551D01*
G02X1607248Y1678815I0J303D01*
G01Y1688821D01*
G37*
G36*
G01X1622996D02*
G02X1623299Y1689124I303J0D01*
G01X1626999D01*
G02X1627302Y1688821I0J-303D01*
G01Y1678815D01*
G02X1626999Y1678512I-303J0D01*
G01X1623299D01*
G02X1622996Y1678815I0J303D01*
G01Y1688821D01*
G37*
G36*
G01X1599374Y1684884D02*
G02X1599677Y1685186I303J-1D01*
G01X1603377D01*
G02X1603680Y1684884I1J-302D01*
G01Y1674878D01*
G02X1603377Y1674576I-303J1D01*
G01X1599677D01*
G02X1599374Y1674878I-1J302D01*
G01Y1684884D01*
G37*
G36*
G01X1615122D02*
G02X1615425Y1685186I303J-1D01*
G01X1619125D01*
G02X1619428Y1684884I1J-302D01*
G01Y1674878D01*
G02X1619125Y1674576I-303J1D01*
G01X1615425D01*
G02X1615122Y1674878I-1J302D01*
G01Y1684884D01*
G37*
G36*
G01X1575754Y1728479D02*
Y1731341D01*
G02X1576056Y1731644I302J1D01*
G01X1579756D01*
G02X1580058Y1731341I-1J-303D01*
G01Y1721335D01*
G02X1579756Y1721032I-302J-1D01*
G01X1576056D01*
G02X1575754Y1721335I1J303D01*
G01Y1724199D01*
G02X1575785Y1724333I302J1D01*
G01X1576704Y1726208D01*
G03Y1726470I-267J131D01*
G01X1575785Y1728345D01*
G02X1575754Y1728479I271J133D01*
G37*
G36*
G01X1591502D02*
Y1731341D01*
G02X1591804Y1731644I302J1D01*
G01X1595504D01*
G02X1595806Y1731341I-1J-303D01*
G01Y1721335D01*
G02X1595504Y1721032I-302J-1D01*
G01X1591804D01*
G02X1591502Y1721335I1J303D01*
G01Y1724199D01*
G02X1591533Y1724333I302J1D01*
G01X1592452Y1726208D01*
G03Y1726470I-267J131D01*
G01X1591533Y1728345D01*
G02X1591502Y1728479I271J133D01*
G37*
G36*
G01X1567880Y1724542D02*
Y1727404D01*
G02X1568182Y1727706I302J0D01*
G01X1571882D01*
G02X1572184Y1727404I0J-302D01*
G01Y1717398D01*
G02X1571882Y1717096I-302J0D01*
G01X1568182D01*
G02X1567880Y1717398I0J302D01*
G01Y1720262D01*
G02X1567911Y1720396I302J1D01*
G01X1568830Y1722271D01*
G03Y1722533I-267J131D01*
G01X1567911Y1724408D01*
G02X1567880Y1724542I271J133D01*
G37*
G36*
G01X1583628D02*
Y1727404D01*
G02X1583930Y1727706I302J0D01*
G01X1587630D01*
G02X1587932Y1727404I0J-302D01*
G01Y1717398D01*
G02X1587630Y1717096I-302J0D01*
G01X1583930D01*
G02X1583628Y1717398I0J302D01*
G01Y1720262D01*
G02X1583659Y1720396I302J1D01*
G01X1584578Y1722271D01*
G03Y1722533I-267J131D01*
G01X1583659Y1724408D01*
G02X1583628Y1724542I271J133D01*
G37*
G36*
G01X1575754Y1714306D02*
Y1717168D01*
G02X1576056Y1717470I302J0D01*
G01X1579756D01*
G02X1580058Y1717168I0J-302D01*
G01Y1707162D01*
G02X1579756Y1706860I-302J0D01*
G01X1576056D01*
G02X1575754Y1707162I0J302D01*
G01Y1710026D01*
G02X1575785Y1710160I302J1D01*
G01X1576704Y1712035D01*
G03Y1712297I-267J131D01*
G01X1575785Y1714172D01*
G02X1575754Y1714306I271J133D01*
G37*
G36*
G01X1591502D02*
Y1717168D01*
G02X1591804Y1717470I302J0D01*
G01X1595504D01*
G02X1595806Y1717168I0J-302D01*
G01Y1707162D01*
G02X1595504Y1706860I-302J0D01*
G01X1591804D01*
G02X1591502Y1707162I0J302D01*
G01Y1710026D01*
G02X1591533Y1710160I302J1D01*
G01X1592452Y1712035D01*
G03Y1712297I-267J131D01*
G01X1591533Y1714172D01*
G02X1591502Y1714306I271J133D01*
G37*
G36*
G01X1567880Y1710369D02*
Y1713231D01*
G02X1568182Y1713534I302J1D01*
G01X1571882D01*
G02X1572184Y1713231I-1J-303D01*
G01Y1703225D01*
G02X1571882Y1702922I-302J-1D01*
G01X1568182D01*
G02X1567880Y1703225I1J303D01*
G01Y1706089D01*
G02X1567911Y1706223I302J1D01*
G01X1568830Y1708098D01*
G03Y1708360I-267J131D01*
G01X1567911Y1710235D01*
G02X1567880Y1710369I271J133D01*
G37*
G36*
G01X1583628D02*
Y1713231D01*
G02X1583930Y1713534I302J1D01*
G01X1587630D01*
G02X1587932Y1713231I-1J-303D01*
G01Y1703225D01*
G02X1587630Y1702922I-302J-1D01*
G01X1583930D01*
G02X1583628Y1703225I1J303D01*
G01Y1706089D01*
G02X1583659Y1706223I302J1D01*
G01X1584578Y1708098D01*
G03Y1708360I-267J131D01*
G01X1583659Y1710235D01*
G02X1583628Y1710369I271J133D01*
G37*
G36*
G01X1575752Y1702994D02*
G02X1576055Y1703296I303J-1D01*
G01X1579755D01*
G02X1580058Y1702994I1J-302D01*
G01Y1692988D01*
G02X1579755Y1692686I-303J1D01*
G01X1576055D01*
G02X1575752Y1692988I-1J302D01*
G01Y1702994D01*
G37*
G36*
G01X1591500D02*
G02X1591803Y1703296I303J-1D01*
G01X1595503D01*
G02X1595806Y1702994I1J-302D01*
G01Y1692988D01*
G02X1595503Y1692686I-303J1D01*
G01X1591803D01*
G02X1591500Y1692988I-1J302D01*
G01Y1702994D01*
G37*
G36*
G01X1567878Y1699057D02*
G02X1568181Y1699360I303J0D01*
G01X1571881D01*
G02X1572184Y1699057I0J-303D01*
G01Y1689051D01*
G02X1571881Y1688748I-303J0D01*
G01X1568181D01*
G02X1567878Y1689051I0J303D01*
G01Y1699057D01*
G37*
G36*
G01X1583626D02*
G02X1583929Y1699360I303J0D01*
G01X1587629D01*
G02X1587932Y1699057I0J-303D01*
G01Y1689051D01*
G02X1587629Y1688748I-303J0D01*
G01X1583929D01*
G02X1583626Y1689051I0J303D01*
G01Y1699057D01*
G37*
G36*
G01X1575752Y1688821D02*
G02X1576055Y1689124I303J0D01*
G01X1579755D01*
G02X1580058Y1688821I0J-303D01*
G01Y1678815D01*
G02X1579755Y1678512I-303J0D01*
G01X1576055D01*
G02X1575752Y1678815I0J303D01*
G01Y1688821D01*
G37*
G36*
G01X1591500D02*
G02X1591803Y1689124I303J0D01*
G01X1595503D01*
G02X1595806Y1688821I0J-303D01*
G01Y1678815D01*
G02X1595503Y1678512I-303J0D01*
G01X1591803D01*
G02X1591500Y1678815I0J303D01*
G01Y1688821D01*
G37*
G36*
G01X1567878Y1684884D02*
G02X1568181Y1685186I303J-1D01*
G01X1571881D01*
G02X1572184Y1684884I1J-302D01*
G01Y1674878D01*
G02X1571881Y1674576I-303J1D01*
G01X1568181D01*
G02X1567878Y1674878I-1J302D01*
G01Y1684884D01*
G37*
G36*
G01X1583626D02*
G02X1583929Y1685186I303J-1D01*
G01X1587629D01*
G02X1587932Y1684884I1J-302D01*
G01Y1674878D01*
G02X1587629Y1674576I-303J1D01*
G01X1583929D01*
G02X1583626Y1674878I-1J302D01*
G01Y1684884D01*
G37*
G36*
G01X1540320Y1728479D02*
Y1731341D01*
G02X1540623Y1731644I303J0D01*
G01X1544323D01*
G02X1544626Y1731341I0J-303D01*
G01Y1721335D01*
G02X1544323Y1721032I-303J0D01*
G01X1540623D01*
G02X1540320Y1721335I0J303D01*
G01Y1724199D01*
G02X1540352Y1724333I303J-1D01*
G01X1541271Y1726208D01*
G03Y1726470I-267J131D01*
G01X1540352Y1728345D01*
G02X1540320Y1728479I270J135D01*
G37*
G36*
G01X1556068D02*
Y1731341D01*
G02X1556371Y1731644I303J0D01*
G01X1560071D01*
G02X1560374Y1731341I0J-303D01*
G01Y1721335D01*
G02X1560071Y1721032I-303J0D01*
G01X1556371D01*
G02X1556068Y1721335I0J303D01*
G01Y1724199D01*
G02X1556100Y1724333I303J-1D01*
G01X1557019Y1726208D01*
G03Y1726470I-267J131D01*
G01X1556100Y1728345D01*
G02X1556068Y1728479I270J135D01*
G37*
G36*
G01X1532446Y1724542D02*
Y1727404D01*
G02X1532749Y1727706I303J-1D01*
G01X1536449D01*
G02X1536752Y1727404I1J-302D01*
G01Y1717398D01*
G02X1536449Y1717096I-303J1D01*
G01X1532749D01*
G02X1532446Y1717398I-1J302D01*
G01Y1720262D01*
G02X1532478Y1720396I303J-1D01*
G01X1533397Y1722271D01*
G03Y1722533I-267J131D01*
G01X1532478Y1724408D01*
G02X1532446Y1724542I270J135D01*
G37*
G36*
G01X1548194D02*
Y1727404D01*
G02X1548497Y1727706I303J-1D01*
G01X1552197D01*
G02X1552500Y1727404I1J-302D01*
G01Y1717398D01*
G02X1552197Y1717096I-303J1D01*
G01X1548497D01*
G02X1548194Y1717398I-1J302D01*
G01Y1720262D01*
G02X1548226Y1720396I303J-1D01*
G01X1549145Y1722271D01*
G03Y1722533I-267J131D01*
G01X1548226Y1724408D01*
G02X1548194Y1724542I270J135D01*
G37*
G36*
G01X1540320Y1714306D02*
Y1717168D01*
G02X1540622Y1717470I302J0D01*
G01X1544322D01*
G02X1544624Y1717168I0J-302D01*
G01Y1707162D01*
G02X1544322Y1706860I-302J0D01*
G01X1540622D01*
G02X1540320Y1707162I0J302D01*
G01Y1710026D01*
G02X1540351Y1710160I302J1D01*
G01X1541270Y1712035D01*
G03Y1712297I-267J131D01*
G01X1540351Y1714172D01*
G02X1540320Y1714306I271J133D01*
G37*
G36*
G01X1556068D02*
Y1717168D01*
G02X1556370Y1717470I302J0D01*
G01X1560070D01*
G02X1560372Y1717168I0J-302D01*
G01Y1707162D01*
G02X1560070Y1706860I-302J0D01*
G01X1556370D01*
G02X1556068Y1707162I0J302D01*
G01Y1710026D01*
G02X1556099Y1710160I302J1D01*
G01X1557018Y1712035D01*
G03Y1712297I-267J131D01*
G01X1556099Y1714172D01*
G02X1556068Y1714306I271J133D01*
G37*
G36*
G01X1532446Y1710369D02*
Y1713231D01*
G02X1532748Y1713534I302J1D01*
G01X1536448D01*
G02X1536750Y1713231I-1J-303D01*
G01Y1703225D01*
G02X1536448Y1702922I-302J-1D01*
G01X1532748D01*
G02X1532446Y1703225I1J303D01*
G01Y1706089D01*
G02X1532477Y1706223I302J1D01*
G01X1533396Y1708098D01*
G03Y1708360I-267J131D01*
G01X1532477Y1710235D01*
G02X1532446Y1710369I271J133D01*
G37*
G36*
G01X1548194D02*
Y1713231D01*
G02X1548496Y1713534I302J1D01*
G01X1552196D01*
G02X1552498Y1713231I-1J-303D01*
G01Y1703225D01*
G02X1552196Y1702922I-302J-1D01*
G01X1548496D01*
G02X1548194Y1703225I1J303D01*
G01Y1706089D01*
G02X1548225Y1706223I302J1D01*
G01X1549144Y1708098D01*
G03Y1708360I-267J131D01*
G01X1548225Y1710235D01*
G02X1548194Y1710369I271J133D01*
G37*
G36*
G01X1540320Y1702994D02*
G02X1540622Y1703296I302J0D01*
G01X1544322D01*
G02X1544624Y1702994I0J-302D01*
G01Y1692988D01*
G02X1544322Y1692686I-302J0D01*
G01X1540622D01*
G02X1540320Y1692988I0J302D01*
G01Y1702994D01*
G37*
G36*
G01X1556068D02*
G02X1556370Y1703296I302J0D01*
G01X1560070D01*
G02X1560372Y1702994I0J-302D01*
G01Y1692988D01*
G02X1560070Y1692686I-302J0D01*
G01X1556370D01*
G02X1556068Y1692988I0J302D01*
G01Y1702994D01*
G37*
G36*
G01X1532446Y1699057D02*
G02X1532748Y1699360I302J1D01*
G01X1536448D01*
G02X1536750Y1699057I-1J-303D01*
G01Y1689051D01*
G02X1536448Y1688748I-302J-1D01*
G01X1532748D01*
G02X1532446Y1689051I1J303D01*
G01Y1699057D01*
G37*
G36*
G01X1548194D02*
G02X1548496Y1699360I302J1D01*
G01X1552196D01*
G02X1552498Y1699057I-1J-303D01*
G01Y1689051D01*
G02X1552196Y1688748I-302J-1D01*
G01X1548496D01*
G02X1548194Y1689051I1J303D01*
G01Y1699057D01*
G37*
G36*
G01X1540320Y1688821D02*
G02X1540622Y1689124I302J1D01*
G01X1544322D01*
G02X1544624Y1688821I-1J-303D01*
G01Y1678815D01*
G02X1544322Y1678512I-302J-1D01*
G01X1540622D01*
G02X1540320Y1678815I1J303D01*
G01Y1688821D01*
G37*
G36*
G01X1556068D02*
G02X1556370Y1689124I302J1D01*
G01X1560070D01*
G02X1560372Y1688821I-1J-303D01*
G01Y1678815D01*
G02X1560070Y1678512I-302J-1D01*
G01X1556370D01*
G02X1556068Y1678815I1J303D01*
G01Y1688821D01*
G37*
G36*
G01X1532446Y1684884D02*
G02X1532748Y1685186I302J0D01*
G01X1536448D01*
G02X1536750Y1684884I0J-302D01*
G01Y1674878D01*
G02X1536448Y1674576I-302J0D01*
G01X1532748D01*
G02X1532446Y1674878I0J302D01*
G01Y1684884D01*
G37*
G36*
G01X1548194D02*
G02X1548496Y1685186I302J0D01*
G01X1552196D01*
G02X1552498Y1684884I0J-302D01*
G01Y1674878D01*
G02X1552196Y1674576I-302J0D01*
G01X1548496D01*
G02X1548194Y1674878I0J302D01*
G01Y1684884D01*
G37*
G36*
G01X1508824Y1728479D02*
Y1731341D01*
G02X1509127Y1731644I303J0D01*
G01X1512827D01*
G02X1513130Y1731341I0J-303D01*
G01Y1721335D01*
G02X1512827Y1721032I-303J0D01*
G01X1509127D01*
G02X1508824Y1721335I0J303D01*
G01Y1724199D01*
G02X1508856Y1724333I303J-1D01*
G01X1509775Y1726208D01*
G03Y1726470I-267J131D01*
G01X1508856Y1728345D01*
G02X1508824Y1728479I270J135D01*
G37*
G36*
G01X1524572D02*
Y1731341D01*
G02X1524875Y1731644I303J0D01*
G01X1528575D01*
G02X1528878Y1731341I0J-303D01*
G01Y1721335D01*
G02X1528575Y1721032I-303J0D01*
G01X1524875D01*
G02X1524572Y1721335I0J303D01*
G01Y1724199D01*
G02X1524604Y1724333I303J-1D01*
G01X1525523Y1726208D01*
G03Y1726470I-267J131D01*
G01X1524604Y1728345D01*
G02X1524572Y1728479I270J135D01*
G37*
G36*
G01X1500950Y1724542D02*
Y1727404D01*
G02X1501253Y1727706I303J-1D01*
G01X1504953D01*
G02X1505256Y1727404I1J-302D01*
G01Y1717398D01*
G02X1504953Y1717096I-303J1D01*
G01X1501253D01*
G02X1500950Y1717398I-1J302D01*
G01Y1720262D01*
G02X1500982Y1720396I303J-1D01*
G01X1501901Y1722271D01*
G03Y1722533I-267J131D01*
G01X1500982Y1724408D01*
G02X1500950Y1724542I270J135D01*
G37*
G36*
G01X1516698D02*
Y1727404D01*
G02X1517001Y1727706I303J-1D01*
G01X1520701D01*
G02X1521004Y1727404I1J-302D01*
G01Y1717398D01*
G02X1520701Y1717096I-303J1D01*
G01X1517001D01*
G02X1516698Y1717398I-1J302D01*
G01Y1720262D01*
G02X1516730Y1720396I303J-1D01*
G01X1517649Y1722271D01*
G03Y1722533I-267J131D01*
G01X1516730Y1724408D01*
G02X1516698Y1724542I270J135D01*
G37*
G36*
G01X1508824Y1714306D02*
Y1717168D01*
G02X1509126Y1717470I302J0D01*
G01X1512826D01*
G02X1513128Y1717168I0J-302D01*
G01Y1707162D01*
G02X1512826Y1706860I-302J0D01*
G01X1509126D01*
G02X1508824Y1707162I0J302D01*
G01Y1710026D01*
G02X1508855Y1710160I302J1D01*
G01X1509774Y1712035D01*
G03Y1712297I-267J131D01*
G01X1508855Y1714172D01*
G02X1508824Y1714306I271J133D01*
G37*
G36*
G01X1524572D02*
Y1717168D01*
G02X1524874Y1717470I302J0D01*
G01X1528574D01*
G02X1528876Y1717168I0J-302D01*
G01Y1707162D01*
G02X1528574Y1706860I-302J0D01*
G01X1524874D01*
G02X1524572Y1707162I0J302D01*
G01Y1710026D01*
G02X1524603Y1710160I302J1D01*
G01X1525522Y1712035D01*
G03Y1712297I-267J131D01*
G01X1524603Y1714172D01*
G02X1524572Y1714306I271J133D01*
G37*
G36*
G01X1500950Y1710369D02*
Y1713231D01*
G02X1501252Y1713534I302J1D01*
G01X1504952D01*
G02X1505254Y1713231I-1J-303D01*
G01Y1703225D01*
G02X1504952Y1702922I-302J-1D01*
G01X1501252D01*
G02X1500950Y1703225I1J303D01*
G01Y1706089D01*
G02X1500981Y1706223I302J1D01*
G01X1501900Y1708098D01*
G03Y1708360I-267J131D01*
G01X1500981Y1710235D01*
G02X1500950Y1710369I271J133D01*
G37*
G36*
G01X1516698D02*
Y1713231D01*
G02X1517000Y1713534I302J1D01*
G01X1520700D01*
G02X1521002Y1713231I-1J-303D01*
G01Y1703225D01*
G02X1520700Y1702922I-302J-1D01*
G01X1517000D01*
G02X1516698Y1703225I1J303D01*
G01Y1706089D01*
G02X1516729Y1706223I302J1D01*
G01X1517648Y1708098D01*
G03Y1708360I-267J131D01*
G01X1516729Y1710235D01*
G02X1516698Y1710369I271J133D01*
G37*
G36*
G01X1508824Y1702994D02*
G02X1509126Y1703296I302J0D01*
G01X1512826D01*
G02X1513128Y1702994I0J-302D01*
G01Y1692988D01*
G02X1512826Y1692686I-302J0D01*
G01X1509126D01*
G02X1508824Y1692988I0J302D01*
G01Y1702994D01*
G37*
G36*
G01X1524572D02*
G02X1524874Y1703296I302J0D01*
G01X1528574D01*
G02X1528876Y1702994I0J-302D01*
G01Y1692988D01*
G02X1528574Y1692686I-302J0D01*
G01X1524874D01*
G02X1524572Y1692988I0J302D01*
G01Y1702994D01*
G37*
G36*
G01X1500950Y1699057D02*
G02X1501252Y1699360I302J1D01*
G01X1504952D01*
G02X1505254Y1699057I-1J-303D01*
G01Y1689051D01*
G02X1504952Y1688748I-302J-1D01*
G01X1501252D01*
G02X1500950Y1689051I1J303D01*
G01Y1699057D01*
G37*
G36*
G01X1516698D02*
G02X1517000Y1699360I302J1D01*
G01X1520700D01*
G02X1521002Y1699057I-1J-303D01*
G01Y1689051D01*
G02X1520700Y1688748I-302J-1D01*
G01X1517000D01*
G02X1516698Y1689051I1J303D01*
G01Y1699057D01*
G37*
G36*
G01X1508824Y1688821D02*
G02X1509126Y1689124I302J1D01*
G01X1512826D01*
G02X1513128Y1688821I-1J-303D01*
G01Y1678815D01*
G02X1512826Y1678512I-302J-1D01*
G01X1509126D01*
G02X1508824Y1678815I1J303D01*
G01Y1688821D01*
G37*
G36*
G01X1524572D02*
G02X1524874Y1689124I302J1D01*
G01X1528574D01*
G02X1528876Y1688821I-1J-303D01*
G01Y1678815D01*
G02X1528574Y1678512I-302J-1D01*
G01X1524874D01*
G02X1524572Y1678815I1J303D01*
G01Y1688821D01*
G37*
G36*
G01X1500950Y1684884D02*
G02X1501252Y1685186I302J0D01*
G01X1504952D01*
G02X1505254Y1684884I0J-302D01*
G01Y1674878D01*
G02X1504952Y1674576I-302J0D01*
G01X1501252D01*
G02X1500950Y1674878I0J302D01*
G01Y1684884D01*
G37*
G36*
G01X1516698D02*
G02X1517000Y1685186I302J0D01*
G01X1520700D01*
G02X1521002Y1684884I0J-302D01*
G01Y1674878D01*
G02X1520700Y1674576I-302J0D01*
G01X1517000D01*
G02X1516698Y1674878I0J302D01*
G01Y1684884D01*
G37*
G36*
G01X1343076Y1728479D02*
Y1731341D01*
G02X1343378Y1731644I302J1D01*
G01X1347078D01*
G02X1347380Y1731341I-1J-303D01*
G01Y1721335D01*
G02X1347078Y1721032I-302J-1D01*
G01X1343378D01*
G02X1343076Y1721335I1J303D01*
G01Y1724199D01*
G02X1343107Y1724333I302J1D01*
G01X1344026Y1726208D01*
G03Y1726470I-267J131D01*
G01X1343107Y1728345D01*
G02X1343076Y1728479I271J133D01*
G37*
G36*
G01X1358824D02*
Y1731341D01*
G02X1359126Y1731644I302J1D01*
G01X1362826D01*
G02X1363128Y1731341I-1J-303D01*
G01Y1721335D01*
G02X1362826Y1721032I-302J-1D01*
G01X1359126D01*
G02X1358824Y1721335I1J303D01*
G01Y1724199D01*
G02X1358855Y1724333I302J1D01*
G01X1359774Y1726208D01*
G03Y1726470I-267J131D01*
G01X1358855Y1728345D01*
G02X1358824Y1728479I271J133D01*
G37*
G36*
G01X1335202Y1724542D02*
Y1727404D01*
G02X1335504Y1727706I302J0D01*
G01X1339204D01*
G02X1339506Y1727404I0J-302D01*
G01Y1717398D01*
G02X1339204Y1717096I-302J0D01*
G01X1335504D01*
G02X1335202Y1717398I0J302D01*
G01Y1720262D01*
G02X1335233Y1720396I302J1D01*
G01X1336152Y1722271D01*
G03Y1722533I-267J131D01*
G01X1335233Y1724408D01*
G02X1335202Y1724542I271J133D01*
G37*
G36*
G01X1350950D02*
Y1727404D01*
G02X1351252Y1727706I302J0D01*
G01X1354952D01*
G02X1355254Y1727404I0J-302D01*
G01Y1717398D01*
G02X1354952Y1717096I-302J0D01*
G01X1351252D01*
G02X1350950Y1717398I0J302D01*
G01Y1720262D01*
G02X1350981Y1720396I302J1D01*
G01X1351900Y1722271D01*
G03Y1722533I-267J131D01*
G01X1350981Y1724408D01*
G02X1350950Y1724542I271J133D01*
G37*
G36*
G01X1343076Y1714306D02*
Y1717168D01*
G02X1343378Y1717470I302J0D01*
G01X1347078D01*
G02X1347380Y1717168I0J-302D01*
G01Y1707162D01*
G02X1347078Y1706860I-302J0D01*
G01X1343378D01*
G02X1343076Y1707162I0J302D01*
G01Y1710026D01*
G02X1343107Y1710160I302J1D01*
G01X1344026Y1712035D01*
G03Y1712297I-267J131D01*
G01X1343107Y1714172D01*
G02X1343076Y1714306I271J133D01*
G37*
G36*
G01X1358824D02*
Y1717168D01*
G02X1359126Y1717470I302J0D01*
G01X1362826D01*
G02X1363128Y1717168I0J-302D01*
G01Y1707162D01*
G02X1362826Y1706860I-302J0D01*
G01X1359126D01*
G02X1358824Y1707162I0J302D01*
G01Y1710026D01*
G02X1358855Y1710160I302J1D01*
G01X1359774Y1712035D01*
G03Y1712297I-267J131D01*
G01X1358855Y1714172D01*
G02X1358824Y1714306I271J133D01*
G37*
G36*
G01X1335202Y1710369D02*
Y1713231D01*
G02X1335504Y1713534I302J1D01*
G01X1339204D01*
G02X1339506Y1713231I-1J-303D01*
G01Y1703225D01*
G02X1339204Y1702922I-302J-1D01*
G01X1335504D01*
G02X1335202Y1703225I1J303D01*
G01Y1706089D01*
G02X1335233Y1706223I302J1D01*
G01X1336152Y1708098D01*
G03Y1708360I-267J131D01*
G01X1335233Y1710235D01*
G02X1335202Y1710369I271J133D01*
G37*
G36*
G01X1350950D02*
Y1713231D01*
G02X1351252Y1713534I302J1D01*
G01X1354952D01*
G02X1355254Y1713231I-1J-303D01*
G01Y1703225D01*
G02X1354952Y1702922I-302J-1D01*
G01X1351252D01*
G02X1350950Y1703225I1J303D01*
G01Y1706089D01*
G02X1350981Y1706223I302J1D01*
G01X1351900Y1708098D01*
G03Y1708360I-267J131D01*
G01X1350981Y1710235D01*
G02X1350950Y1710369I271J133D01*
G37*
G36*
G01X1343076Y1702994D02*
G02X1343378Y1703296I302J0D01*
G01X1347078D01*
G02X1347380Y1702994I0J-302D01*
G01Y1692988D01*
G02X1347078Y1692686I-302J0D01*
G01X1343378D01*
G02X1343076Y1692988I0J302D01*
G01Y1702994D01*
G37*
G36*
G01X1358824D02*
G02X1359126Y1703296I302J0D01*
G01X1362826D01*
G02X1363128Y1702994I0J-302D01*
G01Y1692988D01*
G02X1362826Y1692686I-302J0D01*
G01X1359126D01*
G02X1358824Y1692988I0J302D01*
G01Y1702994D01*
G37*
G36*
G01X1335202Y1699057D02*
G02X1335504Y1699360I302J1D01*
G01X1339204D01*
G02X1339506Y1699057I-1J-303D01*
G01Y1689051D01*
G02X1339204Y1688748I-302J-1D01*
G01X1335504D01*
G02X1335202Y1689051I1J303D01*
G01Y1699057D01*
G37*
G36*
G01X1350950D02*
G02X1351252Y1699360I302J1D01*
G01X1354952D01*
G02X1355254Y1699057I-1J-303D01*
G01Y1689051D01*
G02X1354952Y1688748I-302J-1D01*
G01X1351252D01*
G02X1350950Y1689051I1J303D01*
G01Y1699057D01*
G37*
G36*
G01X1343076Y1688821D02*
G02X1343378Y1689124I302J1D01*
G01X1347078D01*
G02X1347380Y1688821I-1J-303D01*
G01Y1678815D01*
G02X1347078Y1678512I-302J-1D01*
G01X1343378D01*
G02X1343076Y1678815I1J303D01*
G01Y1688821D01*
G37*
G36*
G01X1358824D02*
G02X1359126Y1689124I302J1D01*
G01X1362826D01*
G02X1363128Y1688821I-1J-303D01*
G01Y1678815D01*
G02X1362826Y1678512I-302J-1D01*
G01X1359126D01*
G02X1358824Y1678815I1J303D01*
G01Y1688821D01*
G37*
G36*
G01X1335202Y1684884D02*
G02X1335504Y1685186I302J0D01*
G01X1339204D01*
G02X1339506Y1684884I0J-302D01*
G01Y1674878D01*
G02X1339204Y1674576I-302J0D01*
G01X1335504D01*
G02X1335202Y1674878I0J302D01*
G01Y1684884D01*
G37*
G36*
G01X1350950D02*
G02X1351252Y1685186I302J0D01*
G01X1354952D01*
G02X1355254Y1684884I0J-302D01*
G01Y1674878D01*
G02X1354952Y1674576I-302J0D01*
G01X1351252D01*
G02X1350950Y1674878I0J302D01*
G01Y1684884D01*
G37*
G36*
G01X1311580Y1728479D02*
Y1731341D01*
G02X1311882Y1731644I302J1D01*
G01X1315582D01*
G02X1315884Y1731341I-1J-303D01*
G01Y1721335D01*
G02X1315582Y1721032I-302J-1D01*
G01X1311882D01*
G02X1311580Y1721335I1J303D01*
G01Y1724199D01*
G02X1311611Y1724333I302J1D01*
G01X1312530Y1726208D01*
G03Y1726470I-267J131D01*
G01X1311611Y1728345D01*
G02X1311580Y1728479I271J133D01*
G37*
G36*
G01X1327328D02*
Y1731341D01*
G02X1327630Y1731644I302J1D01*
G01X1331330D01*
G02X1331632Y1731341I-1J-303D01*
G01Y1721335D01*
G02X1331330Y1721032I-302J-1D01*
G01X1327630D01*
G02X1327328Y1721335I1J303D01*
G01Y1724199D01*
G02X1327359Y1724333I302J1D01*
G01X1328278Y1726208D01*
G03Y1726470I-267J131D01*
G01X1327359Y1728345D01*
G02X1327328Y1728479I271J133D01*
G37*
G36*
G01X1303706Y1724542D02*
Y1727404D01*
G02X1304008Y1727706I302J0D01*
G01X1307708D01*
G02X1308010Y1727404I0J-302D01*
G01Y1717398D01*
G02X1307708Y1717096I-302J0D01*
G01X1304008D01*
G02X1303706Y1717398I0J302D01*
G01Y1720262D01*
G02X1303737Y1720396I302J1D01*
G01X1304656Y1722271D01*
G03Y1722533I-267J131D01*
G01X1303737Y1724408D01*
G02X1303706Y1724542I271J133D01*
G37*
G36*
G01X1319454D02*
Y1727404D01*
G02X1319756Y1727706I302J0D01*
G01X1323456D01*
G02X1323758Y1727404I0J-302D01*
G01Y1717398D01*
G02X1323456Y1717096I-302J0D01*
G01X1319756D01*
G02X1319454Y1717398I0J302D01*
G01Y1720262D01*
G02X1319485Y1720396I302J1D01*
G01X1320404Y1722271D01*
G03Y1722533I-267J131D01*
G01X1319485Y1724408D01*
G02X1319454Y1724542I271J133D01*
G37*
G36*
G01X1311580Y1714306D02*
Y1717168D01*
G02X1311882Y1717470I302J0D01*
G01X1315582D01*
G02X1315884Y1717168I0J-302D01*
G01Y1707162D01*
G02X1315582Y1706860I-302J0D01*
G01X1311882D01*
G02X1311580Y1707162I0J302D01*
G01Y1710026D01*
G02X1311611Y1710160I302J1D01*
G01X1312530Y1712035D01*
G03Y1712297I-267J131D01*
G01X1311611Y1714172D01*
G02X1311580Y1714306I271J133D01*
G37*
G36*
G01X1327328D02*
Y1717168D01*
G02X1327630Y1717470I302J0D01*
G01X1331330D01*
G02X1331632Y1717168I0J-302D01*
G01Y1707162D01*
G02X1331330Y1706860I-302J0D01*
G01X1327630D01*
G02X1327328Y1707162I0J302D01*
G01Y1710026D01*
G02X1327359Y1710160I302J1D01*
G01X1328278Y1712035D01*
G03Y1712297I-267J131D01*
G01X1327359Y1714172D01*
G02X1327328Y1714306I271J133D01*
G37*
G36*
G01X1303706Y1710369D02*
Y1713231D01*
G02X1304008Y1713534I302J1D01*
G01X1307708D01*
G02X1308010Y1713231I-1J-303D01*
G01Y1703225D01*
G02X1307708Y1702922I-302J-1D01*
G01X1304008D01*
G02X1303706Y1703225I1J303D01*
G01Y1706089D01*
G02X1303737Y1706223I302J1D01*
G01X1304656Y1708098D01*
G03Y1708360I-267J131D01*
G01X1303737Y1710235D01*
G02X1303706Y1710369I271J133D01*
G37*
G36*
G01X1319454D02*
Y1713231D01*
G02X1319756Y1713534I302J1D01*
G01X1323456D01*
G02X1323758Y1713231I-1J-303D01*
G01Y1703225D01*
G02X1323456Y1702922I-302J-1D01*
G01X1319756D01*
G02X1319454Y1703225I1J303D01*
G01Y1706089D01*
G02X1319485Y1706223I302J1D01*
G01X1320404Y1708098D01*
G03Y1708360I-267J131D01*
G01X1319485Y1710235D01*
G02X1319454Y1710369I271J133D01*
G37*
G36*
G01X1311580Y1702994D02*
G02X1311882Y1703296I302J0D01*
G01X1315582D01*
G02X1315884Y1702994I0J-302D01*
G01Y1692988D01*
G02X1315582Y1692686I-302J0D01*
G01X1311882D01*
G02X1311580Y1692988I0J302D01*
G01Y1702994D01*
G37*
G36*
G01X1327328D02*
G02X1327630Y1703296I302J0D01*
G01X1331330D01*
G02X1331632Y1702994I0J-302D01*
G01Y1692988D01*
G02X1331330Y1692686I-302J0D01*
G01X1327630D01*
G02X1327328Y1692988I0J302D01*
G01Y1702994D01*
G37*
G36*
G01X1303706Y1699057D02*
G02X1304008Y1699360I302J1D01*
G01X1307708D01*
G02X1308010Y1699057I-1J-303D01*
G01Y1689051D01*
G02X1307708Y1688748I-302J-1D01*
G01X1304008D01*
G02X1303706Y1689051I1J303D01*
G01Y1699057D01*
G37*
G36*
G01X1319454D02*
G02X1319756Y1699360I302J1D01*
G01X1323456D01*
G02X1323758Y1699057I-1J-303D01*
G01Y1689051D01*
G02X1323456Y1688748I-302J-1D01*
G01X1319756D01*
G02X1319454Y1689051I1J303D01*
G01Y1699057D01*
G37*
G36*
G01X1311580Y1688821D02*
G02X1311882Y1689124I302J1D01*
G01X1315582D01*
G02X1315884Y1688821I-1J-303D01*
G01Y1678815D01*
G02X1315582Y1678512I-302J-1D01*
G01X1311882D01*
G02X1311580Y1678815I1J303D01*
G01Y1688821D01*
G37*
G36*
G01X1327328D02*
G02X1327630Y1689124I302J1D01*
G01X1331330D01*
G02X1331632Y1688821I-1J-303D01*
G01Y1678815D01*
G02X1331330Y1678512I-302J-1D01*
G01X1327630D01*
G02X1327328Y1678815I1J303D01*
G01Y1688821D01*
G37*
G36*
G01X1303706Y1684884D02*
G02X1304008Y1685186I302J0D01*
G01X1307708D01*
G02X1308010Y1684884I0J-302D01*
G01Y1674878D01*
G02X1307708Y1674576I-302J0D01*
G01X1304008D01*
G02X1303706Y1674878I0J302D01*
G01Y1684884D01*
G37*
G36*
G01X1319454D02*
G02X1319756Y1685186I302J0D01*
G01X1323456D01*
G02X1323758Y1684884I0J-302D01*
G01Y1674878D01*
G02X1323456Y1674576I-302J0D01*
G01X1319756D01*
G02X1319454Y1674878I0J302D01*
G01Y1684884D01*
G37*
G36*
G01X1276146Y1728479D02*
Y1731341D01*
G02X1276449Y1731644I303J0D01*
G01X1280149D01*
G02X1280452Y1731341I0J-303D01*
G01Y1721335D01*
G02X1280149Y1721032I-303J0D01*
G01X1276449D01*
G02X1276146Y1721335I0J303D01*
G01Y1724199D01*
G02X1276178Y1724333I303J-1D01*
G01X1277097Y1726208D01*
G03Y1726470I-267J131D01*
G01X1276178Y1728345D01*
G02X1276146Y1728479I270J135D01*
G37*
G36*
G01X1291894D02*
Y1731341D01*
G02X1292197Y1731644I303J0D01*
G01X1295897D01*
G02X1296200Y1731341I0J-303D01*
G01Y1721335D01*
G02X1295897Y1721032I-303J0D01*
G01X1292197D01*
G02X1291894Y1721335I0J303D01*
G01Y1724199D01*
G02X1291926Y1724333I303J-1D01*
G01X1292845Y1726208D01*
G03Y1726470I-267J131D01*
G01X1291926Y1728345D01*
G02X1291894Y1728479I270J135D01*
G37*
G36*
G01X1268272Y1724542D02*
Y1727404D01*
G02X1268575Y1727706I303J-1D01*
G01X1272275D01*
G02X1272578Y1727404I1J-302D01*
G01Y1717398D01*
G02X1272275Y1717096I-303J1D01*
G01X1268575D01*
G02X1268272Y1717398I-1J302D01*
G01Y1720262D01*
G02X1268304Y1720396I303J-1D01*
G01X1269223Y1722271D01*
G03Y1722533I-267J131D01*
G01X1268304Y1724408D01*
G02X1268272Y1724542I270J135D01*
G37*
G36*
G01X1284020D02*
Y1727404D01*
G02X1284323Y1727706I303J-1D01*
G01X1288023D01*
G02X1288326Y1727404I1J-302D01*
G01Y1717398D01*
G02X1288023Y1717096I-303J1D01*
G01X1284323D01*
G02X1284020Y1717398I-1J302D01*
G01Y1720262D01*
G02X1284052Y1720396I303J-1D01*
G01X1284971Y1722271D01*
G03Y1722533I-267J131D01*
G01X1284052Y1724408D01*
G02X1284020Y1724542I270J135D01*
G37*
G36*
G01X1276146Y1714306D02*
Y1717168D01*
G02X1276448Y1717470I302J0D01*
G01X1280148D01*
G02X1280450Y1717168I0J-302D01*
G01Y1707162D01*
G02X1280148Y1706860I-302J0D01*
G01X1276448D01*
G02X1276146Y1707162I0J302D01*
G01Y1710026D01*
G02X1276177Y1710160I302J1D01*
G01X1277096Y1712035D01*
G03Y1712297I-267J131D01*
G01X1276177Y1714172D01*
G02X1276146Y1714306I271J133D01*
G37*
G36*
G01X1291894D02*
Y1717168D01*
G02X1292196Y1717470I302J0D01*
G01X1295896D01*
G02X1296198Y1717168I0J-302D01*
G01Y1707162D01*
G02X1295896Y1706860I-302J0D01*
G01X1292196D01*
G02X1291894Y1707162I0J302D01*
G01Y1710026D01*
G02X1291925Y1710160I302J1D01*
G01X1292844Y1712035D01*
G03Y1712297I-267J131D01*
G01X1291925Y1714172D01*
G02X1291894Y1714306I271J133D01*
G37*
G36*
G01X1268272Y1710369D02*
Y1713231D01*
G02X1268574Y1713534I302J1D01*
G01X1272274D01*
G02X1272576Y1713231I-1J-303D01*
G01Y1703225D01*
G02X1272274Y1702922I-302J-1D01*
G01X1268574D01*
G02X1268272Y1703225I1J303D01*
G01Y1706089D01*
G02X1268303Y1706223I302J1D01*
G01X1269222Y1708098D01*
G03Y1708360I-267J131D01*
G01X1268303Y1710235D01*
G02X1268272Y1710369I271J133D01*
G37*
G36*
G01X1284020D02*
Y1713231D01*
G02X1284322Y1713534I302J1D01*
G01X1288022D01*
G02X1288324Y1713231I-1J-303D01*
G01Y1703225D01*
G02X1288022Y1702922I-302J-1D01*
G01X1284322D01*
G02X1284020Y1703225I1J303D01*
G01Y1706089D01*
G02X1284051Y1706223I302J1D01*
G01X1284970Y1708098D01*
G03Y1708360I-267J131D01*
G01X1284051Y1710235D01*
G02X1284020Y1710369I271J133D01*
G37*
G36*
G01X1276146Y1702994D02*
G02X1276449Y1703296I303J-1D01*
G01X1280149D01*
G02X1280452Y1702994I1J-302D01*
G01Y1692988D01*
G02X1280149Y1692686I-303J1D01*
G01X1276449D01*
G02X1276146Y1692988I-1J302D01*
G01Y1702994D01*
G37*
G36*
G01X1291894D02*
G02X1292197Y1703296I303J-1D01*
G01X1295897D01*
G02X1296200Y1702994I1J-302D01*
G01Y1692988D01*
G02X1295897Y1692686I-303J1D01*
G01X1292197D01*
G02X1291894Y1692988I-1J302D01*
G01Y1702994D01*
G37*
G36*
G01X1268272Y1699057D02*
G02X1268575Y1699360I303J0D01*
G01X1272275D01*
G02X1272578Y1699057I0J-303D01*
G01Y1689051D01*
G02X1272275Y1688748I-303J0D01*
G01X1268575D01*
G02X1268272Y1689051I0J303D01*
G01Y1699057D01*
G37*
G36*
G01X1284020D02*
G02X1284323Y1699360I303J0D01*
G01X1288023D01*
G02X1288326Y1699057I0J-303D01*
G01Y1689051D01*
G02X1288023Y1688748I-303J0D01*
G01X1284323D01*
G02X1284020Y1689051I0J303D01*
G01Y1699057D01*
G37*
G36*
G01X1276146Y1688821D02*
G02X1276449Y1689124I303J0D01*
G01X1280149D01*
G02X1280452Y1688821I0J-303D01*
G01Y1678815D01*
G02X1280149Y1678512I-303J0D01*
G01X1276449D01*
G02X1276146Y1678815I0J303D01*
G01Y1688821D01*
G37*
G36*
G01X1291894D02*
G02X1292197Y1689124I303J0D01*
G01X1295897D01*
G02X1296200Y1688821I0J-303D01*
G01Y1678815D01*
G02X1295897Y1678512I-303J0D01*
G01X1292197D01*
G02X1291894Y1678815I0J303D01*
G01Y1688821D01*
G37*
G36*
G01X1268272Y1684884D02*
G02X1268575Y1685186I303J-1D01*
G01X1272275D01*
G02X1272578Y1684884I1J-302D01*
G01Y1674878D01*
G02X1272275Y1674576I-303J1D01*
G01X1268575D01*
G02X1268272Y1674878I-1J302D01*
G01Y1684884D01*
G37*
G36*
G01X1284020D02*
G02X1284323Y1685186I303J-1D01*
G01X1288023D01*
G02X1288326Y1684884I1J-302D01*
G01Y1674878D01*
G02X1288023Y1674576I-303J1D01*
G01X1284323D01*
G02X1284020Y1674878I-1J302D01*
G01Y1684884D01*
G37*
G36*
G01X1244650Y1728479D02*
Y1731341D01*
G02X1244953Y1731644I303J0D01*
G01X1248653D01*
G02X1248956Y1731341I0J-303D01*
G01Y1721335D01*
G02X1248653Y1721032I-303J0D01*
G01X1244953D01*
G02X1244650Y1721335I0J303D01*
G01Y1724199D01*
G02X1244682Y1724333I303J-1D01*
G01X1245601Y1726208D01*
G03Y1726470I-267J131D01*
G01X1244682Y1728345D01*
G02X1244650Y1728479I270J135D01*
G37*
G36*
G01X1260398D02*
Y1731341D01*
G02X1260701Y1731644I303J0D01*
G01X1264401D01*
G02X1264704Y1731341I0J-303D01*
G01Y1721335D01*
G02X1264401Y1721032I-303J0D01*
G01X1260701D01*
G02X1260398Y1721335I0J303D01*
G01Y1724199D01*
G02X1260430Y1724333I303J-1D01*
G01X1261349Y1726208D01*
G03Y1726470I-267J131D01*
G01X1260430Y1728345D01*
G02X1260398Y1728479I270J135D01*
G37*
G36*
G01X1236776Y1724542D02*
Y1727404D01*
G02X1237079Y1727706I303J-1D01*
G01X1240779D01*
G02X1241082Y1727404I1J-302D01*
G01Y1717398D01*
G02X1240779Y1717096I-303J1D01*
G01X1237079D01*
G02X1236776Y1717398I-1J302D01*
G01Y1720262D01*
G02X1236808Y1720396I303J-1D01*
G01X1237727Y1722271D01*
G03Y1722533I-267J131D01*
G01X1236808Y1724408D01*
G02X1236776Y1724542I270J135D01*
G37*
G36*
G01X1252524D02*
Y1727404D01*
G02X1252827Y1727706I303J-1D01*
G01X1256527D01*
G02X1256830Y1727404I1J-302D01*
G01Y1717398D01*
G02X1256527Y1717096I-303J1D01*
G01X1252827D01*
G02X1252524Y1717398I-1J302D01*
G01Y1720262D01*
G02X1252556Y1720396I303J-1D01*
G01X1253475Y1722271D01*
G03Y1722533I-267J131D01*
G01X1252556Y1724408D01*
G02X1252524Y1724542I270J135D01*
G37*
G36*
G01X1244650Y1714306D02*
Y1717168D01*
G02X1244952Y1717470I302J0D01*
G01X1248652D01*
G02X1248954Y1717168I0J-302D01*
G01Y1707162D01*
G02X1248652Y1706860I-302J0D01*
G01X1244952D01*
G02X1244650Y1707162I0J302D01*
G01Y1710026D01*
G02X1244681Y1710160I302J1D01*
G01X1245600Y1712035D01*
G03Y1712297I-267J131D01*
G01X1244681Y1714172D01*
G02X1244650Y1714306I271J133D01*
G37*
G36*
G01X1260398D02*
Y1717168D01*
G02X1260700Y1717470I302J0D01*
G01X1264400D01*
G02X1264702Y1717168I0J-302D01*
G01Y1707162D01*
G02X1264400Y1706860I-302J0D01*
G01X1260700D01*
G02X1260398Y1707162I0J302D01*
G01Y1710026D01*
G02X1260429Y1710160I302J1D01*
G01X1261348Y1712035D01*
G03Y1712297I-267J131D01*
G01X1260429Y1714172D01*
G02X1260398Y1714306I271J133D01*
G37*
G36*
G01X1236776Y1710369D02*
Y1713231D01*
G02X1237078Y1713534I302J1D01*
G01X1240778D01*
G02X1241080Y1713231I-1J-303D01*
G01Y1703225D01*
G02X1240778Y1702922I-302J-1D01*
G01X1237078D01*
G02X1236776Y1703225I1J303D01*
G01Y1706089D01*
G02X1236807Y1706223I302J1D01*
G01X1237726Y1708098D01*
G03Y1708360I-267J131D01*
G01X1236807Y1710235D01*
G02X1236776Y1710369I271J133D01*
G37*
G36*
G01X1252524D02*
Y1713231D01*
G02X1252826Y1713534I302J1D01*
G01X1256526D01*
G02X1256828Y1713231I-1J-303D01*
G01Y1703225D01*
G02X1256526Y1702922I-302J-1D01*
G01X1252826D01*
G02X1252524Y1703225I1J303D01*
G01Y1706089D01*
G02X1252555Y1706223I302J1D01*
G01X1253474Y1708098D01*
G03Y1708360I-267J131D01*
G01X1252555Y1710235D01*
G02X1252524Y1710369I271J133D01*
G37*
G36*
G01X1244650Y1702994D02*
G02X1244953Y1703296I303J-1D01*
G01X1248653D01*
G02X1248956Y1702994I1J-302D01*
G01Y1692988D01*
G02X1248653Y1692686I-303J1D01*
G01X1244953D01*
G02X1244650Y1692988I-1J302D01*
G01Y1702994D01*
G37*
G36*
G01X1260398D02*
G02X1260701Y1703296I303J-1D01*
G01X1264401D01*
G02X1264704Y1702994I1J-302D01*
G01Y1692988D01*
G02X1264401Y1692686I-303J1D01*
G01X1260701D01*
G02X1260398Y1692988I-1J302D01*
G01Y1702994D01*
G37*
G36*
G01X1236776Y1699057D02*
G02X1237079Y1699360I303J0D01*
G01X1240779D01*
G02X1241082Y1699057I0J-303D01*
G01Y1689051D01*
G02X1240779Y1688748I-303J0D01*
G01X1237079D01*
G02X1236776Y1689051I0J303D01*
G01Y1699057D01*
G37*
G36*
G01X1252524D02*
G02X1252827Y1699360I303J0D01*
G01X1256527D01*
G02X1256830Y1699057I0J-303D01*
G01Y1689051D01*
G02X1256527Y1688748I-303J0D01*
G01X1252827D01*
G02X1252524Y1689051I0J303D01*
G01Y1699057D01*
G37*
G36*
G01X1244650Y1688821D02*
G02X1244953Y1689124I303J0D01*
G01X1248653D01*
G02X1248956Y1688821I0J-303D01*
G01Y1678815D01*
G02X1248653Y1678512I-303J0D01*
G01X1244953D01*
G02X1244650Y1678815I0J303D01*
G01Y1688821D01*
G37*
G36*
G01X1260398D02*
G02X1260701Y1689124I303J0D01*
G01X1264401D01*
G02X1264704Y1688821I0J-303D01*
G01Y1678815D01*
G02X1264401Y1678512I-303J0D01*
G01X1260701D01*
G02X1260398Y1678815I0J303D01*
G01Y1688821D01*
G37*
G36*
G01X1236776Y1684884D02*
G02X1237079Y1685186I303J-1D01*
G01X1240779D01*
G02X1241082Y1684884I1J-302D01*
G01Y1674878D01*
G02X1240779Y1674576I-303J1D01*
G01X1237079D01*
G02X1236776Y1674878I-1J302D01*
G01Y1684884D01*
G37*
G36*
G01X1252524D02*
G02X1252827Y1685186I303J-1D01*
G01X1256527D01*
G02X1256830Y1684884I1J-302D01*
G01Y1674878D01*
G02X1256527Y1674576I-303J1D01*
G01X1252827D01*
G02X1252524Y1674878I-1J302D01*
G01Y1684884D01*
G37*
G36*
G01X599374Y1728479D02*
Y1731341D01*
G02X599677Y1731644I303J0D01*
G01X603377D01*
G02X603680Y1731341I0J-303D01*
G01Y1721335D01*
G02X603377Y1721032I-303J0D01*
G01X599677D01*
G02X599374Y1721335I0J303D01*
G01Y1724199D01*
G02X599406Y1724333I303J-1D01*
G01X600325Y1726208D01*
G03Y1726470I-267J131D01*
G01X599406Y1728345D01*
G02X599374Y1728479I270J135D01*
G37*
G36*
G01X615122D02*
Y1731341D01*
G02X615425Y1731644I303J0D01*
G01X619125D01*
G02X619428Y1731341I0J-303D01*
G01Y1721335D01*
G02X619125Y1721032I-303J0D01*
G01X615425D01*
G02X615122Y1721335I0J303D01*
G01Y1724199D01*
G02X615154Y1724333I303J-1D01*
G01X616073Y1726208D01*
G03Y1726470I-267J131D01*
G01X615154Y1728345D01*
G02X615122Y1728479I270J135D01*
G37*
G36*
G01X591500Y1724542D02*
Y1727404D01*
G02X591803Y1727706I303J-1D01*
G01X595503D01*
G02X595806Y1727404I1J-302D01*
G01Y1717398D01*
G02X595503Y1717096I-303J1D01*
G01X591803D01*
G02X591500Y1717398I-1J302D01*
G01Y1720262D01*
G02X591532Y1720396I303J-1D01*
G01X592451Y1722271D01*
G03Y1722533I-267J131D01*
G01X591532Y1724408D01*
G02X591500Y1724542I270J135D01*
G37*
G36*
G01X607248D02*
Y1727404D01*
G02X607551Y1727706I303J-1D01*
G01X611251D01*
G02X611554Y1727404I1J-302D01*
G01Y1717398D01*
G02X611251Y1717096I-303J1D01*
G01X607551D01*
G02X607248Y1717398I-1J302D01*
G01Y1720262D01*
G02X607280Y1720396I303J-1D01*
G01X608199Y1722271D01*
G03Y1722533I-267J131D01*
G01X607280Y1724408D01*
G02X607248Y1724542I270J135D01*
G37*
G36*
G01X599376Y1714306D02*
Y1717168D01*
G02X599678Y1717470I302J0D01*
G01X603378D01*
G02X603680Y1717168I0J-302D01*
G01Y1707162D01*
G02X603378Y1706860I-302J0D01*
G01X599678D01*
G02X599376Y1707162I0J302D01*
G01Y1710026D01*
G02X599407Y1710160I302J1D01*
G01X600326Y1712035D01*
G03Y1712297I-267J131D01*
G01X599407Y1714172D01*
G02X599376Y1714306I271J133D01*
G37*
G36*
G01X615124D02*
Y1717168D01*
G02X615426Y1717470I302J0D01*
G01X619126D01*
G02X619428Y1717168I0J-302D01*
G01Y1707162D01*
G02X619126Y1706860I-302J0D01*
G01X615426D01*
G02X615124Y1707162I0J302D01*
G01Y1710026D01*
G02X615155Y1710160I302J1D01*
G01X616074Y1712035D01*
G03Y1712297I-267J131D01*
G01X615155Y1714172D01*
G02X615124Y1714306I271J133D01*
G37*
G36*
G01X591502Y1710369D02*
Y1713231D01*
G02X591804Y1713534I302J1D01*
G01X595504D01*
G02X595806Y1713231I-1J-303D01*
G01Y1703225D01*
G02X595504Y1702922I-302J-1D01*
G01X591804D01*
G02X591502Y1703225I1J303D01*
G01Y1706089D01*
G02X591533Y1706223I302J1D01*
G01X592452Y1708098D01*
G03Y1708360I-267J131D01*
G01X591533Y1710235D01*
G02X591502Y1710369I271J133D01*
G37*
G36*
G01X607250D02*
Y1713231D01*
G02X607552Y1713534I302J1D01*
G01X611252D01*
G02X611554Y1713231I-1J-303D01*
G01Y1703225D01*
G02X611252Y1702922I-302J-1D01*
G01X607552D01*
G02X607250Y1703225I1J303D01*
G01Y1706089D01*
G02X607281Y1706223I302J1D01*
G01X608200Y1708098D01*
G03Y1708360I-267J131D01*
G01X607281Y1710235D01*
G02X607250Y1710369I271J133D01*
G37*
G36*
G01X599374Y1702995D02*
G02X599677Y1703298I303J0D01*
G01X603377D01*
G02X603680Y1702995I0J-303D01*
G01Y1692989D01*
G02X603377Y1692686I-303J0D01*
G01X599677D01*
G02X599374Y1692989I0J303D01*
G01Y1702995D01*
G37*
G36*
G01X615122D02*
G02X615425Y1703298I303J0D01*
G01X619125D01*
G02X619428Y1702995I0J-303D01*
G01Y1692989D01*
G02X619125Y1692686I-303J0D01*
G01X615425D01*
G02X615122Y1692989I0J303D01*
G01Y1702995D01*
G37*
G36*
G01X591500Y1699058D02*
G02X591803Y1699360I303J-1D01*
G01X595503D01*
G02X595806Y1699058I1J-302D01*
G01Y1689052D01*
G02X595503Y1688750I-303J1D01*
G01X591803D01*
G02X591500Y1689052I-1J302D01*
G01Y1699058D01*
G37*
G36*
G01X607248D02*
G02X607551Y1699360I303J-1D01*
G01X611251D01*
G02X611554Y1699058I1J-302D01*
G01Y1689052D01*
G02X611251Y1688750I-303J1D01*
G01X607551D01*
G02X607248Y1689052I-1J302D01*
G01Y1699058D01*
G37*
G36*
G01X599374Y1688821D02*
G02X599677Y1689124I303J0D01*
G01X603377D01*
G02X603680Y1688821I0J-303D01*
G01Y1678815D01*
G02X603377Y1678512I-303J0D01*
G01X599677D01*
G02X599374Y1678815I0J303D01*
G01Y1688821D01*
G37*
G36*
G01X615122D02*
G02X615425Y1689124I303J0D01*
G01X619125D01*
G02X619428Y1688821I0J-303D01*
G01Y1678815D01*
G02X619125Y1678512I-303J0D01*
G01X615425D01*
G02X615122Y1678815I0J303D01*
G01Y1688821D01*
G37*
G36*
G01X591500Y1684884D02*
G02X591803Y1685186I303J-1D01*
G01X595503D01*
G02X595806Y1684884I1J-302D01*
G01Y1674878D01*
G02X595503Y1674576I-303J1D01*
G01X591803D01*
G02X591500Y1674878I-1J302D01*
G01Y1684884D01*
G37*
G36*
G01X607248D02*
G02X607551Y1685186I303J-1D01*
G01X611251D01*
G02X611554Y1684884I1J-302D01*
G01Y1674878D01*
G02X611251Y1674576I-303J1D01*
G01X607551D01*
G02X607248Y1674878I-1J302D01*
G01Y1684884D01*
G37*
G36*
G01X567878Y1728479D02*
Y1731341D01*
G02X568181Y1731644I303J0D01*
G01X571881D01*
G02X572184Y1731341I0J-303D01*
G01Y1721335D01*
G02X571881Y1721032I-303J0D01*
G01X568181D01*
G02X567878Y1721335I0J303D01*
G01Y1724199D01*
G02X567910Y1724333I303J-1D01*
G01X568829Y1726208D01*
G03Y1726470I-267J131D01*
G01X567910Y1728345D01*
G02X567878Y1728479I270J135D01*
G37*
G36*
G01X583626D02*
Y1731341D01*
G02X583929Y1731644I303J0D01*
G01X587629D01*
G02X587932Y1731341I0J-303D01*
G01Y1721335D01*
G02X587629Y1721032I-303J0D01*
G01X583929D01*
G02X583626Y1721335I0J303D01*
G01Y1724199D01*
G02X583658Y1724333I303J-1D01*
G01X584577Y1726208D01*
G03Y1726470I-267J131D01*
G01X583658Y1728345D01*
G02X583626Y1728479I270J135D01*
G37*
G36*
G01X560004Y1724542D02*
Y1727404D01*
G02X560307Y1727706I303J-1D01*
G01X564007D01*
G02X564310Y1727404I1J-302D01*
G01Y1717398D01*
G02X564007Y1717096I-303J1D01*
G01X560307D01*
G02X560004Y1717398I-1J302D01*
G01Y1720262D01*
G02X560036Y1720396I303J-1D01*
G01X560955Y1722271D01*
G03Y1722533I-267J131D01*
G01X560036Y1724408D01*
G02X560004Y1724542I270J135D01*
G37*
G36*
G01X575752D02*
Y1727404D01*
G02X576055Y1727706I303J-1D01*
G01X579755D01*
G02X580058Y1727404I1J-302D01*
G01Y1717398D01*
G02X579755Y1717096I-303J1D01*
G01X576055D01*
G02X575752Y1717398I-1J302D01*
G01Y1720262D01*
G02X575784Y1720396I303J-1D01*
G01X576703Y1722271D01*
G03Y1722533I-267J131D01*
G01X575784Y1724408D01*
G02X575752Y1724542I270J135D01*
G37*
G36*
G01X567880Y1714306D02*
Y1717168D01*
G02X568182Y1717470I302J0D01*
G01X571882D01*
G02X572184Y1717168I0J-302D01*
G01Y1707162D01*
G02X571882Y1706860I-302J0D01*
G01X568182D01*
G02X567880Y1707162I0J302D01*
G01Y1710026D01*
G02X567911Y1710160I302J1D01*
G01X568830Y1712035D01*
G03Y1712297I-267J131D01*
G01X567911Y1714172D01*
G02X567880Y1714306I271J133D01*
G37*
G36*
G01X583628D02*
Y1717168D01*
G02X583930Y1717470I302J0D01*
G01X587630D01*
G02X587932Y1717168I0J-302D01*
G01Y1707162D01*
G02X587630Y1706860I-302J0D01*
G01X583930D01*
G02X583628Y1707162I0J302D01*
G01Y1710026D01*
G02X583659Y1710160I302J1D01*
G01X584578Y1712035D01*
G03Y1712297I-267J131D01*
G01X583659Y1714172D01*
G02X583628Y1714306I271J133D01*
G37*
G36*
G01X560006Y1710369D02*
Y1713231D01*
G02X560308Y1713534I302J1D01*
G01X564008D01*
G02X564310Y1713231I-1J-303D01*
G01Y1703225D01*
G02X564008Y1702922I-302J-1D01*
G01X560308D01*
G02X560006Y1703225I1J303D01*
G01Y1706089D01*
G02X560037Y1706223I302J1D01*
G01X560956Y1708098D01*
G03Y1708360I-267J131D01*
G01X560037Y1710235D01*
G02X560006Y1710369I271J133D01*
G37*
G36*
G01X575754D02*
Y1713231D01*
G02X576056Y1713534I302J1D01*
G01X579756D01*
G02X580058Y1713231I-1J-303D01*
G01Y1703225D01*
G02X579756Y1702922I-302J-1D01*
G01X576056D01*
G02X575754Y1703225I1J303D01*
G01Y1706089D01*
G02X575785Y1706223I302J1D01*
G01X576704Y1708098D01*
G03Y1708360I-267J131D01*
G01X575785Y1710235D01*
G02X575754Y1710369I271J133D01*
G37*
G36*
G01X567878Y1702995D02*
G02X568181Y1703298I303J0D01*
G01X571881D01*
G02X572184Y1702995I0J-303D01*
G01Y1692989D01*
G02X571881Y1692686I-303J0D01*
G01X568181D01*
G02X567878Y1692989I0J303D01*
G01Y1702995D01*
G37*
G36*
G01X583626D02*
G02X583929Y1703298I303J0D01*
G01X587629D01*
G02X587932Y1702995I0J-303D01*
G01Y1692989D01*
G02X587629Y1692686I-303J0D01*
G01X583929D01*
G02X583626Y1692989I0J303D01*
G01Y1702995D01*
G37*
G36*
G01X560004Y1699058D02*
G02X560307Y1699360I303J-1D01*
G01X564007D01*
G02X564310Y1699058I1J-302D01*
G01Y1689052D01*
G02X564007Y1688750I-303J1D01*
G01X560307D01*
G02X560004Y1689052I-1J302D01*
G01Y1699058D01*
G37*
G36*
G01X575752D02*
G02X576055Y1699360I303J-1D01*
G01X579755D01*
G02X580058Y1699058I1J-302D01*
G01Y1689052D01*
G02X579755Y1688750I-303J1D01*
G01X576055D01*
G02X575752Y1689052I-1J302D01*
G01Y1699058D01*
G37*
G36*
G01X567878Y1688821D02*
G02X568181Y1689124I303J0D01*
G01X571881D01*
G02X572184Y1688821I0J-303D01*
G01Y1678815D01*
G02X571881Y1678512I-303J0D01*
G01X568181D01*
G02X567878Y1678815I0J303D01*
G01Y1688821D01*
G37*
G36*
G01X583626D02*
G02X583929Y1689124I303J0D01*
G01X587629D01*
G02X587932Y1688821I0J-303D01*
G01Y1678815D01*
G02X587629Y1678512I-303J0D01*
G01X583929D01*
G02X583626Y1678815I0J303D01*
G01Y1688821D01*
G37*
G36*
G01X560004Y1684884D02*
G02X560307Y1685186I303J-1D01*
G01X564007D01*
G02X564310Y1684884I1J-302D01*
G01Y1674878D01*
G02X564007Y1674576I-303J1D01*
G01X560307D01*
G02X560004Y1674878I-1J302D01*
G01Y1684884D01*
G37*
G36*
G01X575752D02*
G02X576055Y1685186I303J-1D01*
G01X579755D01*
G02X580058Y1684884I1J-302D01*
G01Y1674878D01*
G02X579755Y1674576I-303J1D01*
G01X576055D01*
G02X575752Y1674878I-1J302D01*
G01Y1684884D01*
G37*
G36*
G01X532446Y1728479D02*
Y1731341D01*
G02X532748Y1731644I302J1D01*
G01X536448D01*
G02X536750Y1731341I-1J-303D01*
G01Y1721335D01*
G02X536448Y1721032I-302J-1D01*
G01X532748D01*
G02X532446Y1721335I1J303D01*
G01Y1724199D01*
G02X532477Y1724333I302J1D01*
G01X533396Y1726208D01*
G03Y1726470I-267J131D01*
G01X532477Y1728345D01*
G02X532446Y1728479I271J133D01*
G37*
G36*
G01X548194D02*
Y1731341D01*
G02X548496Y1731644I302J1D01*
G01X552196D01*
G02X552498Y1731341I-1J-303D01*
G01Y1721335D01*
G02X552196Y1721032I-302J-1D01*
G01X548496D01*
G02X548194Y1721335I1J303D01*
G01Y1724199D01*
G02X548225Y1724333I302J1D01*
G01X549144Y1726208D01*
G03Y1726470I-267J131D01*
G01X548225Y1728345D01*
G02X548194Y1728479I271J133D01*
G37*
G36*
G01X524572Y1724542D02*
Y1727404D01*
G02X524874Y1727706I302J0D01*
G01X528574D01*
G02X528876Y1727404I0J-302D01*
G01Y1717398D01*
G02X528574Y1717096I-302J0D01*
G01X524874D01*
G02X524572Y1717398I0J302D01*
G01Y1720262D01*
G02X524603Y1720396I302J1D01*
G01X525522Y1722271D01*
G03Y1722533I-267J131D01*
G01X524603Y1724408D01*
G02X524572Y1724542I271J133D01*
G37*
G36*
G01X540320D02*
Y1727404D01*
G02X540622Y1727706I302J0D01*
G01X544322D01*
G02X544624Y1727404I0J-302D01*
G01Y1717398D01*
G02X544322Y1717096I-302J0D01*
G01X540622D01*
G02X540320Y1717398I0J302D01*
G01Y1720262D01*
G02X540351Y1720396I302J1D01*
G01X541270Y1722271D01*
G03Y1722533I-267J131D01*
G01X540351Y1724408D01*
G02X540320Y1724542I271J133D01*
G37*
G36*
G01X532446Y1714306D02*
Y1717168D01*
G02X532748Y1717470I302J0D01*
G01X536448D01*
G02X536750Y1717168I0J-302D01*
G01Y1707162D01*
G02X536448Y1706860I-302J0D01*
G01X532748D01*
G02X532446Y1707162I0J302D01*
G01Y1710026D01*
G02X532477Y1710160I302J1D01*
G01X533396Y1712035D01*
G03Y1712297I-267J131D01*
G01X532477Y1714172D01*
G02X532446Y1714306I271J133D01*
G37*
G36*
G01X548194D02*
Y1717168D01*
G02X548496Y1717470I302J0D01*
G01X552196D01*
G02X552498Y1717168I0J-302D01*
G01Y1707162D01*
G02X552196Y1706860I-302J0D01*
G01X548496D01*
G02X548194Y1707162I0J302D01*
G01Y1710026D01*
G02X548225Y1710160I302J1D01*
G01X549144Y1712035D01*
G03Y1712297I-267J131D01*
G01X548225Y1714172D01*
G02X548194Y1714306I271J133D01*
G37*
G36*
G01X524572Y1710369D02*
Y1713231D01*
G02X524874Y1713534I302J1D01*
G01X528574D01*
G02X528876Y1713231I-1J-303D01*
G01Y1703225D01*
G02X528574Y1702922I-302J-1D01*
G01X524874D01*
G02X524572Y1703225I1J303D01*
G01Y1706089D01*
G02X524603Y1706223I302J1D01*
G01X525522Y1708098D01*
G03Y1708360I-267J131D01*
G01X524603Y1710235D01*
G02X524572Y1710369I271J133D01*
G37*
G36*
G01X540320D02*
Y1713231D01*
G02X540622Y1713534I302J1D01*
G01X544322D01*
G02X544624Y1713231I-1J-303D01*
G01Y1703225D01*
G02X544322Y1702922I-302J-1D01*
G01X540622D01*
G02X540320Y1703225I1J303D01*
G01Y1706089D01*
G02X540351Y1706223I302J1D01*
G01X541270Y1708098D01*
G03Y1708360I-267J131D01*
G01X540351Y1710235D01*
G02X540320Y1710369I271J133D01*
G37*
G36*
G01X532446Y1702995D02*
G02X532748Y1703298I302J1D01*
G01X536448D01*
G02X536750Y1702995I-1J-303D01*
G01Y1692989D01*
G02X536448Y1692686I-302J-1D01*
G01X532748D01*
G02X532446Y1692989I1J303D01*
G01Y1702995D01*
G37*
G36*
G01X548194D02*
G02X548496Y1703298I302J1D01*
G01X552196D01*
G02X552498Y1702995I-1J-303D01*
G01Y1692989D01*
G02X552196Y1692686I-302J-1D01*
G01X548496D01*
G02X548194Y1692989I1J303D01*
G01Y1702995D01*
G37*
G36*
G01X524572Y1699058D02*
G02X524874Y1699360I302J0D01*
G01X528574D01*
G02X528876Y1699058I0J-302D01*
G01Y1689052D01*
G02X528574Y1688750I-302J0D01*
G01X524874D01*
G02X524572Y1689052I0J302D01*
G01Y1699058D01*
G37*
G36*
G01X540320D02*
G02X540622Y1699360I302J0D01*
G01X544322D01*
G02X544624Y1699058I0J-302D01*
G01Y1689052D01*
G02X544322Y1688750I-302J0D01*
G01X540622D01*
G02X540320Y1689052I0J302D01*
G01Y1699058D01*
G37*
G36*
G01X532446Y1688821D02*
G02X532748Y1689124I302J1D01*
G01X536448D01*
G02X536750Y1688821I-1J-303D01*
G01Y1678815D01*
G02X536448Y1678512I-302J-1D01*
G01X532748D01*
G02X532446Y1678815I1J303D01*
G01Y1688821D01*
G37*
G36*
G01X548194D02*
G02X548496Y1689124I302J1D01*
G01X552196D01*
G02X552498Y1688821I-1J-303D01*
G01Y1678815D01*
G02X552196Y1678512I-302J-1D01*
G01X548496D01*
G02X548194Y1678815I1J303D01*
G01Y1688821D01*
G37*
G36*
G01X524572Y1684884D02*
G02X524874Y1685186I302J0D01*
G01X528574D01*
G02X528876Y1684884I0J-302D01*
G01Y1674878D01*
G02X528574Y1674576I-302J0D01*
G01X524874D01*
G02X524572Y1674878I0J302D01*
G01Y1684884D01*
G37*
G36*
G01X540320D02*
G02X540622Y1685186I302J0D01*
G01X544322D01*
G02X544624Y1684884I0J-302D01*
G01Y1674878D01*
G02X544322Y1674576I-302J0D01*
G01X540622D01*
G02X540320Y1674878I0J302D01*
G01Y1684884D01*
G37*
G36*
G01X500950Y1728479D02*
Y1731341D01*
G02X501252Y1731644I302J1D01*
G01X504952D01*
G02X505254Y1731341I-1J-303D01*
G01Y1721335D01*
G02X504952Y1721032I-302J-1D01*
G01X501252D01*
G02X500950Y1721335I1J303D01*
G01Y1724199D01*
G02X500981Y1724333I302J1D01*
G01X501900Y1726208D01*
G03Y1726470I-267J131D01*
G01X500981Y1728345D01*
G02X500950Y1728479I271J133D01*
G37*
G36*
G01X516698D02*
Y1731341D01*
G02X517000Y1731644I302J1D01*
G01X520700D01*
G02X521002Y1731341I-1J-303D01*
G01Y1721335D01*
G02X520700Y1721032I-302J-1D01*
G01X517000D01*
G02X516698Y1721335I1J303D01*
G01Y1724199D01*
G02X516729Y1724333I302J1D01*
G01X517648Y1726208D01*
G03Y1726470I-267J131D01*
G01X516729Y1728345D01*
G02X516698Y1728479I271J133D01*
G37*
G36*
G01X493076Y1724542D02*
Y1727404D01*
G02X493378Y1727706I302J0D01*
G01X497078D01*
G02X497380Y1727404I0J-302D01*
G01Y1717398D01*
G02X497078Y1717096I-302J0D01*
G01X493378D01*
G02X493076Y1717398I0J302D01*
G01Y1720262D01*
G02X493107Y1720396I302J1D01*
G01X494026Y1722271D01*
G03Y1722533I-267J131D01*
G01X493107Y1724408D01*
G02X493076Y1724542I271J133D01*
G37*
G36*
G01X508824D02*
Y1727404D01*
G02X509126Y1727706I302J0D01*
G01X512826D01*
G02X513128Y1727404I0J-302D01*
G01Y1717398D01*
G02X512826Y1717096I-302J0D01*
G01X509126D01*
G02X508824Y1717398I0J302D01*
G01Y1720262D01*
G02X508855Y1720396I302J1D01*
G01X509774Y1722271D01*
G03Y1722533I-267J131D01*
G01X508855Y1724408D01*
G02X508824Y1724542I271J133D01*
G37*
G36*
G01X500950Y1714306D02*
Y1717168D01*
G02X501252Y1717470I302J0D01*
G01X504952D01*
G02X505254Y1717168I0J-302D01*
G01Y1707162D01*
G02X504952Y1706860I-302J0D01*
G01X501252D01*
G02X500950Y1707162I0J302D01*
G01Y1710026D01*
G02X500981Y1710160I302J1D01*
G01X501900Y1712035D01*
G03Y1712297I-267J131D01*
G01X500981Y1714172D01*
G02X500950Y1714306I271J133D01*
G37*
G36*
G01X516698D02*
Y1717168D01*
G02X517000Y1717470I302J0D01*
G01X520700D01*
G02X521002Y1717168I0J-302D01*
G01Y1707162D01*
G02X520700Y1706860I-302J0D01*
G01X517000D01*
G02X516698Y1707162I0J302D01*
G01Y1710026D01*
G02X516729Y1710160I302J1D01*
G01X517648Y1712035D01*
G03Y1712297I-267J131D01*
G01X516729Y1714172D01*
G02X516698Y1714306I271J133D01*
G37*
G36*
G01X493076Y1710369D02*
Y1713231D01*
G02X493378Y1713534I302J1D01*
G01X497078D01*
G02X497380Y1713231I-1J-303D01*
G01Y1703225D01*
G02X497078Y1702922I-302J-1D01*
G01X493378D01*
G02X493076Y1703225I1J303D01*
G01Y1706089D01*
G02X493107Y1706223I302J1D01*
G01X494026Y1708098D01*
G03Y1708360I-267J131D01*
G01X493107Y1710235D01*
G02X493076Y1710369I271J133D01*
G37*
G36*
G01X508824D02*
Y1713231D01*
G02X509126Y1713534I302J1D01*
G01X512826D01*
G02X513128Y1713231I-1J-303D01*
G01Y1703225D01*
G02X512826Y1702922I-302J-1D01*
G01X509126D01*
G02X508824Y1703225I1J303D01*
G01Y1706089D01*
G02X508855Y1706223I302J1D01*
G01X509774Y1708098D01*
G03Y1708360I-267J131D01*
G01X508855Y1710235D01*
G02X508824Y1710369I271J133D01*
G37*
G36*
G01X500950Y1702995D02*
G02X501252Y1703298I302J1D01*
G01X504952D01*
G02X505254Y1702995I-1J-303D01*
G01Y1692989D01*
G02X504952Y1692686I-302J-1D01*
G01X501252D01*
G02X500950Y1692989I1J303D01*
G01Y1702995D01*
G37*
G36*
G01X516698D02*
G02X517000Y1703298I302J1D01*
G01X520700D01*
G02X521002Y1702995I-1J-303D01*
G01Y1692989D01*
G02X520700Y1692686I-302J-1D01*
G01X517000D01*
G02X516698Y1692989I1J303D01*
G01Y1702995D01*
G37*
G36*
G01X493076Y1699058D02*
G02X493378Y1699360I302J0D01*
G01X497078D01*
G02X497380Y1699058I0J-302D01*
G01Y1689052D01*
G02X497078Y1688750I-302J0D01*
G01X493378D01*
G02X493076Y1689052I0J302D01*
G01Y1699058D01*
G37*
G36*
G01X508824D02*
G02X509126Y1699360I302J0D01*
G01X512826D01*
G02X513128Y1699058I0J-302D01*
G01Y1689052D01*
G02X512826Y1688750I-302J0D01*
G01X509126D01*
G02X508824Y1689052I0J302D01*
G01Y1699058D01*
G37*
G36*
G01X500950Y1688821D02*
G02X501252Y1689124I302J1D01*
G01X504952D01*
G02X505254Y1688821I-1J-303D01*
G01Y1678815D01*
G02X504952Y1678512I-302J-1D01*
G01X501252D01*
G02X500950Y1678815I1J303D01*
G01Y1688821D01*
G37*
G36*
G01X516698D02*
G02X517000Y1689124I302J1D01*
G01X520700D01*
G02X521002Y1688821I-1J-303D01*
G01Y1678815D01*
G02X520700Y1678512I-302J-1D01*
G01X517000D01*
G02X516698Y1678815I1J303D01*
G01Y1688821D01*
G37*
G36*
G01X493076Y1684884D02*
G02X493378Y1685186I302J0D01*
G01X497078D01*
G02X497380Y1684884I0J-302D01*
G01Y1674878D01*
G02X497078Y1674576I-302J0D01*
G01X493378D01*
G02X493076Y1674878I0J302D01*
G01Y1684884D01*
G37*
G36*
G01X508824D02*
G02X509126Y1685186I302J0D01*
G01X512826D01*
G02X513128Y1684884I0J-302D01*
G01Y1674878D01*
G02X512826Y1674576I-302J0D01*
G01X509126D01*
G02X508824Y1674878I0J302D01*
G01Y1684884D01*
G37*
G36*
G01X335202Y1728479D02*
Y1731341D01*
G02X335504Y1731644I302J1D01*
G01X339204D01*
G02X339506Y1731341I-1J-303D01*
G01Y1721335D01*
G02X339204Y1721032I-302J-1D01*
G01X335504D01*
G02X335202Y1721335I1J303D01*
G01Y1724199D01*
G02X335233Y1724333I302J1D01*
G01X336152Y1726208D01*
G03Y1726470I-267J131D01*
G01X335233Y1728345D01*
G02X335202Y1728479I271J133D01*
G37*
G36*
G01X350950D02*
Y1731341D01*
G02X351252Y1731644I302J1D01*
G01X354952D01*
G02X355254Y1731341I-1J-303D01*
G01Y1721335D01*
G02X354952Y1721032I-302J-1D01*
G01X351252D01*
G02X350950Y1721335I1J303D01*
G01Y1724199D01*
G02X350981Y1724333I302J1D01*
G01X351900Y1726208D01*
G03Y1726470I-267J131D01*
G01X350981Y1728345D01*
G02X350950Y1728479I271J133D01*
G37*
G36*
G01X327328Y1724542D02*
Y1727404D01*
G02X327630Y1727706I302J0D01*
G01X331330D01*
G02X331632Y1727404I0J-302D01*
G01Y1717398D01*
G02X331330Y1717096I-302J0D01*
G01X327630D01*
G02X327328Y1717398I0J302D01*
G01Y1720262D01*
G02X327359Y1720396I302J1D01*
G01X328278Y1722271D01*
G03Y1722533I-267J131D01*
G01X327359Y1724408D01*
G02X327328Y1724542I271J133D01*
G37*
G36*
G01X343076D02*
Y1727404D01*
G02X343378Y1727706I302J0D01*
G01X347078D01*
G02X347380Y1727404I0J-302D01*
G01Y1717398D01*
G02X347078Y1717096I-302J0D01*
G01X343378D01*
G02X343076Y1717398I0J302D01*
G01Y1720262D01*
G02X343107Y1720396I302J1D01*
G01X344026Y1722271D01*
G03Y1722533I-267J131D01*
G01X343107Y1724408D01*
G02X343076Y1724542I271J133D01*
G37*
G36*
G01X335202Y1714306D02*
Y1717168D01*
G02X335504Y1717470I302J0D01*
G01X339204D01*
G02X339506Y1717168I0J-302D01*
G01Y1707162D01*
G02X339204Y1706860I-302J0D01*
G01X335504D01*
G02X335202Y1707162I0J302D01*
G01Y1710026D01*
G02X335233Y1710160I302J1D01*
G01X336152Y1712035D01*
G03Y1712297I-267J131D01*
G01X335233Y1714172D01*
G02X335202Y1714306I271J133D01*
G37*
G36*
G01X350950D02*
Y1717168D01*
G02X351252Y1717470I302J0D01*
G01X354952D01*
G02X355254Y1717168I0J-302D01*
G01Y1707162D01*
G02X354952Y1706860I-302J0D01*
G01X351252D01*
G02X350950Y1707162I0J302D01*
G01Y1710026D01*
G02X350981Y1710160I302J1D01*
G01X351900Y1712035D01*
G03Y1712297I-267J131D01*
G01X350981Y1714172D01*
G02X350950Y1714306I271J133D01*
G37*
G36*
G01X327328Y1710369D02*
Y1713231D01*
G02X327630Y1713534I302J1D01*
G01X331330D01*
G02X331632Y1713231I-1J-303D01*
G01Y1703225D01*
G02X331330Y1702922I-302J-1D01*
G01X327630D01*
G02X327328Y1703225I1J303D01*
G01Y1706089D01*
G02X327359Y1706223I302J1D01*
G01X328278Y1708098D01*
G03Y1708360I-267J131D01*
G01X327359Y1710235D01*
G02X327328Y1710369I271J133D01*
G37*
G36*
G01X343076D02*
Y1713231D01*
G02X343378Y1713534I302J1D01*
G01X347078D01*
G02X347380Y1713231I-1J-303D01*
G01Y1703225D01*
G02X347078Y1702922I-302J-1D01*
G01X343378D01*
G02X343076Y1703225I1J303D01*
G01Y1706089D01*
G02X343107Y1706223I302J1D01*
G01X344026Y1708098D01*
G03Y1708360I-267J131D01*
G01X343107Y1710235D01*
G02X343076Y1710369I271J133D01*
G37*
G36*
G01X335202Y1702994D02*
G02X335504Y1703296I302J0D01*
G01X339204D01*
G02X339506Y1702994I0J-302D01*
G01Y1692988D01*
G02X339204Y1692686I-302J0D01*
G01X335504D01*
G02X335202Y1692988I0J302D01*
G01Y1702994D01*
G37*
G36*
G01X350950D02*
G02X351252Y1703296I302J0D01*
G01X354952D01*
G02X355254Y1702994I0J-302D01*
G01Y1692988D01*
G02X354952Y1692686I-302J0D01*
G01X351252D01*
G02X350950Y1692988I0J302D01*
G01Y1702994D01*
G37*
G36*
G01X327328Y1699057D02*
G02X327630Y1699360I302J1D01*
G01X331330D01*
G02X331632Y1699057I-1J-303D01*
G01Y1689051D01*
G02X331330Y1688748I-302J-1D01*
G01X327630D01*
G02X327328Y1689051I1J303D01*
G01Y1699057D01*
G37*
G36*
G01X343076D02*
G02X343378Y1699360I302J1D01*
G01X347078D01*
G02X347380Y1699057I-1J-303D01*
G01Y1689051D01*
G02X347078Y1688748I-302J-1D01*
G01X343378D01*
G02X343076Y1689051I1J303D01*
G01Y1699057D01*
G37*
G36*
G01X335202Y1688821D02*
G02X335504Y1689124I302J1D01*
G01X339204D01*
G02X339506Y1688821I-1J-303D01*
G01Y1678815D01*
G02X339204Y1678512I-302J-1D01*
G01X335504D01*
G02X335202Y1678815I1J303D01*
G01Y1688821D01*
G37*
G36*
G01X350950D02*
G02X351252Y1689124I302J1D01*
G01X354952D01*
G02X355254Y1688821I-1J-303D01*
G01Y1678815D01*
G02X354952Y1678512I-302J-1D01*
G01X351252D01*
G02X350950Y1678815I1J303D01*
G01Y1688821D01*
G37*
G36*
G01X327328Y1684884D02*
G02X327630Y1685186I302J0D01*
G01X331330D01*
G02X331632Y1684884I0J-302D01*
G01Y1674878D01*
G02X331330Y1674576I-302J0D01*
G01X327630D01*
G02X327328Y1674878I0J302D01*
G01Y1684884D01*
G37*
G36*
G01X343076D02*
G02X343378Y1685186I302J0D01*
G01X347078D01*
G02X347380Y1684884I0J-302D01*
G01Y1674878D01*
G02X347078Y1674576I-302J0D01*
G01X343378D01*
G02X343076Y1674878I0J302D01*
G01Y1684884D01*
G37*
G36*
G01X303706Y1728479D02*
Y1731341D01*
G02X304008Y1731644I302J1D01*
G01X307708D01*
G02X308010Y1731341I-1J-303D01*
G01Y1721335D01*
G02X307708Y1721032I-302J-1D01*
G01X304008D01*
G02X303706Y1721335I1J303D01*
G01Y1724199D01*
G02X303737Y1724333I302J1D01*
G01X304656Y1726208D01*
G03Y1726470I-267J131D01*
G01X303737Y1728345D01*
G02X303706Y1728479I271J133D01*
G37*
G36*
G01X319454D02*
Y1731341D01*
G02X319756Y1731644I302J1D01*
G01X323456D01*
G02X323758Y1731341I-1J-303D01*
G01Y1721335D01*
G02X323456Y1721032I-302J-1D01*
G01X319756D01*
G02X319454Y1721335I1J303D01*
G01Y1724199D01*
G02X319485Y1724333I302J1D01*
G01X320404Y1726208D01*
G03Y1726470I-267J131D01*
G01X319485Y1728345D01*
G02X319454Y1728479I271J133D01*
G37*
G36*
G01X295832Y1724542D02*
Y1727404D01*
G02X296134Y1727706I302J0D01*
G01X299834D01*
G02X300136Y1727404I0J-302D01*
G01Y1717398D01*
G02X299834Y1717096I-302J0D01*
G01X296134D01*
G02X295832Y1717398I0J302D01*
G01Y1720262D01*
G02X295863Y1720396I302J1D01*
G01X296782Y1722271D01*
G03Y1722533I-267J131D01*
G01X295863Y1724408D01*
G02X295832Y1724542I271J133D01*
G37*
G36*
G01X311580D02*
Y1727404D01*
G02X311882Y1727706I302J0D01*
G01X315582D01*
G02X315884Y1727404I0J-302D01*
G01Y1717398D01*
G02X315582Y1717096I-302J0D01*
G01X311882D01*
G02X311580Y1717398I0J302D01*
G01Y1720262D01*
G02X311611Y1720396I302J1D01*
G01X312530Y1722271D01*
G03Y1722533I-267J131D01*
G01X311611Y1724408D01*
G02X311580Y1724542I271J133D01*
G37*
G36*
G01X303706Y1714306D02*
Y1717168D01*
G02X304008Y1717470I302J0D01*
G01X307708D01*
G02X308010Y1717168I0J-302D01*
G01Y1707162D01*
G02X307708Y1706860I-302J0D01*
G01X304008D01*
G02X303706Y1707162I0J302D01*
G01Y1710026D01*
G02X303737Y1710160I302J1D01*
G01X304656Y1712035D01*
G03Y1712297I-267J131D01*
G01X303737Y1714172D01*
G02X303706Y1714306I271J133D01*
G37*
G36*
G01X319454D02*
Y1717168D01*
G02X319756Y1717470I302J0D01*
G01X323456D01*
G02X323758Y1717168I0J-302D01*
G01Y1707162D01*
G02X323456Y1706860I-302J0D01*
G01X319756D01*
G02X319454Y1707162I0J302D01*
G01Y1710026D01*
G02X319485Y1710160I302J1D01*
G01X320404Y1712035D01*
G03Y1712297I-267J131D01*
G01X319485Y1714172D01*
G02X319454Y1714306I271J133D01*
G37*
G36*
G01X295832Y1710369D02*
Y1713231D01*
G02X296134Y1713534I302J1D01*
G01X299834D01*
G02X300136Y1713231I-1J-303D01*
G01Y1703225D01*
G02X299834Y1702922I-302J-1D01*
G01X296134D01*
G02X295832Y1703225I1J303D01*
G01Y1706089D01*
G02X295863Y1706223I302J1D01*
G01X296782Y1708098D01*
G03Y1708360I-267J131D01*
G01X295863Y1710235D01*
G02X295832Y1710369I271J133D01*
G37*
G36*
G01X311580D02*
Y1713231D01*
G02X311882Y1713534I302J1D01*
G01X315582D01*
G02X315884Y1713231I-1J-303D01*
G01Y1703225D01*
G02X315582Y1702922I-302J-1D01*
G01X311882D01*
G02X311580Y1703225I1J303D01*
G01Y1706089D01*
G02X311611Y1706223I302J1D01*
G01X312530Y1708098D01*
G03Y1708360I-267J131D01*
G01X311611Y1710235D01*
G02X311580Y1710369I271J133D01*
G37*
G36*
G01X303706Y1702994D02*
G02X304008Y1703296I302J0D01*
G01X307708D01*
G02X308010Y1702994I0J-302D01*
G01Y1692988D01*
G02X307708Y1692686I-302J0D01*
G01X304008D01*
G02X303706Y1692988I0J302D01*
G01Y1702994D01*
G37*
G36*
G01X319454D02*
G02X319756Y1703296I302J0D01*
G01X323456D01*
G02X323758Y1702994I0J-302D01*
G01Y1692988D01*
G02X323456Y1692686I-302J0D01*
G01X319756D01*
G02X319454Y1692988I0J302D01*
G01Y1702994D01*
G37*
G36*
G01X295832Y1699057D02*
G02X296134Y1699360I302J1D01*
G01X299834D01*
G02X300136Y1699057I-1J-303D01*
G01Y1689051D01*
G02X299834Y1688748I-302J-1D01*
G01X296134D01*
G02X295832Y1689051I1J303D01*
G01Y1699057D01*
G37*
G36*
G01X311580D02*
G02X311882Y1699360I302J1D01*
G01X315582D01*
G02X315884Y1699057I-1J-303D01*
G01Y1689051D01*
G02X315582Y1688748I-302J-1D01*
G01X311882D01*
G02X311580Y1689051I1J303D01*
G01Y1699057D01*
G37*
G36*
G01X303706Y1688821D02*
G02X304008Y1689124I302J1D01*
G01X307708D01*
G02X308010Y1688821I-1J-303D01*
G01Y1678815D01*
G02X307708Y1678512I-302J-1D01*
G01X304008D01*
G02X303706Y1678815I1J303D01*
G01Y1688821D01*
G37*
G36*
G01X319454D02*
G02X319756Y1689124I302J1D01*
G01X323456D01*
G02X323758Y1688821I-1J-303D01*
G01Y1678815D01*
G02X323456Y1678512I-302J-1D01*
G01X319756D01*
G02X319454Y1678815I1J303D01*
G01Y1688821D01*
G37*
G36*
G01X295832Y1684884D02*
G02X296134Y1685186I302J0D01*
G01X299834D01*
G02X300136Y1684884I0J-302D01*
G01Y1674878D01*
G02X299834Y1674576I-302J0D01*
G01X296134D01*
G02X295832Y1674878I0J302D01*
G01Y1684884D01*
G37*
G36*
G01X311580D02*
G02X311882Y1685186I302J0D01*
G01X315582D01*
G02X315884Y1684884I0J-302D01*
G01Y1674878D01*
G02X315582Y1674576I-302J0D01*
G01X311882D01*
G02X311580Y1674878I0J302D01*
G01Y1684884D01*
G37*
G36*
G01X268272Y1728479D02*
Y1731341D01*
G02X268575Y1731644I303J0D01*
G01X272275D01*
G02X272578Y1731341I0J-303D01*
G01Y1721335D01*
G02X272275Y1721032I-303J0D01*
G01X268575D01*
G02X268272Y1721335I0J303D01*
G01Y1724199D01*
G02X268304Y1724333I303J-1D01*
G01X269223Y1726208D01*
G03Y1726470I-267J131D01*
G01X268304Y1728345D01*
G02X268272Y1728479I270J135D01*
G37*
G36*
G01X284020D02*
Y1731341D01*
G02X284323Y1731644I303J0D01*
G01X288023D01*
G02X288326Y1731341I0J-303D01*
G01Y1721335D01*
G02X288023Y1721032I-303J0D01*
G01X284323D01*
G02X284020Y1721335I0J303D01*
G01Y1724199D01*
G02X284052Y1724333I303J-1D01*
G01X284971Y1726208D01*
G03Y1726470I-267J131D01*
G01X284052Y1728345D01*
G02X284020Y1728479I270J135D01*
G37*
G36*
G01X260398Y1724542D02*
Y1727404D01*
G02X260701Y1727706I303J-1D01*
G01X264401D01*
G02X264704Y1727404I1J-302D01*
G01Y1717398D01*
G02X264401Y1717096I-303J1D01*
G01X260701D01*
G02X260398Y1717398I-1J302D01*
G01Y1720262D01*
G02X260430Y1720396I303J-1D01*
G01X261349Y1722271D01*
G03Y1722533I-267J131D01*
G01X260430Y1724408D01*
G02X260398Y1724542I270J135D01*
G37*
G36*
G01X276146D02*
Y1727404D01*
G02X276449Y1727706I303J-1D01*
G01X280149D01*
G02X280452Y1727404I1J-302D01*
G01Y1717398D01*
G02X280149Y1717096I-303J1D01*
G01X276449D01*
G02X276146Y1717398I-1J302D01*
G01Y1720262D01*
G02X276178Y1720396I303J-1D01*
G01X277097Y1722271D01*
G03Y1722533I-267J131D01*
G01X276178Y1724408D01*
G02X276146Y1724542I270J135D01*
G37*
G36*
G01X268272Y1714306D02*
Y1717168D01*
G02X268575Y1717470I303J-1D01*
G01X272275D01*
G02X272578Y1717168I1J-302D01*
G01Y1707162D01*
G02X272275Y1706860I-303J1D01*
G01X268575D01*
G02X268272Y1707162I-1J302D01*
G01Y1710026D01*
G02X268304Y1710160I303J-1D01*
G01X269223Y1712035D01*
G03Y1712297I-267J131D01*
G01X268304Y1714172D01*
G02X268272Y1714306I270J135D01*
G37*
G36*
G01X284020D02*
Y1717168D01*
G02X284323Y1717470I303J-1D01*
G01X288023D01*
G02X288326Y1717168I1J-302D01*
G01Y1707162D01*
G02X288023Y1706860I-303J1D01*
G01X284323D01*
G02X284020Y1707162I-1J302D01*
G01Y1710026D01*
G02X284052Y1710160I303J-1D01*
G01X284971Y1712035D01*
G03Y1712297I-267J131D01*
G01X284052Y1714172D01*
G02X284020Y1714306I270J135D01*
G37*
G36*
G01X260398Y1710369D02*
Y1713231D01*
G02X260701Y1713534I303J0D01*
G01X264401D01*
G02X264704Y1713231I0J-303D01*
G01Y1703225D01*
G02X264401Y1702922I-303J0D01*
G01X260701D01*
G02X260398Y1703225I0J303D01*
G01Y1706089D01*
G02X260430Y1706223I303J-1D01*
G01X261349Y1708098D01*
G03Y1708360I-267J131D01*
G01X260430Y1710235D01*
G02X260398Y1710369I270J135D01*
G37*
G36*
G01X276146D02*
Y1713231D01*
G02X276449Y1713534I303J0D01*
G01X280149D01*
G02X280452Y1713231I0J-303D01*
G01Y1703225D01*
G02X280149Y1702922I-303J0D01*
G01X276449D01*
G02X276146Y1703225I0J303D01*
G01Y1706089D01*
G02X276178Y1706223I303J-1D01*
G01X277097Y1708098D01*
G03Y1708360I-267J131D01*
G01X276178Y1710235D01*
G02X276146Y1710369I270J135D01*
G37*
G36*
G01X268272Y1702994D02*
G02X268575Y1703296I303J-1D01*
G01X272275D01*
G02X272578Y1702994I1J-302D01*
G01Y1692988D01*
G02X272275Y1692686I-303J1D01*
G01X268575D01*
G02X268272Y1692988I-1J302D01*
G01Y1702994D01*
G37*
G36*
G01X284020D02*
G02X284323Y1703296I303J-1D01*
G01X288023D01*
G02X288326Y1702994I1J-302D01*
G01Y1692988D01*
G02X288023Y1692686I-303J1D01*
G01X284323D01*
G02X284020Y1692988I-1J302D01*
G01Y1702994D01*
G37*
G36*
G01X260398Y1699057D02*
G02X260701Y1699360I303J0D01*
G01X264401D01*
G02X264704Y1699057I0J-303D01*
G01Y1689051D01*
G02X264401Y1688748I-303J0D01*
G01X260701D01*
G02X260398Y1689051I0J303D01*
G01Y1699057D01*
G37*
G36*
G01X276146D02*
G02X276449Y1699360I303J0D01*
G01X280149D01*
G02X280452Y1699057I0J-303D01*
G01Y1689051D01*
G02X280149Y1688748I-303J0D01*
G01X276449D01*
G02X276146Y1689051I0J303D01*
G01Y1699057D01*
G37*
G36*
G01X268272Y1688821D02*
G02X268575Y1689124I303J0D01*
G01X272275D01*
G02X272578Y1688821I0J-303D01*
G01Y1678815D01*
G02X272275Y1678512I-303J0D01*
G01X268575D01*
G02X268272Y1678815I0J303D01*
G01Y1688821D01*
G37*
G36*
G01X284020D02*
G02X284323Y1689124I303J0D01*
G01X288023D01*
G02X288326Y1688821I0J-303D01*
G01Y1678815D01*
G02X288023Y1678512I-303J0D01*
G01X284323D01*
G02X284020Y1678815I0J303D01*
G01Y1688821D01*
G37*
G36*
G01X260398Y1684884D02*
G02X260701Y1685186I303J-1D01*
G01X264401D01*
G02X264704Y1684884I1J-302D01*
G01Y1674878D01*
G02X264401Y1674576I-303J1D01*
G01X260701D01*
G02X260398Y1674878I-1J302D01*
G01Y1684884D01*
G37*
G36*
G01X276146D02*
G02X276449Y1685186I303J-1D01*
G01X280149D01*
G02X280452Y1684884I1J-302D01*
G01Y1674878D01*
G02X280149Y1674576I-303J1D01*
G01X276449D01*
G02X276146Y1674878I-1J302D01*
G01Y1684884D01*
G37*
G36*
G01X268272Y1674648D02*
G02X268575Y1674950I303J-1D01*
G01X272275D01*
G02X272578Y1674648I1J-302D01*
G01Y1664642D01*
G02X272275Y1664340I-303J1D01*
G01X268575D01*
G02X268272Y1664642I-1J302D01*
G01Y1674648D01*
G37*
G36*
G01X284020D02*
G02X284323Y1674950I303J-1D01*
G01X288023D01*
G02X288326Y1674648I1J-302D01*
G01Y1664642D01*
G02X288023Y1664340I-303J1D01*
G01X284323D01*
G02X284020Y1664642I-1J302D01*
G01Y1674648D01*
G37*
G36*
G01X276146Y1670711D02*
G02X276449Y1671014I303J0D01*
G01X280149D01*
G02X280452Y1670711I0J-303D01*
G01Y1660705D01*
G02X280149Y1660402I-303J0D01*
G01X276449D01*
G02X276146Y1660705I0J303D01*
G01Y1670711D01*
G37*
G36*
G01X268272Y1660474D02*
G02X268575Y1660776I303J-1D01*
G01X272275D01*
G02X272578Y1660474I1J-302D01*
G01Y1650468D01*
G02X272275Y1650166I-303J1D01*
G01X268575D01*
G02X268272Y1650468I-1J302D01*
G01Y1660474D01*
G37*
G36*
G01X284020D02*
G02X284323Y1660776I303J-1D01*
G01X288023D01*
G02X288326Y1660474I1J-302D01*
G01Y1650468D01*
G02X288023Y1650166I-303J1D01*
G01X284323D01*
G02X284020Y1650468I-1J302D01*
G01Y1660474D01*
G37*
G36*
G01X276146Y1656537D02*
G02X276449Y1656840I303J0D01*
G01X280149D01*
G02X280452Y1656537I0J-303D01*
G01Y1646531D01*
G02X280149Y1646228I-303J0D01*
G01X276449D01*
G02X276146Y1646531I0J303D01*
G01Y1656537D01*
G37*
G36*
G01X236776Y1728479D02*
Y1731341D01*
G02X237079Y1731644I303J0D01*
G01X240779D01*
G02X241082Y1731341I0J-303D01*
G01Y1721335D01*
G02X240779Y1721032I-303J0D01*
G01X237079D01*
G02X236776Y1721335I0J303D01*
G01Y1724199D01*
G02X236808Y1724333I303J-1D01*
G01X237727Y1726208D01*
G03Y1726470I-267J131D01*
G01X236808Y1728345D01*
G02X236776Y1728479I270J135D01*
G37*
G36*
G01X252524D02*
Y1731341D01*
G02X252827Y1731644I303J0D01*
G01X256527D01*
G02X256830Y1731341I0J-303D01*
G01Y1721335D01*
G02X256527Y1721032I-303J0D01*
G01X252827D01*
G02X252524Y1721335I0J303D01*
G01Y1724199D01*
G02X252556Y1724333I303J-1D01*
G01X253475Y1726208D01*
G03Y1726470I-267J131D01*
G01X252556Y1728345D01*
G02X252524Y1728479I270J135D01*
G37*
G36*
G01X228902Y1724542D02*
Y1727404D01*
G02X229205Y1727706I303J-1D01*
G01X232905D01*
G02X233208Y1727404I1J-302D01*
G01Y1717398D01*
G02X232905Y1717096I-303J1D01*
G01X229205D01*
G02X228902Y1717398I-1J302D01*
G01Y1720262D01*
G02X228934Y1720396I303J-1D01*
G01X229853Y1722271D01*
G03Y1722533I-267J131D01*
G01X228934Y1724408D01*
G02X228902Y1724542I270J135D01*
G37*
G36*
G01X244650D02*
Y1727404D01*
G02X244953Y1727706I303J-1D01*
G01X248653D01*
G02X248956Y1727404I1J-302D01*
G01Y1717398D01*
G02X248653Y1717096I-303J1D01*
G01X244953D01*
G02X244650Y1717398I-1J302D01*
G01Y1720262D01*
G02X244682Y1720396I303J-1D01*
G01X245601Y1722271D01*
G03Y1722533I-267J131D01*
G01X244682Y1724408D01*
G02X244650Y1724542I270J135D01*
G37*
G36*
G01X236776Y1714306D02*
Y1717168D01*
G02X237079Y1717470I303J-1D01*
G01X240779D01*
G02X241082Y1717168I1J-302D01*
G01Y1707162D01*
G02X240779Y1706860I-303J1D01*
G01X237079D01*
G02X236776Y1707162I-1J302D01*
G01Y1710026D01*
G02X236808Y1710160I303J-1D01*
G01X237727Y1712035D01*
G03Y1712297I-267J131D01*
G01X236808Y1714172D01*
G02X236776Y1714306I270J135D01*
G37*
G36*
G01X252524D02*
Y1717168D01*
G02X252827Y1717470I303J-1D01*
G01X256527D01*
G02X256830Y1717168I1J-302D01*
G01Y1707162D01*
G02X256527Y1706860I-303J1D01*
G01X252827D01*
G02X252524Y1707162I-1J302D01*
G01Y1710026D01*
G02X252556Y1710160I303J-1D01*
G01X253475Y1712035D01*
G03Y1712297I-267J131D01*
G01X252556Y1714172D01*
G02X252524Y1714306I270J135D01*
G37*
G36*
G01X228902Y1710369D02*
Y1713231D01*
G02X229205Y1713534I303J0D01*
G01X232905D01*
G02X233208Y1713231I0J-303D01*
G01Y1703225D01*
G02X232905Y1702922I-303J0D01*
G01X229205D01*
G02X228902Y1703225I0J303D01*
G01Y1706089D01*
G02X228934Y1706223I303J-1D01*
G01X229853Y1708098D01*
G03Y1708360I-267J131D01*
G01X228934Y1710235D01*
G02X228902Y1710369I270J135D01*
G37*
G36*
G01X244650D02*
Y1713231D01*
G02X244953Y1713534I303J0D01*
G01X248653D01*
G02X248956Y1713231I0J-303D01*
G01Y1703225D01*
G02X248653Y1702922I-303J0D01*
G01X244953D01*
G02X244650Y1703225I0J303D01*
G01Y1706089D01*
G02X244682Y1706223I303J-1D01*
G01X245601Y1708098D01*
G03Y1708360I-267J131D01*
G01X244682Y1710235D01*
G02X244650Y1710369I270J135D01*
G37*
G36*
G01X236776Y1702994D02*
G02X237079Y1703296I303J-1D01*
G01X240779D01*
G02X241082Y1702994I1J-302D01*
G01Y1692988D01*
G02X240779Y1692686I-303J1D01*
G01X237079D01*
G02X236776Y1692988I-1J302D01*
G01Y1702994D01*
G37*
G36*
G01X252524D02*
G02X252827Y1703296I303J-1D01*
G01X256527D01*
G02X256830Y1702994I1J-302D01*
G01Y1692988D01*
G02X256527Y1692686I-303J1D01*
G01X252827D01*
G02X252524Y1692988I-1J302D01*
G01Y1702994D01*
G37*
G36*
G01X228902Y1699057D02*
G02X229205Y1699360I303J0D01*
G01X232905D01*
G02X233208Y1699057I0J-303D01*
G01Y1689051D01*
G02X232905Y1688748I-303J0D01*
G01X229205D01*
G02X228902Y1689051I0J303D01*
G01Y1699057D01*
G37*
G36*
G01X244650D02*
G02X244953Y1699360I303J0D01*
G01X248653D01*
G02X248956Y1699057I0J-303D01*
G01Y1689051D01*
G02X248653Y1688748I-303J0D01*
G01X244953D01*
G02X244650Y1689051I0J303D01*
G01Y1699057D01*
G37*
G36*
G01X236776Y1688821D02*
G02X237079Y1689124I303J0D01*
G01X240779D01*
G02X241082Y1688821I0J-303D01*
G01Y1678815D01*
G02X240779Y1678512I-303J0D01*
G01X237079D01*
G02X236776Y1678815I0J303D01*
G01Y1688821D01*
G37*
G36*
G01X252524D02*
G02X252827Y1689124I303J0D01*
G01X256527D01*
G02X256830Y1688821I0J-303D01*
G01Y1678815D01*
G02X256527Y1678512I-303J0D01*
G01X252827D01*
G02X252524Y1678815I0J303D01*
G01Y1688821D01*
G37*
G36*
G01X228902Y1684884D02*
G02X229205Y1685186I303J-1D01*
G01X232905D01*
G02X233208Y1684884I1J-302D01*
G01Y1674878D01*
G02X232905Y1674576I-303J1D01*
G01X229205D01*
G02X228902Y1674878I-1J302D01*
G01Y1684884D01*
G37*
G36*
G01X244650D02*
G02X244953Y1685186I303J-1D01*
G01X248653D01*
G02X248956Y1684884I1J-302D01*
G01Y1674878D01*
G02X248653Y1674576I-303J1D01*
G01X244953D01*
G02X244650Y1674878I-1J302D01*
G01Y1684884D01*
G37*
G36*
G01X252524Y1674648D02*
G02X252827Y1674950I303J-1D01*
G01X256527D01*
G02X256830Y1674648I1J-302D01*
G01Y1664642D01*
G02X256527Y1664340I-303J1D01*
G01X252827D01*
G02X252524Y1664642I-1J302D01*
G01Y1674648D01*
G37*
G36*
G01X228902Y1670711D02*
G02X229205Y1671014I303J0D01*
G01X232905D01*
G02X233208Y1670711I0J-303D01*
G01Y1660705D01*
G02X232905Y1660402I-303J0D01*
G01X229205D01*
G02X228902Y1660705I0J303D01*
G01Y1670711D01*
G37*
G36*
G01X244650D02*
G02X244953Y1671014I303J0D01*
G01X248653D01*
G02X248956Y1670711I0J-303D01*
G01Y1660705D01*
G02X248653Y1660402I-303J0D01*
G01X244953D01*
G02X244650Y1660705I0J303D01*
G01Y1670711D01*
G37*
G36*
G01X236776Y1660474D02*
G02X237079Y1660776I303J-1D01*
G01X240779D01*
G02X241082Y1660474I1J-302D01*
G01Y1650468D01*
G02X240779Y1650166I-303J1D01*
G01X237079D01*
G02X236776Y1650468I-1J302D01*
G01Y1660474D01*
G37*
G36*
G01X228902Y1656537D02*
G02X229205Y1656840I303J0D01*
G01X232905D01*
G02X233208Y1656537I0J-303D01*
G01Y1646531D01*
G02X232905Y1646228I-303J0D01*
G01X229205D01*
G02X228902Y1646531I0J303D01*
G01Y1656537D01*
G37*
G36*
G01X226465Y1520264D02*
G02X227525Y1520900I1060J-565D01*
G01X227526D01*
G02X228728Y1519698I0J-1202D01*
G02X228568Y1519098I-1203J0D01*
G01X227023Y1516425D01*
X227021Y1516421D01*
G02X225951Y1515768I-1070J550D01*
G01X225950D01*
G02X224748Y1516970I0J1202D01*
G01Y1516972D01*
G02X224897Y1517551I1202J-1D01*
G01X226463Y1520261D01*
X226465Y1520264D01*
G37*
G36*
G01X231189D02*
G02X232249Y1520900I1060J-565D01*
G01X232250D01*
G02X233452Y1519698I0J-1202D01*
G02X233292Y1519098I-1203J0D01*
G01X231747Y1516425D01*
X231745Y1516421D01*
G02X230675Y1515768I-1070J550D01*
G01X230674D01*
G02X229472Y1516970I0J1202D01*
G01Y1516972D01*
G02X229621Y1517551I1202J-1D01*
G01X231187Y1520261D01*
X231189Y1520264D01*
G37*
G36*
G01X235914D02*
G02X236974Y1520900I1060J-565D01*
G01X236975D01*
G02X238178Y1519698I1J-1202D01*
G02X238017Y1519098I-1204J1D01*
G01X236472Y1516425D01*
X236470Y1516421D01*
G02X235400Y1515768I-1070J550D01*
G01X235399D01*
G02X234196Y1516970I-1J1202D01*
G01Y1516972D01*
G02X234346Y1517551I1203J-3D01*
G01X235912Y1520261D01*
X235914Y1520264D01*
G37*
G36*
G01X240638D02*
G02X241698Y1520900I1060J-565D01*
G01X241699D01*
G02X242902Y1519698I1J-1202D01*
G02X242741Y1519098I-1204J1D01*
G01X241196Y1516425D01*
X241194Y1516421D01*
G02X240124Y1515768I-1070J550D01*
G01X240123D01*
G02X238920Y1516970I-1J1202D01*
G01Y1516972D01*
G02X239070Y1517551I1203J-3D01*
G01X240636Y1520261D01*
X240638Y1520264D01*
G37*
G36*
G01X245362D02*
G02X246422Y1520900I1060J-565D01*
G01X246423D01*
G02X247626Y1519698I1J-1202D01*
G02X247465Y1519098I-1204J1D01*
G01X245920Y1516425D01*
X245918Y1516421D01*
G02X244848Y1515768I-1070J550D01*
G01X244847D01*
G02X243644Y1516970I-1J1202D01*
G01Y1516972D01*
G02X243794Y1517551I1203J-3D01*
G01X245360Y1520261D01*
X245362Y1520264D01*
G37*
G36*
G01X250087D02*
G02X251147Y1520900I1060J-565D01*
G01X251148D01*
G02X252350Y1519698I0J-1202D01*
G02X252190Y1519098I-1203J0D01*
G01X250645Y1516425D01*
X250643Y1516421D01*
G02X249573Y1515768I-1070J550D01*
G01X249572D01*
G02X248370Y1516970I0J1202D01*
G01Y1516972D01*
G02X248519Y1517551I1202J-1D01*
G01X250085Y1520261D01*
X250087Y1520264D01*
G37*
G36*
G01X254811D02*
G02X255871Y1520900I1060J-565D01*
G01X255872D01*
G02X257074Y1519698I0J-1202D01*
G02X256914Y1519098I-1203J0D01*
G01X255369Y1516425D01*
X255367Y1516421D01*
G02X254297Y1515768I-1070J550D01*
G01X254296D01*
G02X253094Y1516970I0J1202D01*
G01Y1516972D01*
G02X253243Y1517551I1202J-1D01*
G01X254809Y1520261D01*
X254811Y1520264D01*
G37*
G36*
G01X259536D02*
G02X260596Y1520900I1060J-565D01*
G01X260597D01*
G02X261800Y1519698I1J-1202D01*
G02X261639Y1519098I-1204J1D01*
G01X260094Y1516425D01*
X260092Y1516421D01*
G02X259022Y1515768I-1070J550D01*
G01X259021D01*
G02X257818Y1516970I-1J1202D01*
G01Y1516972D01*
G02X257968Y1517551I1203J-3D01*
G01X259534Y1520261D01*
X259536Y1520264D01*
G37*
G36*
G01X1234338Y1553264D02*
G02X1235398Y1553900I1060J-565D01*
G01X1235399D01*
G02X1236602Y1552698I1J-1202D01*
G02X1236441Y1552098I-1204J1D01*
G01X1234896Y1549425D01*
X1234894Y1549421D01*
G02X1233824Y1548768I-1070J550D01*
G01X1233823D01*
G02X1232620Y1549970I-1J1202D01*
G01Y1549972D01*
G02X1232770Y1550551I1203J-3D01*
G01X1234336Y1553261D01*
X1234338Y1553264D01*
G37*
G36*
G01X1239062D02*
G02X1240122Y1553900I1060J-565D01*
G01X1240123D01*
G02X1241326Y1552698I1J-1202D01*
G02X1241165Y1552098I-1204J1D01*
G01X1239620Y1549425D01*
X1239618Y1549421D01*
G02X1238548Y1548768I-1070J550D01*
G01X1238547D01*
G02X1237344Y1549970I-1J1202D01*
G01Y1549972D01*
G02X1237494Y1550551I1203J-3D01*
G01X1239060Y1553261D01*
X1239062Y1553264D01*
G37*
G36*
G01X1243787D02*
G02X1244847Y1553900I1060J-565D01*
G01X1244848D01*
G02X1246050Y1552698I0J-1202D01*
G02X1245890Y1552098I-1203J0D01*
G01X1244345Y1549425D01*
X1244343Y1549421D01*
G02X1243273Y1548768I-1070J550D01*
G01X1243272D01*
G02X1242070Y1549970I0J1202D01*
G01Y1549972D01*
G02X1242219Y1550551I1202J-1D01*
G01X1243785Y1553261D01*
X1243787Y1553264D01*
G37*
G36*
G01X1248511D02*
G02X1249571Y1553900I1060J-565D01*
G01X1249572D01*
G02X1250774Y1552698I0J-1202D01*
G02X1250614Y1552098I-1203J0D01*
G01X1249069Y1549425D01*
X1249067Y1549421D01*
G02X1247997Y1548768I-1070J550D01*
G01X1247996D01*
G02X1246794Y1549970I0J1202D01*
G01Y1549972D01*
G02X1246943Y1550551I1202J-1D01*
G01X1248509Y1553261D01*
X1248511Y1553264D01*
G37*
G36*
G01X1257960D02*
G02X1259020Y1553900I1060J-565D01*
G01X1259021D01*
G02X1260224Y1552698I1J-1202D01*
G02X1260063Y1552098I-1204J1D01*
G01X1258518Y1549425D01*
X1258516Y1549421D01*
G02X1257446Y1548768I-1070J550D01*
G01X1257445D01*
G02X1256242Y1549970I-1J1202D01*
G01Y1549972D01*
G02X1256392Y1550551I1203J-3D01*
G01X1257958Y1553261D01*
X1257960Y1553264D01*
G37*
G36*
G01X1267409D02*
G02X1268469Y1553900I1060J-565D01*
G01X1268470D01*
G02X1269672Y1552698I0J-1202D01*
G02X1269512Y1552098I-1203J0D01*
G01X1267967Y1549425D01*
X1267965Y1549421D01*
G02X1266895Y1548768I-1070J550D01*
G01X1266894D01*
G02X1265692Y1549970I0J1202D01*
G01Y1549972D01*
G02X1265841Y1550551I1202J-1D01*
G01X1267407Y1553261D01*
X1267409Y1553264D01*
G37*
G36*
G01X639269Y1612790D02*
G02Y1615794I0J1502D01*
G01X642669D01*
G02Y1612790I0J-1502D01*
G01X639269D01*
G37*
G36*
G01X627209D02*
G02Y1615794I0J1502D01*
G01X630609D01*
G02Y1612790I0J-1502D01*
G01X627209D01*
G37*
G36*
G01X621179Y1590878D02*
G02Y1593882I0J1502D01*
G01X624579D01*
G02Y1590878I0J-1502D01*
G01X621179D01*
G37*
G36*
G01X633239Y1622790D02*
G02Y1625794I0J1502D01*
G01X636639D01*
G02Y1622790I0J-1502D01*
G01X633239D01*
G37*
G36*
G01X615149Y1600878D02*
G02Y1603882I0J1502D01*
G01X618549D01*
G02Y1600878I0J-1502D01*
G01X615149D01*
G37*
G36*
G01X609119Y1590878D02*
G02Y1593882I0J1502D01*
G01X612519D01*
G02Y1590878I0J-1502D01*
G01X609119D01*
G37*
G36*
G01Y1622790D02*
G02Y1625794I0J1502D01*
G01X612519D01*
G02Y1622790I0J-1502D01*
G01X609119D01*
G37*
G36*
G01X621179D02*
G02Y1625794I0J1502D01*
G01X624579D01*
G02Y1622790I0J-1502D01*
G01X621179D01*
G37*
G36*
G01X615149Y1612790D02*
G02Y1615794I0J1502D01*
G01X618549D01*
G02Y1612790I0J-1502D01*
G01X615149D01*
G37*
G36*
G01X627209Y1600878D02*
G02Y1603882I0J1502D01*
G01X630609D01*
G02Y1600878I0J-1502D01*
G01X627209D01*
G37*
G36*
G01X639269D02*
G02Y1603882I0J1502D01*
G01X642669D01*
G02Y1600878I0J-1502D01*
G01X639269D01*
G37*
G36*
G01X633239Y1590878D02*
G02Y1593882I0J1502D01*
G01X636639D01*
G02Y1590878I0J-1502D01*
G01X633239D01*
G37*
G54D93*
X766889Y1486756D03*
Y1530256D03*
G54D100*
X1571516Y319099D03*
X1290127Y410635D03*
X1005307Y155043D03*
X820901Y147112D03*
X788710Y1488821D03*
X712291Y106722D03*
X263316Y87665D03*
X101675Y160694D03*
G54D109*
X505185Y41141D03*
X60303Y20354D03*
X1534712D03*
G54D87*
X398673Y-18871D03*
Y-8871D03*
X373673D03*
Y-18871D03*
X398673Y-28871D03*
X373673D03*
X718093Y-8871D03*
Y-18871D03*
X743093D03*
Y-8871D03*
X718093Y-28871D03*
X743093D03*
X850152Y-5011D03*
X825152D03*
X850152Y-15011D03*
X825152D03*
X850152Y-35011D03*
Y-25011D03*
X825152D03*
Y-35011D03*
X850152Y4989D03*
X825152D03*
X850152Y14989D03*
X825152D03*
X850152Y24989D03*
X825152D03*
X1169572Y-5011D03*
X1194572D03*
X1169572Y-15011D03*
X1194572D03*
X1169572Y-25011D03*
Y-35011D03*
X1194572D03*
Y-25011D03*
X1169572Y4989D03*
X1194572D03*
X1169572Y14989D03*
X1194572D03*
X1169572Y24989D03*
X1194572D03*
X1253672Y-15011D03*
X1228672D03*
X1253672Y-35011D03*
Y-25011D03*
X1228672D03*
Y-35011D03*
X1253672Y-5011D03*
X1228672D03*
X1253672Y4989D03*
Y14989D03*
X1228672D03*
Y4989D03*
X1253672Y24989D03*
X1228672D03*
X1428431Y-15011D03*
X1453431D03*
X1428431Y-25011D03*
Y-35011D03*
X1453431D03*
Y-25011D03*
X1428431Y-5011D03*
X1453431D03*
X1428431Y14989D03*
Y4989D03*
X1453431D03*
Y14989D03*
X1428431Y24989D03*
X1453431D03*
X1546966Y-39212D03*
Y-29212D03*
X1521966D03*
Y-39212D03*
X1546966Y-19212D03*
X1521966D03*
X1721725Y-29212D03*
Y-39212D03*
X1746725D03*
Y-29212D03*
X1721725Y-19212D03*
X1746725D03*
G54D94*
X1787330Y24291D03*
X922441Y237697D03*
X929331Y160413D03*
X312921Y24291D03*
G54D97*
X676509Y224606D03*
G54D98*
Y145866D03*
G54D105*
X1066280Y1704890D03*
G54D108*
X1340948Y1179681D03*
G54D99*
X1700840Y1424519D03*
X1524437Y640365D03*
X1487677Y640145D03*
X1415690Y601230D03*
X1320516Y1375715D03*
X1291146D03*
X1166535Y1412479D03*
X754645Y1426892D03*
X433624Y594259D03*
X363731Y653394D03*
X326731D03*
G54D104*
X1131824Y1602293D03*
X1141084Y1644972D03*
X1090958Y1648228D03*
X1115098Y1470571D03*
X1562640Y1558031D03*
X554766Y1525031D03*
X1170404Y1558031D03*
X558876Y1456605D03*
X1298466Y1558031D03*
X426704Y1525031D03*
X165336Y1676777D03*
X85836Y1656843D03*
X1434578Y1558031D03*
X436776Y1612094D03*
X388630Y1238447D03*
X390974Y1221149D03*
X313284Y1216822D03*
X814296Y1385745D03*
X1521718Y1579697D03*
X1516994D03*
X1512270D03*
X1507546D03*
X1474474D03*
X1469750D03*
X1493372D03*
X1488648D03*
X1649780D03*
X1645056D03*
X1640332D03*
X1635608D03*
X1602536D03*
X1597812D03*
X1621434D03*
X1616710D03*
X466600Y1546697D03*
X461876D03*
X1385606Y1579697D03*
X1380882D03*
X1376158D03*
X1371434D03*
X1338362D03*
X1333638D03*
X1357260D03*
X1352536D03*
X499672Y1546697D03*
X641906D03*
X637182D03*
X632458D03*
X627734D03*
X513844D03*
X509120D03*
X504396D03*
X485498D03*
X480774D03*
X1257544Y1579697D03*
X1252820D03*
X1248096D03*
X1243372D03*
X1210300D03*
X1205576D03*
X1229198D03*
X1224474D03*
X589938Y1546697D03*
X608836D03*
X594662D03*
X613560D03*
X1680730Y1515382D03*
X672856Y1482382D03*
X1563222Y1514890D03*
X1552668Y1515382D03*
X1435160Y1514890D03*
X1299048D03*
X555348Y1481890D03*
X544794Y1482382D03*
X427286Y1481890D03*
X387182Y1546697D03*
X382458D03*
X358836D03*
X354112D03*
X339938D03*
X335214D03*
X321040D03*
X316316D03*
X259120D03*
X254396D03*
X230774D03*
X226050D03*
X211876D03*
X207152D03*
X192978D03*
X188254D03*
X142576Y1641863D03*
X555348Y1503690D03*
X1170986Y1536690D03*
Y1514890D03*
X1416556Y1515382D03*
Y1528782D03*
X544794Y1495782D03*
X1680730Y1528782D03*
X1299048Y1536690D03*
X1342036Y1204729D03*
X427286Y1503690D03*
X1563222Y1536690D03*
X526460Y99195D03*
X40922Y1656569D03*
X372000Y844727D03*
Y833497D03*
X672856Y1495782D03*
X1435160Y1536690D03*
X1552668Y1528782D03*
X1288494D03*
Y1515382D03*
X400426Y114515D03*
X570860Y123010D03*
X553780Y122940D03*
X417486Y125879D03*
X50880Y1417263D03*
X35852Y690616D03*
Y679710D03*
Y701522D03*
Y668745D03*
G54D110*
X1681102Y1626654D03*
X163662Y1593661D03*
X1171536Y1626654D03*
X698819Y1482244D03*
X1706693Y1515236D03*
X1145945D03*
X138071Y1482244D03*
X673228Y1593661D03*
G54D103*
X403837Y1610756D03*
X1142917Y1585014D03*
X1118133Y1589698D03*
X1146501Y1653908D03*
X162531Y1525031D03*
X290593D03*
X546253Y1455807D03*
X165491Y1663882D03*
X87891Y1672821D03*
X704771Y169488D03*
X280621Y1495782D03*
X1370685Y1224732D03*
X653999Y1425057D03*
X58349Y1408031D03*
X154945Y1626050D03*
X1531167Y1579697D03*
X1526443D03*
X1502821D03*
X1498097D03*
X1483923D03*
X1479199D03*
X1465025D03*
X1460301D03*
X1659229D03*
X1654505D03*
X1630883D03*
X1626159D03*
X1611985D03*
X1607261D03*
X1593087D03*
X1588363D03*
X476049Y1546697D03*
X471325D03*
X1395055Y1579697D03*
X1390331D03*
X1366709D03*
X1361985D03*
X1347811D03*
X1343087D03*
X1328913D03*
X1324189D03*
X494947Y1546697D03*
X490223D03*
X646631D03*
X623009D03*
X618285D03*
X651355D03*
X518569D03*
X523293D03*
X452427D03*
X457151D03*
X1266993Y1579697D03*
X1262269D03*
X1238647D03*
X1233923D03*
X1219749D03*
X1215025D03*
X1200851D03*
X1196127D03*
X585213Y1546697D03*
X604111D03*
X599387D03*
X580489D03*
X1346063Y1216029D03*
X193679Y1641752D03*
X297323Y1655472D03*
X307255Y1645450D03*
X163113Y1503690D03*
Y1481890D03*
X280621Y1482382D03*
X291175Y1481890D03*
Y1503690D03*
X377733Y1546697D03*
X373009D03*
X368285D03*
X363561D03*
X349387D03*
X344663D03*
X330489D03*
X325765D03*
X249671D03*
X244947D03*
X240223D03*
X235499D03*
X221325D03*
X216601D03*
X202427D03*
X197703D03*
X205479Y1650430D03*
X408683Y1482382D03*
X1315657Y1197832D03*
X408683Y1495782D03*
X163735Y1633669D03*
X99443Y1660231D03*
X100443Y1685763D03*
X41679Y1675023D03*
X371999Y821227D03*
X385001Y815227D03*
X1007587Y774180D03*
Y763246D03*
Y840056D03*
Y829054D03*
Y818052D03*
Y807118D03*
Y796184D03*
Y785182D03*
X559069Y103685D03*
X482255Y131522D03*
X704771Y193110D03*
X716699Y210721D03*
Y198887D03*
Y175387D03*
Y187387D03*
X704771Y216732D03*
Y204921D03*
Y181299D03*
G54D107*
X516020Y107320D03*
X535170Y113180D03*
X80948Y523563D03*
X405606Y127765D03*
X80318Y541363D03*
G54D91*
X1766929Y1714960D03*
G54D95*
X1739745Y605411D03*
X1094076Y605378D03*
X763602Y605413D03*
X117933Y605376D03*
G54D85*
X1729562Y-24215D03*
Y-34215D03*
X1436268Y9986D03*
Y-14D03*
Y-20014D03*
Y-30014D03*
X725930Y-13874D03*
Y-23874D03*
X390846Y-13874D03*
Y-23874D03*
G54D84*
X1837795Y18819D03*
X19685Y-29134D03*
X1804650Y1667292D03*
X441043Y1672205D03*
X1416437D03*
X1800449Y126194D03*
X44000Y154200D03*
X31818Y1424257D03*
X1885039Y49021D03*
X2081889Y-29134D03*
X2081889Y1803261D03*
X1871260Y1291627D03*
G54D106*
X47619Y417134D03*
X1025493Y763769D03*
X62813Y414050D03*
G54D102*
X1829921Y130314D03*
G54D96*
X1057659Y204724D03*
X805690D03*
G54D86*
X1539139Y-24215D03*
Y-34215D03*
X1245845Y9986D03*
Y-14D03*
Y-20014D03*
Y-30014D03*
X1177409Y19986D03*
Y9986D03*
Y-10014D03*
Y-20014D03*
X842325Y19986D03*
Y9986D03*
Y-10014D03*
Y-20014D03*
G54D90*
X274913Y1019214D03*
X606409D03*
X1251055Y1019213D03*
X1582551D03*
G54D89*
X320189Y838505D03*
X1296331Y838504D03*
G54D88*
X561133Y838505D03*
Y1199923D03*
X1537275Y838504D03*
Y1199922D03*
X1296331D03*
X320189Y1199923D03*
G54D92*
X841240Y1420331D03*
X1016240D03*
G54D101*
X177413Y277208D03*
X704185Y277236D03*
X1153555Y277208D03*
X1680327Y277236D03*
%LPC*%
G75*
G36*
G01X816753Y1718420D02*
X901267D01*
G02X901409Y1718361I0J-200D01*
G01X904191Y1715579D01*
G02X904250Y1715437I-141J-142D01*
G01Y1662129D01*
G03X904616Y1661245I1251J0D01*
G01X923910Y1641951D01*
G03X924794Y1641585I884J885D01*
G01X1071014D01*
G02X1071156Y1641526I0J-200D01*
G01X1102501Y1610181D01*
G02X1102560Y1610039I-141J-142D01*
G01Y1554974D01*
G02X1102501Y1554832I-200J0D01*
G03X1102500Y1554831I883J-884D01*
G01X1100990Y1553321D01*
G03X1100989Y1553320I883J-884D01*
G02X1100847Y1553261I-142J141D01*
G01X1094691D01*
G02X1094581Y1553294I0J200D01*
G03X1092934Y1553786I-1647J-2511D01*
G03X1091528Y1553436I1J-3002D01*
G02X1091340I-94J177D01*
G03X1089934Y1553786I-1407J-2652D01*
G03X1088287Y1553294I0J-3003D01*
G02X1088177Y1553261I-110J167D01*
G01X1059235D01*
G02X1059120Y1553297I0J200D01*
G03X1057396Y1553842I-1725J-2457D01*
G03X1055990Y1553492I1J-3002D01*
G02X1055802I-94J177D01*
G03X1054396Y1553842I-1407J-2652D01*
G03X1052672Y1553297I1J-3002D01*
G02X1052557Y1553261I-115J164D01*
G01X1027635D01*
G02X1027520Y1553297I0J200D01*
G03X1025796Y1553842I-1725J-2457D01*
G03X1024390Y1553492I1J-3002D01*
G02X1024202I-94J177D01*
G03X1022796Y1553842I-1407J-2652D01*
G03X1021072Y1553297I1J-3002D01*
G02X1020957Y1553261I-115J164D01*
G01X996035D01*
G02X995920Y1553297I0J200D01*
G03X994196Y1553842I-1725J-2457D01*
G03X992790Y1553492I1J-3002D01*
G02X992602I-94J177D01*
G03X991196Y1553842I-1407J-2652D01*
G03X989472Y1553297I1J-3002D01*
G02X989357Y1553261I-115J164D01*
G01X964400D01*
G02X964287Y1553296I0J200D01*
G03X962584Y1553826I-1703J-2471D01*
G03X961178Y1553476I1J-3002D01*
G02X960990I-94J177D01*
G03X959584Y1553826I-1407J-2652D01*
G03X957881Y1553296I0J-3001D01*
G02X957768Y1553261I-113J165D01*
G01X941933D01*
G02X941733Y1553461I0J200D01*
G01Y1599014D01*
G03X941367Y1599898I-1251J0D01*
G01X924975Y1616290D01*
G03X924091Y1616656I-884J-885D01*
G01X904314D01*
G02X904172Y1616715I0J200D01*
G01X894306Y1626581D01*
G03X893422Y1626947I-884J-885D01*
G01X771451D01*
G02X771309Y1627006I0J200D01*
G01X768659Y1629656D01*
G02X768600Y1629798I141J142D01*
G01Y1656300D01*
G02X768659Y1656442I200J0D01*
G03X768660Y1656443I-883J884D01*
G01X810874Y1698657D01*
G03X811240Y1699541I-885J884D01*
G01Y1712907D01*
G02X811299Y1713049I200J0D01*
G01X816611Y1718361D01*
G02X816753Y1718420I142J-141D01*
G37*
G36*
G01X1075557Y1548281D02*
G03X1075558Y1548280I884J883D01*
G01X1077438Y1546400D01*
G03X1077439Y1546399I884J883D01*
G02X1077498Y1546257I-141J-142D01*
G01Y1512423D01*
G02X1077439Y1512281I-200J0D01*
G03X1077438Y1512280I883J-884D01*
G01X1076566Y1511408D01*
G02X1076564Y1511406I-142J140D01*
G03X1076557Y1511399I881J-887D01*
G02X1076415Y1511340I-142J141D01*
G01X943081D01*
G02X942939Y1511399I0J200D01*
G03X942938Y1511400I-884J-883D01*
G01X941065Y1513273D01*
X941064Y1513274D01*
G03X941057Y1513281I-887J-881D01*
G02X940998Y1513423I141J142D01*
G01Y1547257D01*
G02X941057Y1547399I200J0D01*
G03X941058Y1547400I-883J884D01*
G01X941938Y1548280D01*
G03X941939Y1548281I-883J884D01*
G02X942081Y1548340I142J-141D01*
G01X1075415D01*
G02X1075557Y1548281I0J-200D01*
G37*
G36*
G01X1081757Y1543874D02*
X1082064Y1544181D01*
G02X1082206Y1544240I142J-141D01*
G01X1099402D01*
G02X1099602Y1544040I0J-200D01*
G01Y1511540D01*
G02X1099402Y1511340I-200J0D01*
G01X1082781D01*
G02X1082639Y1511399I0J200D01*
G01X1081757Y1512281D01*
G02X1081698Y1512423I141J142D01*
G01Y1543732D01*
G02X1081757Y1543874I200J0D01*
G37*
%LPD*%
G75*
G54D14*
X11782Y167036D03*
X18691Y167208D03*
X22409Y230021D03*
X19684Y237154D03*
X19230Y1446459D03*
X34281Y277798D03*
Y282916D03*
X35689Y298207D03*
X34281Y312916D03*
Y307798D03*
X35740Y363337D03*
X39320Y392269D03*
X28562Y517025D03*
X39967Y526709D03*
X30562Y533055D03*
X35952Y551605D03*
X35852Y670445D03*
Y667045D03*
Y681410D03*
Y678010D03*
Y692316D03*
Y703222D03*
Y688916D03*
Y699822D03*
X35010Y1289485D03*
X35040Y1292433D03*
X35080Y1298360D03*
X35040Y1295380D03*
X34584Y1307744D03*
Y1310244D03*
Y1312744D03*
Y1315244D03*
X33822Y1477075D03*
Y1486075D03*
Y1483075D03*
Y1480075D03*
X27205Y1501630D03*
Y1498230D03*
X38058Y1591405D03*
X35167Y1598896D03*
Y1626896D03*
Y1629405D03*
X32927Y1668587D03*
X42449Y282916D03*
Y277798D03*
X41492Y292892D03*
Y298207D03*
X47892Y295452D03*
X40500Y288500D03*
X55254Y292892D03*
X42449Y312916D03*
Y307798D03*
X51114Y360862D03*
X43020Y382942D03*
X40940Y387302D03*
X41933Y395652D03*
X47619Y419084D03*
X47618Y415184D03*
X49360Y428806D03*
X45960D03*
X49212Y451602D03*
X45812D03*
X47812Y517635D03*
X42810Y528070D03*
X39952Y551605D03*
X55099Y1298676D03*
Y1292676D03*
X51000Y1339200D03*
X42822Y1477075D03*
Y1483075D03*
Y1486075D03*
Y1480075D03*
X49265Y1490950D03*
Y1493450D03*
X49188Y1499181D03*
X41360Y1498971D03*
X41309Y1496173D03*
X38650Y1499326D03*
X49177Y1496272D03*
X48383Y1532395D03*
X48157Y1536296D03*
X49196Y1551294D03*
X48324Y1545961D03*
X48758Y1559295D03*
X48907Y1554972D03*
X47735Y1584885D03*
X47973Y1589981D03*
X43633Y1606896D03*
X46833Y1612596D03*
X43933Y1613818D03*
X47633Y1600896D03*
X53633Y1629896D03*
X41208Y1619896D03*
X42491Y1638656D03*
X40167Y1632405D03*
X40922Y1654869D03*
Y1658269D03*
X45052Y1684283D03*
X41679Y1673323D03*
Y1676723D03*
X65933Y28406D03*
Y48720D03*
X66650Y265316D03*
X57271Y272357D03*
X59780Y282866D03*
X62567Y295103D03*
X66289Y298207D03*
X59780Y312866D03*
X59322Y360702D03*
X63429D03*
X67681D03*
X53406Y402862D03*
X62812Y412100D03*
X62813Y416000D03*
X64821Y430806D03*
X60921D03*
X63540Y438802D03*
X64442Y510667D03*
X55682Y517595D03*
X62142Y539495D03*
X56192Y537795D03*
X63633Y528229D03*
X58365Y552365D03*
X53299D03*
X56627Y585818D03*
X59259Y737422D03*
X58751Y777718D03*
X61251D03*
Y775218D03*
X58751D03*
X61620Y768510D03*
X56440Y766180D03*
X58751Y790218D03*
Y792718D03*
Y780218D03*
X61251D03*
X56057Y792750D03*
X61251Y792718D03*
Y790218D03*
X56057Y790250D03*
Y787750D03*
X61251Y787718D03*
X56057Y785250D03*
X61251Y785218D03*
Y782718D03*
X56057Y782750D03*
X58751Y782718D03*
Y785218D03*
Y787718D03*
X57752Y808020D03*
X60547Y1276036D03*
X57747Y1270470D03*
X55099Y1289676D03*
X55043Y1295676D03*
X53700Y1342300D03*
X67010Y1476292D03*
X57822Y1477075D03*
X57777Y1490580D03*
X66710Y1485324D03*
Y1482324D03*
X66785Y1479175D03*
X57822Y1482791D03*
Y1485294D03*
Y1480075D03*
X64030Y1491595D03*
X57770Y1488047D03*
X66696Y1488010D03*
X64030Y1499095D03*
Y1501595D03*
Y1494095D03*
Y1496595D03*
X55370Y1551351D03*
X66229Y1549536D03*
X61605Y1546833D03*
X64275Y1546296D03*
X57811Y1598061D03*
X58633Y1587481D03*
X63633D03*
X61110Y1598146D03*
X58633Y1629896D03*
X64133Y1627896D03*
X64633Y1632896D03*
X64427Y1643496D03*
X64462Y1655624D03*
X61927Y1643496D03*
X65257Y1652941D03*
X56815Y1643431D03*
X62202Y1684579D03*
X66127Y1687362D03*
X79726Y145191D03*
X82026Y143491D03*
X71659Y149191D03*
X71779Y165194D03*
X71775Y153194D03*
X72462Y268223D03*
X77680Y378395D03*
Y380895D03*
X68020Y395222D03*
X80948Y525513D03*
Y521613D03*
X80318Y543313D03*
Y539413D03*
X80915Y767400D03*
X80784Y771366D03*
X68354Y1314097D03*
X80378Y1406676D03*
X83441Y1430500D03*
X81052Y1427410D03*
X81132Y1424195D03*
X79055Y1434000D03*
X73820Y1442893D03*
X81401Y1436105D03*
X73820Y1445945D03*
X73757Y1448500D03*
X81822Y1477075D03*
X77883Y1491440D03*
X80932D03*
X80852Y1488638D03*
X75245Y1491440D03*
X81822Y1480075D03*
Y1483075D03*
Y1486075D03*
X72396Y1491290D03*
X72390Y1499211D03*
X77883Y1499240D03*
X80833D03*
X77883Y1494040D03*
Y1496640D03*
X80932Y1494040D03*
Y1496640D03*
X75245Y1499240D03*
Y1494040D03*
Y1496640D03*
X72396Y1493890D03*
Y1496490D03*
X77920Y1538245D03*
X75796Y1545669D03*
X75396Y1542369D03*
X78796Y1545669D03*
X78096Y1542444D03*
X78372Y1556416D03*
Y1558916D03*
X78522Y1562641D03*
Y1565141D03*
Y1567888D03*
X78403Y1580311D03*
X81103D03*
X78522Y1570388D03*
X81468Y1570285D03*
X68133Y1587896D03*
X81006Y1593265D03*
X72660Y1587365D03*
X72375Y1604365D03*
X74133Y1610896D03*
X70567Y1625603D03*
X72255Y1616730D03*
X74134Y1621396D03*
X75380Y1627622D03*
X75764Y1636993D03*
X79164Y1636992D03*
X77427Y1644410D03*
X82127Y1687362D03*
X82500Y1698511D03*
Y1706511D03*
X82000Y1716331D03*
X82500Y1720331D03*
X82000Y1724331D03*
X92197Y143853D03*
X87137Y143663D03*
X93775Y197241D03*
Y212241D03*
Y207241D03*
Y202241D03*
X87520Y382219D03*
Y391391D03*
Y395865D03*
X90225Y610351D03*
X84057Y599372D03*
X84038Y602233D03*
X90225Y614351D03*
Y618351D03*
Y622351D03*
X94474Y766871D03*
X95790Y1278014D03*
X82953Y1307607D03*
X83023Y1311607D03*
X97546Y1385912D03*
X85736Y1391597D03*
X86827Y1404080D03*
X93000Y1417000D03*
Y1408000D03*
X93069Y1412500D03*
X85103Y1433051D03*
X93000Y1426000D03*
X97800Y1433000D03*
X93000Y1421500D03*
Y1444500D03*
Y1448500D03*
X84500Y1444500D03*
Y1448500D03*
X88722Y1476741D03*
X89092Y1491106D03*
X89042Y1488506D03*
X83991Y1491440D03*
X83892Y1488840D03*
X88722Y1479741D03*
Y1482741D03*
Y1485741D03*
X83892Y1499140D03*
X83991Y1494040D03*
Y1496540D03*
X84051Y1501690D03*
X83796Y1533746D03*
X83811Y1537296D03*
X91511Y1552296D03*
X93296Y1549142D03*
X97018Y1546331D03*
X88511Y1552296D03*
X83121Y1542294D03*
X94786Y1574205D03*
Y1576705D03*
X97486Y1574205D03*
Y1576705D03*
X83603Y1580311D03*
X84093Y1570285D03*
X90675Y1590783D03*
X96124Y1593458D03*
Y1595958D03*
X93424Y1593458D03*
X90675Y1593283D03*
X93424Y1595958D03*
X90675Y1595783D03*
X93537Y1598506D03*
X96237D03*
X90649Y1598507D03*
X84833Y1611896D03*
X90892Y1654749D03*
X85836Y1655143D03*
Y1658543D03*
X87891Y1671121D03*
Y1674521D03*
X90127Y1687362D03*
X96101Y1696469D03*
X82945Y1702511D03*
X95342Y1713741D03*
X96555Y1705508D03*
X95400Y1719741D03*
X95460Y1725241D03*
X101679Y151191D03*
X101675Y160694D03*
X100818Y165506D03*
Y168906D03*
X110616Y767400D03*
X110485Y771366D03*
X105165Y1300380D03*
Y1302880D03*
X107665D03*
Y1300380D03*
X102665Y1302880D03*
Y1300380D03*
X105165Y1305380D03*
X107665D03*
X102665D03*
Y1307880D03*
Y1310380D03*
Y1312880D03*
X105165Y1307880D03*
Y1310380D03*
Y1312880D03*
X107665D03*
Y1310380D03*
Y1307880D03*
X105165Y1315380D03*
X107665D03*
X105165Y1317880D03*
X107665D03*
X102665D03*
Y1315380D03*
X98101Y1369018D03*
Y1371559D03*
X104863Y1382593D03*
X99594Y1379933D03*
X104863Y1380085D03*
X112305Y1382130D03*
X108817Y1380530D03*
X111555Y1379562D03*
X101874Y1376408D03*
X111600Y1403100D03*
X113500Y1398600D03*
X110000Y1407425D03*
X110075Y1410500D03*
X101637Y1432938D03*
X102076Y1427833D03*
X101955Y1448660D03*
X101500Y1436000D03*
X102398Y1440000D03*
X113500Y1455600D03*
X112481Y1452424D03*
X112100Y1467500D03*
X103571Y1476485D03*
X103555Y1485128D03*
Y1479128D03*
Y1482128D03*
X109733Y1491367D03*
X110605Y1487896D03*
X104184Y1491292D03*
X106784D03*
X105453Y1487893D03*
X108053D03*
X102931Y1488097D03*
X101584Y1491292D03*
X106396Y1485113D03*
X108996D03*
X106371Y1482181D03*
X108971D03*
X107197Y1501756D03*
X109712Y1499196D03*
X104616Y1501811D03*
X107112Y1499196D03*
X109733Y1493967D03*
Y1496567D03*
X106784Y1493892D03*
Y1496492D03*
X101634D03*
X104512Y1499196D03*
X104184Y1496492D03*
Y1493892D03*
X101534Y1499244D03*
X101634Y1493992D03*
X101835Y1501863D03*
X109878Y1501879D03*
X102011Y1550242D03*
X99818Y1546296D03*
X111196Y1542569D03*
X111901Y1545543D03*
X112418Y1555680D03*
X112339Y1565015D03*
Y1562515D03*
X112418Y1558180D03*
X99986Y1574205D03*
Y1576705D03*
X108555Y1574657D03*
Y1577462D03*
X98824Y1593558D03*
X101524D03*
X98824Y1596058D03*
X101524D03*
X101637Y1598606D03*
X98937D03*
X112353Y1646612D03*
X110378Y1670313D03*
X99443Y1661931D03*
Y1658531D03*
X110378Y1674313D03*
X100443Y1684063D03*
Y1687463D03*
X107500Y1707450D03*
X115016Y300281D03*
Y320715D03*
X118407Y526766D03*
X113042Y686285D03*
X113980Y717480D03*
X116480D03*
X118980D03*
X121480D03*
X123980D03*
X113980Y714980D03*
X116480D03*
X118980D03*
X121480D03*
X123980D03*
X116480Y722480D03*
X118980D03*
X121480D03*
X123980D03*
X113980Y719980D03*
X116480D03*
X118980D03*
X121480D03*
X123980D03*
X113980Y722480D03*
X124174Y766871D03*
X120965Y1307880D03*
Y1310380D03*
Y1312880D03*
X118465D03*
Y1310380D03*
Y1307880D03*
Y1300380D03*
X123465Y1302880D03*
Y1300380D03*
X120965Y1305380D03*
X118465D03*
X123465D03*
Y1307880D03*
Y1310380D03*
Y1312880D03*
X120965Y1300380D03*
Y1302880D03*
X118465D03*
X120965Y1315380D03*
X118465D03*
X120965Y1317880D03*
X118465D03*
X123465D03*
Y1315380D03*
X121207Y1363643D03*
X115321Y1372872D03*
X120181D03*
X117751D03*
X121241Y1367047D03*
Y1369947D03*
X127211Y1373177D03*
Y1378977D03*
X125111Y1377577D03*
X122945Y1379207D03*
X127211Y1376077D03*
X125011Y1374577D03*
X122945Y1376307D03*
X122050Y1403750D03*
X129200Y1401000D03*
X124700D03*
X126000Y1414000D03*
Y1418000D03*
X116700Y1415700D03*
Y1410500D03*
X120700Y1408100D03*
X116900Y1449000D03*
X113600Y1449100D03*
X116122Y1458000D03*
X119100Y1460300D03*
X124600Y1465100D03*
X121500Y1467400D03*
X113100Y1537346D03*
X114030Y1542419D03*
X114610Y1545543D03*
X121705Y1619460D03*
X114618Y1624541D03*
X117655Y1621766D03*
X118956Y1635244D03*
X124312Y1633488D03*
X126717Y1635893D03*
X126428Y1658587D03*
X126760Y1682383D03*
X123353Y1695941D03*
X127353Y1696062D03*
X127710Y1700166D03*
X127290Y1705666D03*
X125183Y1716741D03*
X127168Y1721695D03*
X129020Y1726741D03*
X140360Y430160D03*
X141642Y488684D03*
Y494147D03*
X139980Y507420D03*
X139890Y503440D03*
X140471Y670445D03*
X131752Y668506D03*
X134902D03*
X140600Y683029D03*
X131752Y686074D03*
X134902D03*
X131960Y679290D03*
X140317Y767400D03*
Y771200D03*
X140265Y1307880D03*
Y1310380D03*
Y1312880D03*
X137765D03*
Y1310380D03*
Y1307880D03*
X135265Y1312880D03*
Y1310380D03*
Y1307880D03*
Y1305380D03*
X140265D03*
X137765D03*
X135265Y1300380D03*
Y1302880D03*
X140265Y1300380D03*
Y1302880D03*
X137765D03*
Y1300380D03*
X140265Y1315380D03*
X137765D03*
X135265D03*
Y1317880D03*
X140265D03*
X137765D03*
X130701Y1369018D03*
Y1371559D03*
X137463Y1382593D03*
X132194Y1379933D03*
X137463Y1380085D03*
X141417Y1380530D03*
X134474Y1376408D03*
X138000Y1400600D03*
X134800Y1408100D03*
X142000Y1414500D03*
X136000Y1432000D03*
X141500Y1433500D03*
Y1429500D03*
X139500Y1446000D03*
X133100Y1444100D03*
X138013Y1440487D03*
X141514Y1436500D03*
X128661Y1464000D03*
X139802Y1556133D03*
X129070Y1608338D03*
X137386Y1626412D03*
X135543Y1637055D03*
X132353Y1646612D03*
X136353D03*
X142465Y1662493D03*
X143000Y1701011D03*
X142293Y1705166D03*
X129493Y1711846D03*
X143000Y1709166D03*
X135722Y1715672D03*
X147920Y28261D03*
X148780Y48720D03*
X149231Y224204D03*
X148228Y216118D03*
X158380Y419760D03*
X147450Y423860D03*
X154770Y441830D03*
X147810Y475710D03*
X146982Y521997D03*
Y530997D03*
X159513Y674855D03*
X152822Y665500D03*
X153875Y766871D03*
X151065Y1307880D03*
Y1310380D03*
Y1312880D03*
X153565D03*
Y1310380D03*
Y1307880D03*
X156065Y1312880D03*
Y1310380D03*
Y1307880D03*
Y1305380D03*
X151065D03*
X153565D03*
X156065Y1300380D03*
Y1302880D03*
X151065Y1300380D03*
Y1302880D03*
X153565D03*
Y1300380D03*
X151065Y1315380D03*
X153565D03*
X156065D03*
Y1317880D03*
X151065D03*
X153565D03*
X152781Y1372872D03*
X150351D03*
X147921D03*
X153741Y1369977D03*
Y1367077D03*
X144905Y1382130D03*
X144155Y1379562D03*
X155545Y1379207D03*
Y1376307D03*
X145000Y1414425D03*
X150900Y1425500D03*
X154443Y1441195D03*
X156174Y1435396D03*
X156477Y1447733D03*
X154083Y1456007D03*
X148340Y1454674D03*
X154671Y1450019D03*
X154305Y1453101D03*
X159000Y1525480D03*
X155618Y1549331D03*
X155071Y1543604D03*
X152843Y1559146D03*
Y1562666D03*
X154945Y1624350D03*
X146453Y1614879D03*
X149171Y1616759D03*
X154945Y1627750D03*
X142576Y1640163D03*
X152353Y1646612D03*
X142576Y1643563D03*
X154111Y1663933D03*
X154010Y1676811D03*
X157410D03*
X143778Y1685087D03*
X147253Y1696343D03*
X155353Y1687843D03*
X159427Y1696652D03*
X152605Y1715941D03*
X149338Y1705603D03*
X156825Y1705510D03*
X146000Y1718241D03*
X146086Y1705603D03*
X145267Y1722241D03*
X152496Y1722941D03*
X146483Y1725636D03*
X155260Y1723682D03*
X162830Y396930D03*
X172120Y412350D03*
X172010Y474900D03*
X166760Y506880D03*
X166670Y502900D03*
X163372Y670863D03*
X172725Y667898D03*
X162482Y679319D03*
X161735Y684456D03*
X172725Y679230D03*
X169987Y767666D03*
Y771266D03*
X170265Y1312880D03*
Y1310380D03*
Y1307880D03*
X167765Y1312880D03*
Y1310380D03*
Y1307880D03*
Y1305380D03*
X170265D03*
X167765Y1300380D03*
Y1302880D03*
X170265D03*
Y1300380D03*
Y1315380D03*
X167765D03*
Y1317880D03*
X170265D03*
X163401Y1369018D03*
Y1371559D03*
X159811Y1373177D03*
X170163Y1382593D03*
X164894Y1379933D03*
X170163Y1380085D03*
X167174Y1376408D03*
X159811Y1378977D03*
Y1376077D03*
X157711Y1377577D03*
X157611Y1374577D03*
X163099Y1414400D03*
X162873Y1411611D03*
X163061Y1409048D03*
Y1406548D03*
X160684Y1441046D03*
X158704Y1439411D03*
X161210Y1443542D03*
X163271Y1441588D03*
X163148Y1474504D03*
X172180Y1490210D03*
X172070Y1495550D03*
X163460Y1491010D03*
X163320Y1494340D03*
X161188Y1510800D03*
X162188Y1518040D03*
X162531Y1523331D03*
Y1526731D03*
X167666Y1550751D03*
X165166D03*
X162666D03*
X170166D03*
X170230Y1542960D03*
X160150Y1553251D03*
Y1555751D03*
X162666D03*
X165166D03*
X167666D03*
X170166D03*
Y1553251D03*
X167666D03*
X165166D03*
X162666D03*
X170166Y1567621D03*
X167666D03*
X165166D03*
X162666D03*
X170166Y1565121D03*
X167666D03*
X165166D03*
X162666D03*
Y1562621D03*
X165166D03*
X167666D03*
X170166D03*
X162466Y1570121D03*
X164966D03*
X167466D03*
X169966D03*
X163735Y1635369D03*
Y1631969D03*
X157511Y1663933D03*
X165491Y1665582D03*
Y1662182D03*
X165336Y1675077D03*
Y1678477D03*
X162740Y1713172D03*
Y1704885D03*
X166467Y1720973D03*
X171925Y1717984D03*
X171945Y1730693D03*
X162740Y1723886D03*
X184930Y125502D03*
X181025Y159123D03*
X183890Y388180D03*
X174320Y395040D03*
X189290Y396730D03*
X177675Y419260D03*
X185160Y419220D03*
X181550Y441290D03*
X182500Y672500D03*
X172500Y684799D03*
X183576Y766871D03*
X183565Y1310380D03*
Y1312880D03*
X186065D03*
Y1310380D03*
Y1307880D03*
X172765D03*
Y1310380D03*
Y1312880D03*
X183565Y1307880D03*
Y1305380D03*
X186065D03*
X183565Y1300380D03*
Y1302880D03*
X186065D03*
Y1300380D03*
X172765Y1305380D03*
Y1300380D03*
Y1302880D03*
Y1315380D03*
X183565D03*
X186065D03*
X183565Y1317880D03*
X186065D03*
X172765D03*
X185481Y1372872D03*
X183051D03*
X180621D03*
X186481Y1370147D03*
Y1367247D03*
X177605Y1382130D03*
X174117Y1380530D03*
X176855Y1379562D03*
X185558Y1418560D03*
Y1416060D03*
X183058Y1418560D03*
Y1416060D03*
X173164Y1406397D03*
Y1408897D03*
X172976Y1411460D03*
X173202Y1414249D03*
X185558Y1421060D03*
Y1423560D03*
Y1426060D03*
X183058Y1421060D03*
Y1426060D03*
Y1423560D03*
Y1428560D03*
X185558D03*
X173490Y1542540D03*
X173050Y1555751D03*
Y1553251D03*
X178582Y1575390D03*
X181087Y1576135D03*
X178582Y1572490D03*
Y1569590D03*
X180292Y1582589D03*
X177792D03*
X177509Y1653825D03*
X177666Y1649223D03*
X183974Y1656804D03*
X183920Y1653973D03*
X184139Y1651088D03*
X180103Y1668921D03*
X177672Y1657538D03*
X183986Y1659548D03*
X182533Y1676854D03*
X185124Y1701851D03*
X185084Y1691988D03*
X179999Y1699156D03*
X185173Y1695138D03*
X178385Y1715441D03*
X183813Y1705404D03*
X178376Y1720559D03*
X185760Y1731666D03*
X204088Y138912D03*
X200577Y125502D03*
X190000Y143000D03*
X191264Y147768D03*
X193610Y153951D03*
X192592Y353072D03*
X188055Y731734D03*
X199718Y767400D03*
X197651Y769241D03*
X200365Y1312880D03*
Y1310380D03*
Y1307880D03*
Y1305380D03*
Y1300380D03*
Y1302880D03*
X188565Y1312880D03*
Y1310380D03*
Y1307880D03*
Y1305380D03*
Y1300380D03*
Y1302880D03*
X200365Y1315380D03*
Y1317880D03*
X188565Y1315380D03*
Y1317880D03*
X196301Y1369018D03*
Y1371559D03*
X192511Y1373177D03*
X197794Y1379933D03*
X200074Y1376408D03*
X188245Y1379207D03*
X190411Y1377577D03*
X192511Y1378977D03*
X190311Y1374577D03*
X188245Y1376307D03*
X192511Y1376077D03*
X200408Y1416249D03*
Y1418749D03*
X192983Y1417568D03*
X188058Y1416060D03*
Y1418560D03*
X190483Y1417568D03*
X197983D03*
X195483D03*
X188695Y1404813D03*
Y1407313D03*
X191995Y1404813D03*
Y1407313D03*
X194495Y1404813D03*
Y1407313D03*
X196995Y1404813D03*
Y1407313D03*
X199495Y1404813D03*
Y1407313D03*
X188507Y1409876D03*
X191807D03*
X194307D03*
X196807D03*
X199307D03*
X200558Y1421551D03*
X195483Y1420068D03*
X192983D03*
X195483Y1422568D03*
X197983D03*
X192983D03*
X188058Y1421060D03*
Y1423560D03*
X190483Y1420068D03*
Y1422568D03*
X197983Y1420068D03*
X188058Y1426060D03*
X193679Y1640052D03*
Y1643452D03*
X198698Y1662215D03*
X199747Y1675603D03*
X200424Y1686870D03*
X197780Y1696973D03*
X200478Y1701758D03*
X200448Y1690771D03*
X202076Y1717845D03*
X189760Y1713061D03*
X193274Y1709769D03*
X199843Y1709837D03*
X203510Y1712441D03*
X196763Y1710444D03*
X189760Y1723041D03*
Y1731564D03*
X194000Y1720551D03*
X203655Y1723000D03*
X198760Y1719991D03*
X217687Y522453D03*
X214999Y585668D03*
X211254Y595145D03*
X208254D03*
X211009Y610001D03*
X208009D03*
X214202Y606943D03*
X208254Y603245D03*
X211254D03*
X214202Y609681D03*
X208326Y606918D03*
X211326D03*
X210199Y714074D03*
X206199D03*
X206254Y732537D03*
X206933Y737277D03*
X208818Y766871D03*
X205365Y1307880D03*
Y1310380D03*
Y1312880D03*
X202865D03*
Y1310380D03*
Y1307880D03*
X216165D03*
Y1310380D03*
Y1312880D03*
Y1305380D03*
Y1300380D03*
Y1302880D03*
X205365Y1305380D03*
X202865D03*
X205365Y1300380D03*
Y1302880D03*
X202865D03*
Y1300380D03*
X205365Y1315380D03*
X202865D03*
X216165D03*
Y1317880D03*
X205365D03*
X202865D03*
X213521Y1372872D03*
X215951D03*
X203063Y1382593D03*
Y1380085D03*
X210505Y1382130D03*
X207017Y1380530D03*
X209755Y1379562D03*
X205558Y1418560D03*
Y1416060D03*
X202945Y1415910D03*
Y1418410D03*
X208058Y1416060D03*
X208061Y1418605D03*
X205479Y1652130D03*
Y1648730D03*
X206788Y1660960D03*
X210833Y1660867D03*
X210217Y1668603D03*
X207807Y1681302D03*
Y1696409D03*
X211862Y1701100D03*
X212365Y1705403D03*
X211000Y1717675D03*
X229131Y26477D03*
X225731D03*
X229127Y50649D03*
X225727D03*
X233284Y137195D03*
X221051Y153167D03*
X223687Y522453D03*
X229687D03*
X226599Y570970D03*
X217999Y585668D03*
X223999D03*
X220999D03*
X217202Y606943D03*
X220202D03*
X223202D03*
X223111Y603782D03*
X225895Y609691D03*
X228895D03*
X220111Y603782D03*
X217202Y609681D03*
X220202D03*
X223202D03*
X218024Y622385D03*
X221024D03*
X224024D03*
X227024D03*
X221024Y632385D03*
X218024D03*
X224024D03*
X227024D03*
X224157Y715915D03*
Y712915D03*
X229263Y765863D03*
X229275Y769292D03*
X218665Y1312880D03*
Y1310380D03*
Y1307880D03*
X221165Y1312880D03*
Y1310380D03*
Y1307880D03*
Y1305380D03*
X218665D03*
X221165Y1300380D03*
Y1302880D03*
X218665D03*
Y1300380D03*
Y1315380D03*
X221165D03*
Y1317880D03*
X218665D03*
X229101Y1369018D03*
Y1371559D03*
X218381Y1372872D03*
X219401Y1370067D03*
Y1367167D03*
X225411Y1373177D03*
X230594Y1379933D03*
X225411Y1378977D03*
Y1376077D03*
X221145Y1379207D03*
X223311Y1377577D03*
X223211Y1374577D03*
X221145Y1376307D03*
X238059Y26235D03*
X233335Y17665D03*
X235697Y21585D03*
X241306Y20325D03*
X246356Y26855D03*
X246506Y20365D03*
X242216Y39365D03*
X246216D03*
X238059Y37165D03*
X235697Y39755D03*
X248816Y48965D03*
X239816Y54365D03*
X248487Y68690D03*
X242920Y67915D03*
X238846Y72977D03*
X235186Y98067D03*
X234331Y103286D03*
X232529Y114830D03*
X238297Y121555D03*
X244818Y111546D03*
Y115546D03*
X235460Y115790D03*
X235186Y112022D03*
X238600Y130400D03*
X235147Y124435D03*
X243813Y132383D03*
X241271Y130719D03*
X234000Y148000D03*
X239988Y141986D03*
X236104Y151996D03*
X245486Y159705D03*
X234628Y166735D03*
X240413Y360867D03*
X233413D03*
X235913D03*
X243845Y656940D03*
X246045Y655540D03*
X243845Y651140D03*
Y654040D03*
X245945Y652540D03*
X232981Y743983D03*
X240200Y766300D03*
X246371Y772388D03*
X232965Y1297880D03*
X237965D03*
X235465D03*
Y1300380D03*
Y1302880D03*
X237965D03*
Y1300380D03*
X235465Y1305380D03*
X237965D03*
X232965Y1302880D03*
Y1300380D03*
Y1305380D03*
Y1307880D03*
Y1310380D03*
Y1312880D03*
X237965Y1307880D03*
Y1310380D03*
Y1312880D03*
X235465D03*
Y1310380D03*
Y1307880D03*
X237965Y1315380D03*
X235465D03*
X232965D03*
X246321Y1372872D03*
X235863Y1380085D03*
X243305Y1382130D03*
X239817Y1380530D03*
X242555Y1379562D03*
X235863Y1382593D03*
X232874Y1376408D03*
X255106Y16615D03*
X251106Y12615D03*
X250216Y39365D03*
X254046Y39425D03*
X259316Y48965D03*
X261016Y51565D03*
X252316Y48965D03*
X255816D03*
X254016Y51565D03*
X250516D03*
X257516D03*
X247893Y100546D03*
X248093Y92146D03*
X261416Y100665D03*
X253874Y111774D03*
X252800Y114800D03*
X256586Y138373D03*
X260596Y151065D03*
X248350Y165700D03*
X257252Y156730D03*
X258439Y214000D03*
X247859Y375389D03*
X250359D03*
X254859D03*
X247694Y378523D03*
X250194D03*
X254694D03*
X258751Y647987D03*
X262239Y649587D03*
X259501Y650555D03*
X255735Y657245D03*
X253305D03*
X250875D03*
X248111Y653810D03*
Y650910D03*
X250312Y663080D03*
Y660180D03*
X247587Y714760D03*
Y717260D03*
X252591Y714737D03*
Y717237D03*
X250091D03*
Y714737D03*
X247587Y712237D03*
X250087D03*
X252587D03*
X247587Y719760D03*
X252591Y719737D03*
X250091D03*
X247587Y724760D03*
X252587D03*
X250087D03*
X247587Y722260D03*
Y727260D03*
X250087Y729760D03*
X247587D03*
X250087Y727260D03*
X252587D03*
Y729760D03*
X252591Y722237D03*
X250091D03*
X254671Y776388D03*
X257071Y772770D03*
X260971Y777988D03*
X248765Y1297880D03*
X251265D03*
X248765Y1292880D03*
Y1295380D03*
X251265D03*
Y1292880D03*
X248765Y1307880D03*
Y1310380D03*
Y1312880D03*
X251265D03*
Y1310380D03*
Y1307880D03*
X248765Y1305380D03*
X251265D03*
X248765Y1300380D03*
Y1302880D03*
X251265D03*
Y1300380D03*
X248765Y1315380D03*
X251265D03*
Y1317880D03*
X248765D03*
X248751Y1372872D03*
X251181D03*
X252211Y1370232D03*
Y1367332D03*
X258211Y1373177D03*
X256111Y1377577D03*
X258211Y1378977D03*
X256011Y1374577D03*
X258211Y1376077D03*
X253945Y1379207D03*
Y1376307D03*
X261530Y1550300D03*
X275116Y28565D03*
X275896Y48875D03*
X266420Y39120D03*
X265365Y49171D03*
X263516Y51565D03*
X261816Y48965D03*
X263182Y73396D03*
X269860Y72741D03*
X262893Y77529D03*
Y80029D03*
X263316Y87665D03*
X275238Y83024D03*
X264916Y100665D03*
X268416D03*
X262916Y97965D03*
X266416D03*
X269916D03*
X273616Y96665D03*
X264293Y120972D03*
X269487Y121095D03*
X275793Y120248D03*
X266000Y125800D03*
X275793Y129595D03*
X266971Y140110D03*
X264574Y151206D03*
X276821Y140465D03*
X270178Y140322D03*
X262500Y161100D03*
X273500Y207500D03*
X266360Y203070D03*
X269925Y217700D03*
X274993Y522052D03*
X269568Y522366D03*
X266327Y522456D03*
X274096Y574698D03*
X273208Y588237D03*
X267601Y608378D03*
X271462Y650184D03*
X266193Y650032D03*
X272955Y658558D03*
X266193Y647524D03*
X269182Y653709D03*
X272955Y661099D03*
X276575Y685381D03*
Y688281D03*
Y691181D03*
X265891Y714737D03*
Y717237D03*
X263391D03*
Y714737D03*
X263387Y712237D03*
X265887D03*
X265891Y719737D03*
X263391D03*
X265787Y724760D03*
X263287D03*
X265787Y727260D03*
X263287D03*
X265787Y729760D03*
X263287D03*
X265787Y732260D03*
X263287D03*
X265891Y722237D03*
X263391D03*
X265787Y737260D03*
X263287D03*
X265787Y734760D03*
X263287D03*
X271161Y780588D03*
X268991Y783248D03*
X271245Y785474D03*
X274282Y786741D03*
X272054Y801112D03*
X270850Y797605D03*
X272165Y1256716D03*
X269665Y1259216D03*
X272165D03*
X269765Y1269234D03*
X272265D03*
X269765Y1261734D03*
Y1264234D03*
Y1266734D03*
X272265D03*
Y1264234D03*
Y1261734D03*
X267179Y1269273D03*
Y1266773D03*
Y1264273D03*
Y1261773D03*
Y1271773D03*
X269679D03*
X272179D03*
X262701Y1322872D03*
Y1325413D03*
X264194Y1333787D03*
X269463Y1333939D03*
X273417Y1334384D03*
X276155Y1333416D03*
X269463Y1336447D03*
X266474Y1330262D03*
X269829Y1521436D03*
X273597Y1519845D03*
X269144Y1511953D03*
X273474Y1516120D03*
Y1512220D03*
X269144Y1514453D03*
Y1516953D03*
X267322Y1519250D03*
X276624Y1516120D03*
Y1512220D03*
X276637Y1521436D03*
X274546Y1549295D03*
Y1546795D03*
X267297Y1546119D03*
X286996Y20365D03*
X290795Y28365D03*
X284228Y25935D03*
X280828D03*
X282716Y40020D03*
X290716D03*
X287988Y54893D03*
X291379Y55746D03*
X293157Y50525D03*
X284226Y50649D03*
X280826D03*
X278638Y83024D03*
X288553Y105006D03*
X285353D03*
X280853Y109906D03*
X282853Y115606D03*
X285853D03*
X280853Y107306D03*
X286996Y139865D03*
X283049Y139731D03*
X288000Y209000D03*
X290000Y222575D03*
X289163Y212503D03*
X278425Y230925D03*
X289393Y498960D03*
X278547Y523041D03*
X284018Y522300D03*
X287723Y548499D03*
X289421Y575098D03*
X291481Y682228D03*
X280841Y688051D03*
X278675Y686781D03*
X280841Y685151D03*
X288465Y691493D03*
X283605D03*
X286035D03*
X278775Y689781D03*
X283042Y697280D03*
Y694380D03*
X285317Y746478D03*
X282817D03*
X280317D03*
Y759110D03*
X285317D03*
X282817D03*
X285317Y761610D03*
X285321Y748978D03*
Y751478D03*
Y753978D03*
X282821D03*
Y751478D03*
Y748978D03*
X285321Y756478D03*
X282821D03*
X280317Y756610D03*
Y751610D03*
Y754110D03*
Y749110D03*
Y761610D03*
X282817D03*
X284035Y796850D03*
X285258Y799314D03*
X282323Y794867D03*
X281449Y809609D03*
X283987Y811342D03*
X285565Y1246716D03*
X288065D03*
X283065D03*
X288065Y1251716D03*
X285565D03*
X283065D03*
X288065Y1249216D03*
X285565D03*
X283065D03*
Y1254216D03*
X288065D03*
X285565D03*
X283065Y1269234D03*
X285565D03*
X283065Y1261734D03*
Y1264234D03*
Y1266734D03*
X285565D03*
Y1264234D03*
Y1261734D03*
X283065Y1256716D03*
X285565D03*
X288065D03*
X283065Y1259216D03*
X285565D03*
X288065D03*
Y1266716D03*
Y1264216D03*
Y1261716D03*
Y1269216D03*
X285479Y1271773D03*
X282979D03*
X287979D03*
X284781Y1326726D03*
X282351D03*
X279921D03*
X285891Y1320942D03*
Y1323842D03*
X289611Y1328431D03*
X276905Y1335984D03*
X289711Y1331431D03*
X287545Y1330161D03*
Y1333061D03*
X280088Y1509469D03*
X282588D03*
X279774Y1512220D03*
Y1516120D03*
X284024Y1514576D03*
X279499Y1519845D03*
X284024Y1512076D03*
X290593Y1523331D03*
Y1526731D03*
X291416Y1541795D03*
Y1549295D03*
Y1546795D03*
Y1544295D03*
X285586Y1551844D03*
X288004Y1551099D03*
X290509Y1551844D03*
X288004Y1548199D03*
X284014Y1538682D03*
X286514D03*
X284546Y1549295D03*
Y1546795D03*
Y1541795D03*
Y1544295D03*
X287046D03*
Y1541795D03*
X277046Y1546795D03*
Y1549295D03*
X282046D03*
Y1546795D03*
Y1544295D03*
X279546Y1549295D03*
Y1546795D03*
X282046Y1541795D03*
X300230Y14820D03*
X302606Y26365D03*
X292056Y24475D03*
X295516Y26365D03*
X300244Y28365D03*
X299496Y22865D03*
X304923Y24657D03*
X304968Y28365D03*
X303252Y38199D03*
X298716Y40020D03*
X296337Y55855D03*
X301306Y52485D03*
X298542Y51088D03*
X303711Y50860D03*
X295755Y72800D03*
X301107Y75676D03*
X305820Y73693D03*
X303852Y65042D03*
X306470Y65160D03*
X301780Y82900D03*
X299002Y88700D03*
X307816Y95727D03*
X301179Y112806D03*
Y110006D03*
Y107106D03*
X296478Y149203D03*
X296474Y158706D03*
X292811Y213242D03*
X296283Y242391D03*
X306528Y256528D03*
X297815Y580384D03*
X294299Y577188D03*
X302130Y584160D03*
X304192Y684425D03*
X298923Y684273D03*
X294969Y683828D03*
X292231Y684796D03*
X298923Y681765D03*
X301912Y687950D03*
X305685Y695340D03*
Y692799D03*
X298617Y746478D03*
X296117D03*
X301117D03*
X298621Y753978D03*
X296121D03*
Y751478D03*
Y748978D03*
X298621Y756478D03*
X296121D03*
X301121Y748996D03*
Y751496D03*
Y753996D03*
Y756496D03*
X296117Y759110D03*
Y761610D03*
X301117Y759110D03*
X298617D03*
X301117Y761610D03*
X298617D03*
X298621Y748978D03*
Y751478D03*
X301117Y766610D03*
X296117D03*
Y764110D03*
X301117Y771610D03*
X298617D03*
Y769110D03*
X301117D03*
X296117Y771610D03*
Y769110D03*
X298617Y766610D03*
Y764110D03*
X301117D03*
X305061Y1254131D03*
X300061D03*
X302561D03*
X305061Y1249131D03*
Y1251631D03*
X300061D03*
X302561D03*
X300061Y1249131D03*
X302561D03*
X305061Y1246631D03*
X300061D03*
X302561D03*
X302661Y1269149D03*
X305161D03*
X302661Y1261649D03*
Y1264149D03*
Y1266649D03*
X305161D03*
Y1264149D03*
Y1261649D03*
X300061Y1269131D03*
Y1266631D03*
X305061Y1259131D03*
Y1256631D03*
X300061D03*
Y1259131D03*
Y1261631D03*
Y1264131D03*
X302561Y1256631D03*
Y1259131D03*
X305075Y1271688D03*
X302575D03*
X300075D03*
X295597Y1322844D03*
Y1325385D03*
X291811Y1327031D03*
X297090Y1333759D03*
X302359Y1333911D03*
X306313Y1334356D03*
X302359Y1336419D03*
X299370Y1330234D03*
X291811Y1332831D03*
Y1329931D03*
X294725Y1381612D03*
X294533Y1384401D03*
X305204Y1381461D03*
X305012Y1384250D03*
X294684Y1387040D03*
X305163Y1386889D03*
X294683Y1390281D03*
X305163Y1389678D03*
X295042Y1530596D03*
X296416Y1549295D03*
X293916D03*
Y1546795D03*
X296416D03*
Y1544295D03*
X293916D03*
X296416Y1541795D03*
X293916D03*
X298916D03*
Y1549295D03*
Y1546795D03*
Y1544295D03*
X303041Y1544299D03*
X297323Y1657172D03*
Y1653772D03*
X310396Y50365D03*
X306566Y50225D03*
X323036Y73125D03*
X310455Y75895D03*
X320190Y77648D03*
X314653Y71806D03*
Y68906D03*
X312410Y89060D03*
X322871Y84321D03*
X316982Y89003D03*
X311053Y112806D03*
Y110006D03*
Y107106D03*
X323646Y147120D03*
Y152120D03*
X308240Y148100D03*
X317472Y222262D03*
Y225217D03*
X319970Y228167D03*
X320095Y231810D03*
X319075Y260075D03*
X311749Y440921D03*
X314780Y545716D03*
X322955Y556148D03*
X310445Y700931D03*
X312611Y702301D03*
X321235Y711636D03*
X316375D03*
X318805D03*
X311545Y709931D03*
X310445Y703931D03*
X311445Y706931D03*
X313611Y708201D03*
Y705301D03*
X315912Y717400D03*
Y714500D03*
X313087Y769160D03*
Y771660D03*
Y774160D03*
Y776660D03*
X318091Y769128D03*
Y771628D03*
Y774128D03*
X315591D03*
Y771628D03*
Y769128D03*
X318091Y776628D03*
X315591D03*
X313087Y766628D03*
X315587D03*
X318087D03*
Y791660D03*
X313087D03*
X315587D03*
X318087Y789160D03*
X313087D03*
X315587D03*
Y779160D03*
X313087Y784160D03*
X315587D03*
X313087Y786660D03*
X315587D03*
X313087Y781660D03*
X315587D03*
X313087Y779160D03*
X318087Y786660D03*
Y784160D03*
Y779160D03*
Y781660D03*
X313284Y1218522D03*
Y1215122D03*
X318461Y1254131D03*
X320961D03*
X315961D03*
Y1249131D03*
X318461D03*
X320961D03*
X315961Y1251631D03*
X318461D03*
X320961D03*
X315961Y1246631D03*
X318461D03*
X320961D03*
X315961Y1269149D03*
X318461D03*
X315961Y1261649D03*
Y1264149D03*
Y1266649D03*
X318461D03*
Y1264149D03*
Y1261649D03*
X320961Y1269131D03*
Y1256631D03*
Y1259131D03*
Y1261631D03*
X318461Y1256631D03*
Y1259131D03*
X320961Y1264131D03*
Y1266631D03*
X315961Y1256631D03*
Y1259131D03*
X320875Y1271688D03*
X315875D03*
X318375D03*
X312817Y1326698D03*
X315247D03*
X317677D03*
X318811Y1320902D03*
Y1323802D03*
X309801Y1335956D03*
X309051Y1333388D03*
X320441Y1330133D03*
Y1333033D03*
X307255Y1643750D03*
Y1647150D03*
X323113Y76941D03*
X334339Y162580D03*
X323646Y160120D03*
Y156120D03*
X331780Y182900D03*
X336000Y284000D03*
X324406Y367744D03*
X325816Y543012D03*
X324647Y566086D03*
X334031Y613498D03*
Y610498D03*
X331391D03*
Y613498D03*
X333502Y600019D03*
Y603019D03*
X330109Y602883D03*
Y605883D03*
X334031Y619398D03*
Y616498D03*
X331391D03*
Y619398D03*
X324251Y702378D03*
X331693Y701915D03*
Y704423D03*
X327739Y703978D03*
X325001Y704946D03*
X334682Y708100D03*
X331391Y769128D03*
Y771628D03*
Y774128D03*
X328891D03*
Y771628D03*
Y769128D03*
X331391Y776628D03*
X328891D03*
X333887Y766628D03*
X328887D03*
X331387D03*
X333891Y776646D03*
Y774146D03*
Y771646D03*
Y769146D03*
X333887Y791660D03*
X328887D03*
X331387D03*
X333887Y789160D03*
X328887D03*
X331387D03*
X333887Y779160D03*
Y781660D03*
X331387Y779160D03*
X328887D03*
Y781660D03*
X331387D03*
X333887Y786660D03*
X328887D03*
X331387D03*
X333887Y784160D03*
X328887D03*
X331387D03*
X335465Y1246631D03*
X332965D03*
X335465Y1249131D03*
X332965D03*
X335465Y1251631D03*
X332965D03*
X335465Y1254131D03*
X332965D03*
X335465Y1259131D03*
Y1256631D03*
X332965Y1259131D03*
Y1256631D03*
X335565Y1269149D03*
Y1261649D03*
Y1264149D03*
Y1266649D03*
X332961Y1269188D03*
Y1266688D03*
Y1261688D03*
Y1264188D03*
Y1271688D03*
X335461D03*
X328501Y1322787D03*
Y1325328D03*
X324707Y1327003D03*
X322507Y1328403D03*
X329994Y1333702D03*
X335263Y1333854D03*
Y1336362D03*
X332274Y1330177D03*
X324707Y1332803D03*
X322607Y1331403D03*
X324707Y1329903D03*
X334038Y1373469D03*
X334230Y1370680D03*
X323559Y1373620D03*
X323751Y1370831D03*
X334189Y1376108D03*
X323710Y1376259D03*
X334189Y1378897D03*
X323709Y1379500D03*
X341082Y56308D03*
X340436Y120555D03*
X343446Y131170D03*
X338244Y192264D03*
X344984Y199299D03*
X344106Y222659D03*
X348107Y220420D03*
X341895Y233980D03*
X348645Y229180D03*
X352000Y230643D03*
Y235643D03*
X344034Y282609D03*
X348890Y409120D03*
Y411620D03*
X340337Y496462D03*
X346751Y515376D03*
X351157Y550415D03*
X350566Y541882D03*
X351018Y554896D03*
X351157Y566936D03*
X345521Y564388D03*
X349397Y564459D03*
X351157Y570415D03*
X341500Y574500D03*
X342500Y582500D03*
Y578500D03*
X338420Y574500D03*
X351157Y590415D03*
Y586415D03*
X337031Y607498D03*
Y613498D03*
Y610498D03*
X346031Y607498D03*
X343031D03*
X349031D03*
X346031Y610498D03*
X343031D03*
X349031D03*
X340031Y607498D03*
Y610498D03*
Y613498D03*
X346031Y604498D03*
X343031D03*
X349031D03*
X340031D03*
X343691Y614018D03*
X346191D03*
X348691D03*
X343721Y618348D03*
X346221D03*
X348721D03*
X351191Y614018D03*
X351221Y618348D03*
X340031Y619398D03*
Y616498D03*
X337031Y619398D03*
Y616498D03*
X342675Y640994D03*
X345175D03*
X347675D03*
X350175D03*
X342675Y643494D03*
X345175D03*
X347675D03*
X350175D03*
X342595Y646054D03*
X345095D03*
X347595D03*
X350095D03*
X336962Y704575D03*
X338455Y715490D03*
Y712949D03*
X349435Y711368D03*
X346671Y705033D03*
X344505Y706663D03*
X346671Y707933D03*
X344605Y709663D03*
X342405Y705263D03*
Y708163D03*
Y711063D03*
X348395Y717060D03*
Y714160D03*
X346051Y769058D03*
Y771558D03*
Y774058D03*
Y776558D03*
X351151Y769040D03*
Y771540D03*
Y774040D03*
X348651D03*
Y771540D03*
Y769040D03*
X351151Y776540D03*
X348651D03*
X351147Y766540D03*
X348647D03*
X346147D03*
X346051Y791558D03*
X348551D03*
X351051D03*
X346051Y789058D03*
X348551D03*
X346051Y784058D03*
X348551D03*
X346051Y786558D03*
X348551D03*
X346051Y779058D03*
X348551D03*
X346051Y781558D03*
X348551D03*
X351051Y789058D03*
Y784058D03*
Y786558D03*
Y779058D03*
Y781558D03*
X347107Y1174343D03*
X339278Y1192112D03*
X336778D03*
X347885Y1206426D03*
X339532Y1218605D03*
X349938Y1214563D03*
X337965Y1251631D03*
Y1249131D03*
Y1254131D03*
X348865Y1246631D03*
Y1251631D03*
Y1249131D03*
Y1254131D03*
X337965Y1246631D03*
X348865Y1269149D03*
Y1261649D03*
Y1264149D03*
Y1266649D03*
X338065Y1269149D03*
Y1266649D03*
Y1264149D03*
Y1261649D03*
X337965Y1256631D03*
Y1259131D03*
X348865D03*
Y1256631D03*
X337961Y1271688D03*
X348861D03*
X348151Y1326641D03*
X350581D03*
X345721D03*
X342705Y1335899D03*
X339217Y1334299D03*
X341955Y1333331D03*
X346464Y1380102D03*
X343964D03*
X348964D03*
Y1387602D03*
Y1385102D03*
Y1382602D03*
X343964Y1385102D03*
Y1387602D03*
X346464Y1385102D03*
Y1387602D03*
X343964Y1382602D03*
X346464D03*
X348964Y1390102D03*
X343964D03*
Y1392602D03*
X346464D03*
Y1390102D03*
X343777Y1395166D03*
X346302Y1395242D03*
X348828Y1395392D03*
X349032Y1392675D03*
X361744Y120713D03*
X363621Y127665D03*
X361171Y223114D03*
X358618Y223129D03*
X361171Y220614D03*
X358671D03*
X355910Y223847D03*
X365739Y221871D03*
X365559Y238896D03*
X357925Y304082D03*
X351390Y409120D03*
X353890D03*
Y411620D03*
X351390D03*
X365852Y516466D03*
X365071Y551038D03*
X355100Y544390D03*
X362200Y566750D03*
X364047Y556773D03*
X359200Y566990D03*
X360261Y561044D03*
X359657Y570702D03*
X359157Y574415D03*
X365158Y597546D03*
Y593580D03*
X352031Y607498D03*
Y610498D03*
X355031Y607498D03*
Y613498D03*
Y610498D03*
X352031Y604498D03*
X355031D03*
X361031Y607498D03*
Y613498D03*
Y610498D03*
X358031Y607498D03*
Y613498D03*
Y610498D03*
Y604498D03*
Y619398D03*
Y616498D03*
X355031Y619398D03*
Y616498D03*
X361031Y619398D03*
Y616498D03*
X352675Y640994D03*
Y643494D03*
X355275Y641034D03*
Y643534D03*
X355195Y646094D03*
X352595Y646054D03*
X357311Y702110D03*
X364753Y701647D03*
Y704155D03*
X360799Y703710D03*
X358061Y704678D03*
X351865Y711368D03*
X354295D03*
X364451Y769040D03*
Y771540D03*
Y774040D03*
X361951D03*
Y771540D03*
Y769040D03*
X364451Y776540D03*
X361951D03*
X364447Y766540D03*
X361947D03*
X364451Y791558D03*
X361951D03*
X364451Y786558D03*
Y789058D03*
X361951D03*
Y786558D03*
X364451Y784058D03*
X361951Y781558D03*
X364451Y779058D03*
Y781558D03*
X361951Y779058D03*
Y784058D03*
X361671Y803588D03*
X356671D03*
X351671D03*
X363313Y812088D03*
X359813Y812188D03*
X356313D03*
X352813D03*
X356535Y849708D03*
X364897Y852564D03*
X364821Y861852D03*
X357400Y855982D03*
X356895Y859791D03*
X353281Y859620D03*
X363236Y1199632D03*
X361922Y1206891D03*
X357271Y1208988D03*
X351413Y1210052D03*
X365461Y1254188D03*
Y1251688D03*
Y1249188D03*
Y1246688D03*
X351365Y1246631D03*
X353865D03*
Y1251631D03*
X351365D03*
X353865Y1249131D03*
X351365D03*
X353865Y1254131D03*
X351365D03*
Y1269149D03*
Y1266649D03*
Y1264149D03*
Y1261649D03*
X365461Y1256688D03*
Y1259188D03*
X353865Y1266631D03*
Y1264131D03*
Y1261631D03*
Y1269131D03*
X351365Y1259131D03*
Y1256631D03*
X353865Y1259131D03*
Y1256631D03*
X365561Y1269288D03*
Y1264288D03*
Y1266788D03*
Y1261788D03*
Y1271788D03*
X351361Y1271688D03*
X353861D03*
X361301Y1322987D03*
Y1325528D03*
X351651Y1320942D03*
Y1323842D03*
X357611Y1326946D03*
X355411Y1328346D03*
X362794Y1333902D03*
X365074Y1330377D03*
X353345Y1332976D03*
X357611Y1329846D03*
X353345Y1330076D03*
X355511Y1331346D03*
X357611Y1332746D03*
X356764Y1359296D03*
X354264D03*
X364764D03*
X362264D03*
X359764D03*
X351632Y1359203D03*
X351923Y1364724D03*
X354423D03*
X356923D03*
X359423D03*
X362223D03*
X364723D03*
X351772Y1362085D03*
X354272D03*
X356772D03*
X359272D03*
X362072D03*
X364572D03*
X363964Y1385102D03*
X356464Y1380102D03*
X358964D03*
X361464D03*
X353964D03*
X351464D03*
X363964D03*
Y1382602D03*
X351464Y1385102D03*
X353964D03*
X361464D03*
X356464D03*
X358964D03*
X351464Y1382602D03*
X361464D03*
X358964D03*
X356464D03*
X353964D03*
X352067Y1387665D03*
X354567D03*
X357067D03*
X359567D03*
X363190Y1387527D03*
X365979Y1387641D03*
X352332Y1391886D03*
X354832D03*
X357332D03*
X359832D03*
X363191Y1390292D03*
Y1392792D03*
X365980Y1392906D03*
Y1390406D03*
X363003Y1395393D03*
X365792Y1395507D03*
X352313Y1395223D03*
X359859D03*
X357208D03*
X365493Y1655107D03*
X370888Y155250D03*
X377118Y222229D03*
X380012Y239615D03*
X370327Y228951D03*
X370352Y235455D03*
X366671Y297114D03*
X369171D03*
X369671Y292114D03*
Y294614D03*
X380935Y443386D03*
X375935D03*
X378435D03*
X382184Y466351D03*
X378976Y479226D03*
X379633Y493942D03*
X371962Y524954D03*
X368371Y553038D03*
X371971Y553138D03*
X375410Y552254D03*
X377502Y554193D03*
X380157Y553090D03*
X375271Y542191D03*
X379114Y544866D03*
X368647Y550422D03*
X370271Y555038D03*
X379689Y586040D03*
X368798Y587938D03*
X369271Y600138D03*
X373477Y593338D03*
X378577Y593026D03*
X377577Y590126D03*
X370022Y704307D03*
X371515Y715222D03*
Y712681D03*
X367742Y707832D03*
X379711Y708001D03*
Y705101D03*
X375445Y708231D03*
X377545Y706731D03*
X375445Y705331D03*
X377645Y709731D03*
X375445Y711131D03*
X366951Y769058D03*
Y771558D03*
Y774058D03*
Y776558D03*
X379187Y766428D03*
Y768960D03*
Y771460D03*
Y773960D03*
Y776460D03*
X366947Y766540D03*
X366951Y781558D03*
Y786558D03*
Y789058D03*
Y784058D03*
X379187Y786460D03*
Y783960D03*
Y788960D03*
Y778960D03*
Y781460D03*
X366951Y791558D03*
X379187Y791460D03*
X366951Y779058D03*
X376671Y803588D03*
X371671D03*
X366671D03*
X366864Y857274D03*
X369626Y860717D03*
X370316Y1204673D03*
X367931Y1196981D03*
X376271Y1207488D03*
X380718Y1221906D03*
X379223Y1219527D03*
X372126Y1214455D03*
X368726D03*
X367961Y1254188D03*
Y1251688D03*
Y1249188D03*
Y1246688D03*
X370461Y1254188D03*
Y1249188D03*
Y1251688D03*
Y1246688D03*
X367961Y1256688D03*
Y1259188D03*
X370461D03*
Y1256688D03*
X368061Y1269206D03*
X370561D03*
X368061Y1261706D03*
Y1264206D03*
Y1266706D03*
X370561D03*
Y1264206D03*
Y1261706D03*
Y1271788D03*
X368061D03*
X380951Y1326841D03*
X378521D03*
X368063Y1334054D03*
X375505Y1336099D03*
X372017Y1334499D03*
X374755Y1333531D03*
X368063Y1336562D03*
X368964Y1382602D03*
Y1385102D03*
X366464D03*
X368964Y1380102D03*
X366464D03*
Y1382602D03*
X368542Y1387639D03*
X368543Y1390404D03*
Y1392904D03*
X368355Y1395505D03*
X374432Y1582600D03*
X375050Y1639400D03*
X371823Y1644516D03*
X370533Y1658605D03*
X374962Y1648511D03*
X372953Y1653197D03*
X373330Y1668539D03*
X370369Y1661817D03*
X372449Y1680520D03*
X372395Y1677449D03*
X390841Y-15571D03*
Y-12171D03*
X395048Y121178D03*
X384375Y147365D03*
X386350Y138980D03*
X395590Y147010D03*
X391310Y227871D03*
X389912Y280345D03*
X390881Y284156D03*
X395053Y318125D03*
X383525Y443386D03*
X389784Y476070D03*
X384827Y507057D03*
X397184Y507101D03*
X382184D03*
X388985Y554870D03*
X383071Y553738D03*
X382705Y546433D03*
X395171Y559463D03*
X395669Y563328D03*
X385318Y555238D03*
X394168Y568482D03*
X395157Y573815D03*
X393481Y571239D03*
X387103Y584506D03*
X392471Y596988D03*
X391021Y588788D03*
X390351Y702178D03*
X393839Y703778D03*
X391101Y704746D03*
X382475Y711436D03*
X387335D03*
X384905D03*
X381812Y717060D03*
Y714160D03*
X394987Y766428D03*
X381687D03*
X384187D03*
X394991Y773928D03*
Y771428D03*
Y768928D03*
Y776428D03*
X384191Y768928D03*
Y771428D03*
Y773928D03*
X381691D03*
Y771428D03*
Y768928D03*
X384191Y776428D03*
X381691D03*
X381687Y791460D03*
X384187D03*
X394987Y784060D03*
Y779060D03*
Y781560D03*
Y789060D03*
Y786560D03*
X381687Y778960D03*
Y786460D03*
Y783960D03*
Y788960D03*
Y781460D03*
X384187Y788960D03*
Y786460D03*
Y783960D03*
Y778960D03*
Y781460D03*
X386381Y1015474D03*
X393861D03*
X386381Y1022560D03*
Y1019017D03*
X393861Y1022560D03*
Y1019017D03*
X390974Y1222849D03*
Y1219449D03*
X388630Y1236747D03*
X381361Y1254188D03*
Y1249188D03*
Y1251688D03*
Y1246688D03*
X383861Y1254188D03*
X386361D03*
X383861Y1249188D03*
X386361D03*
X383861Y1251688D03*
X386361D03*
X383861Y1246688D03*
X386361D03*
X388630Y1240147D03*
X381361Y1269206D03*
X383861D03*
X381361Y1261706D03*
Y1264206D03*
Y1266706D03*
X383861D03*
Y1264206D03*
Y1261706D03*
X381361Y1256688D03*
Y1259188D03*
X386361Y1256688D03*
Y1259188D03*
X383861Y1256688D03*
Y1259188D03*
X386361Y1269288D03*
Y1261788D03*
Y1266788D03*
Y1264288D03*
X381361Y1271788D03*
X386361D03*
X383861D03*
X383381Y1326841D03*
X384481Y1321192D03*
Y1324092D03*
X388211Y1328546D03*
X393883Y1342318D03*
X388311Y1331546D03*
X386145Y1333176D03*
Y1330276D03*
X386611Y1336056D03*
X388771Y1337546D03*
Y1334546D03*
X395376Y1353233D03*
X393883Y1344859D03*
X395384Y1519250D03*
X395359Y1546519D03*
X389290Y1561250D03*
X387939Y1565534D03*
X389276Y1568413D03*
X391526Y1582373D03*
X394521Y1575891D03*
X388784Y1581801D03*
X393005Y1592304D03*
X381711Y1593842D03*
X381607Y1590393D03*
X388445Y1585898D03*
X389333Y1598816D03*
X387805Y1617302D03*
Y1614802D03*
X394824Y1629713D03*
X394000Y1621500D03*
X389824Y1629713D03*
X389000Y1621500D03*
X384824Y1629713D03*
X381350Y1649000D03*
Y1642900D03*
Y1645800D03*
X382115Y1661545D03*
X387324Y1680495D03*
X392324D03*
X382642Y1680979D03*
X385068Y1683502D03*
X410500Y104883D03*
X410400Y107383D03*
X399264Y121144D03*
X403141Y148300D03*
X410678Y159140D03*
X408603Y152278D03*
X411299Y212096D03*
X400000Y220300D03*
X411940Y240501D03*
X410000Y304000D03*
X402184Y466469D03*
X410984Y496649D03*
X406184Y507900D03*
X403657Y546915D03*
X408550Y557850D03*
X404871Y567338D03*
X403381Y573516D03*
X410111Y572608D03*
X407543Y577415D03*
Y580490D03*
X408445Y687531D03*
X397793Y701715D03*
X410645Y691931D03*
X410545Y688931D03*
X408445Y690431D03*
Y693331D03*
X403062Y704375D03*
X397793Y704223D03*
X404555Y715290D03*
Y712749D03*
X400782Y707900D03*
X399991Y776560D03*
X397491Y768928D03*
Y771428D03*
Y773928D03*
Y776428D03*
X397487Y766428D03*
X399991Y771560D03*
Y769060D03*
X399987Y766428D03*
X399991Y774060D03*
X397487Y779060D03*
Y781560D03*
Y786560D03*
Y784060D03*
X399991D03*
Y779060D03*
Y781560D03*
X401341Y1015474D03*
Y1019017D03*
Y1022560D03*
X403347Y1266162D03*
Y1268662D03*
X400847Y1266162D03*
X398347D03*
X400847Y1268662D03*
X398347D03*
X403347Y1271162D03*
Y1273662D03*
X400847Y1271162D03*
X398347D03*
X400847Y1273662D03*
X398347D03*
X403347Y1276162D03*
Y1278662D03*
X400847D03*
Y1276162D03*
X398347Y1278662D03*
Y1276162D03*
X398447Y1281262D03*
Y1283762D03*
X400947Y1281180D03*
Y1283680D03*
X403447D03*
Y1281180D03*
X400947Y1288680D03*
X403447D03*
X400947Y1286180D03*
X403447D03*
X398447Y1286262D03*
Y1288762D03*
X398461Y1291319D03*
X403461D03*
X400961D03*
X400645Y1353385D03*
X408087Y1355430D03*
X404599Y1353830D03*
X407337Y1352862D03*
X400645Y1355893D03*
X397656Y1349708D03*
X401536Y1516120D03*
Y1512220D03*
X397206Y1516953D03*
Y1511953D03*
Y1514453D03*
X397891Y1521436D03*
X401659Y1519845D03*
X404686Y1516120D03*
Y1512220D03*
X410650Y1509469D03*
X408150D03*
X407836Y1512220D03*
Y1516120D03*
X407561Y1519845D03*
X404699Y1521436D03*
X410108Y1535680D03*
X408895Y1553644D03*
X405331Y1548928D03*
X410851Y1557434D03*
X407198Y1564990D03*
X401249Y1564422D03*
X405758Y1557900D03*
X402912Y1558011D03*
X396452Y1577738D03*
X403163Y1579357D03*
X403004Y1582457D03*
X408925Y1573805D03*
Y1576805D03*
X404669Y1594317D03*
X403837Y1609056D03*
Y1612456D03*
X399447Y1612609D03*
X399801Y1606376D03*
X406697Y1604207D03*
X408856Y1623435D03*
X400380Y1621500D03*
X405436Y1620268D03*
X406343Y1613847D03*
X405747Y1623350D03*
X404640Y1637425D03*
X397822Y1629615D03*
X409552Y1633606D03*
X405342Y1628611D03*
X404661Y1634139D03*
X412000Y1647177D03*
X403844Y1665769D03*
X405000Y1675000D03*
X397324Y1680495D03*
X409000Y1683500D03*
X424975Y54762D03*
X417025D03*
X416549Y66365D03*
Y71665D03*
X427300Y71300D03*
X419900Y96620D03*
X414100D03*
X424084Y110839D03*
X424086Y123023D03*
X422890Y136700D03*
X424086Y133265D03*
X412370Y188210D03*
X411610Y223140D03*
X424815Y217646D03*
X422936Y223501D03*
X419299Y212096D03*
X423299D03*
X420115Y230323D03*
Y240501D03*
Y235442D03*
Y226323D03*
X411940Y235442D03*
X412715Y251165D03*
Y258165D03*
Y266165D03*
X419617Y308000D03*
X424151Y453174D03*
X415984Y466392D03*
X424784Y496572D03*
X419984Y508000D03*
X411500Y510800D03*
X412771Y524820D03*
X414402Y544690D03*
X423351Y684378D03*
X424101Y686946D03*
X412711Y687301D03*
X420335Y693636D03*
X415475D03*
X417905D03*
X412711Y690201D03*
X414712Y699440D03*
Y696540D03*
X420158Y748643D03*
X415158Y756175D03*
Y751175D03*
Y753675D03*
X417658Y748643D03*
X415158D03*
Y761175D03*
X420158D03*
X417658D03*
X415158Y758675D03*
X420162Y751143D03*
Y753643D03*
Y756143D03*
X417662D03*
Y753643D03*
Y751143D03*
X420162Y758643D03*
X417662D03*
X415158Y771175D03*
X420158Y763675D03*
Y766175D03*
X417658Y768675D03*
X415158D03*
X417658Y763675D03*
Y766175D03*
X415158Y763675D03*
Y766175D03*
X415318Y1009765D03*
Y1006025D03*
X424873Y1014745D03*
X423811Y1005800D03*
X415318Y1013505D03*
X424873Y1023013D03*
Y1018879D03*
X415318Y1028466D03*
Y1020986D03*
Y1024726D03*
Y1017245D03*
X418918Y1032206D03*
X423811Y1032431D03*
X424024Y1267144D03*
X414247Y1268662D03*
X416747D03*
X419247D03*
X424024Y1269644D03*
Y1272144D03*
X414247Y1281180D03*
Y1283680D03*
X416747D03*
Y1281180D03*
Y1271162D03*
X414247D03*
X416747Y1278662D03*
Y1276162D03*
X419247Y1278662D03*
Y1276162D03*
Y1273662D03*
X416747D03*
X414247Y1278662D03*
Y1276162D03*
Y1273662D03*
X419361Y1283719D03*
Y1281219D03*
X419247Y1271162D03*
X424024Y1274644D03*
X414247Y1288680D03*
X416747D03*
X414247Y1286180D03*
X416747D03*
X419361Y1288719D03*
Y1291219D03*
X414361D03*
X416861D03*
X419361Y1286219D03*
X417063Y1340523D03*
Y1343423D03*
X415963Y1346172D03*
X413533D03*
X411103D03*
X421315Y1354276D03*
Y1351376D03*
X421205Y1348586D03*
Y1345686D03*
X418675Y1352166D03*
Y1349266D03*
X425631Y1517138D03*
X425087Y1510708D03*
X422587D03*
X423131Y1517138D03*
X412086Y1512076D03*
Y1514576D03*
X422557Y1537595D03*
X420057D03*
X417098Y1536411D03*
X418157Y1549295D03*
X423157Y1541795D03*
Y1544295D03*
X415657Y1541795D03*
X418157Y1546795D03*
Y1544295D03*
Y1541795D03*
X415657Y1549295D03*
Y1546795D03*
Y1544295D03*
X420657Y1541795D03*
Y1544295D03*
Y1546795D03*
Y1549295D03*
X417098Y1538911D03*
X424115Y1548199D03*
Y1551099D03*
X421697Y1551844D03*
X421683Y1565312D03*
X421108Y1560235D03*
X424488Y1565400D03*
X413540Y1556646D03*
X424616Y1560086D03*
X414202Y1559396D03*
X421294Y1557729D03*
X419254Y1566828D03*
X427081Y1581620D03*
X421277Y1571923D03*
X413396Y1594597D03*
X410991Y1597002D03*
X425469Y1595433D03*
X422069D03*
X419277Y1600725D03*
X414500Y1639075D03*
X417365Y1627695D03*
X420765D03*
X423500Y1652500D03*
X411448Y1650598D03*
X420000Y1664925D03*
X411500Y1657500D03*
X417000Y1675000D03*
X413000Y1683500D03*
X415500Y1672500D03*
X433673Y73960D03*
X428149Y65016D03*
X431359Y82589D03*
X433997Y166400D03*
X437997D03*
X436103Y158594D03*
X437997Y170701D03*
X433997D03*
X438200Y212096D03*
X431299Y212095D03*
X437440Y237270D03*
X442710Y237990D03*
X435710Y250340D03*
X440710D03*
X426947Y320749D03*
X433277Y471970D03*
X429784Y466315D03*
X426208Y468977D03*
X436226Y475526D03*
X437084Y501865D03*
X429784Y506947D03*
X442084Y511870D03*
X427500Y510553D03*
X426011Y524888D03*
X436062Y686575D03*
X430793Y686423D03*
X426839Y685978D03*
X430793Y683915D03*
X437555Y697490D03*
Y694949D03*
X433782Y690100D03*
X430958Y748643D03*
X433458D03*
X433462Y751143D03*
Y753643D03*
Y756143D03*
X430962D03*
Y753643D03*
Y751143D03*
Y758643D03*
X440159Y970341D03*
Y977841D03*
Y985341D03*
X438359Y993766D03*
X438434Y989766D03*
X438359Y997766D03*
X427551Y1005800D03*
X434716Y1014745D03*
X431291Y1005800D03*
X435031D03*
X438771D03*
X438359Y1001766D03*
X434716Y1018879D03*
Y1023013D03*
X431291Y1032431D03*
X435031D03*
X438771D03*
X427551D03*
X427615Y1282917D03*
Y1275417D03*
Y1280417D03*
Y1277917D03*
X436903Y1285694D03*
Y1289694D03*
X426704Y1523331D03*
Y1526731D03*
X439935Y1532600D03*
X430027Y1546795D03*
Y1544295D03*
X432527Y1541795D03*
Y1549295D03*
Y1546795D03*
Y1544295D03*
X430027Y1541795D03*
Y1549295D03*
X435027D03*
Y1546795D03*
Y1544295D03*
Y1541795D03*
X427527Y1549295D03*
Y1546795D03*
Y1544295D03*
Y1541795D03*
X426620Y1551844D03*
X437736Y1544392D03*
X431923Y1565790D03*
X432051Y1560635D03*
X437910Y1553910D03*
X433440Y1581700D03*
X429947Y1594398D03*
X436776Y1610394D03*
X430500Y1605835D03*
X431664Y1624342D03*
X436776Y1613794D03*
X433012Y1621612D03*
X430500Y1613709D03*
X434500Y1641500D03*
X431000Y1640500D03*
X432000Y1650000D03*
X436925Y1649500D03*
X441182Y77125D03*
X445267Y82124D03*
X452948Y104003D03*
X445997Y166400D03*
X453997D03*
X449997D03*
X448038Y158659D03*
X441997Y170701D03*
X449997D03*
X448499Y212036D03*
X443299Y212095D03*
X456231Y227764D03*
X443299Y220046D03*
X447299D03*
X456231Y232883D03*
X455422Y244103D03*
X444310Y243370D03*
X446710Y249340D03*
X454518Y280793D03*
X447840Y275970D03*
X441320Y295170D03*
Y301170D03*
Y307170D03*
Y313170D03*
Y316170D03*
X442297Y474442D03*
X453269Y478388D03*
X449496Y474009D03*
X446547Y480123D03*
X443683Y502256D03*
X448024Y505345D03*
X452084Y511870D03*
X447084D03*
X457084D03*
X453723Y526558D03*
X444441Y565549D03*
X450305Y669036D03*
X452735D03*
X447875D03*
X440845Y668731D03*
Y665831D03*
X445111Y662701D03*
X442945Y664331D03*
X440845Y662931D03*
X443045Y667331D03*
X445111Y665601D03*
X447212Y671640D03*
Y674540D03*
X446686Y726660D03*
Y729160D03*
Y731660D03*
X449190Y726528D03*
Y729028D03*
Y731528D03*
X451690D03*
Y729028D03*
Y726528D03*
X446686Y724028D03*
X449186D03*
X451686D03*
Y741660D03*
X449186D03*
Y739160D03*
Y736660D03*
X451686Y739160D03*
Y736660D03*
X446686Y741660D03*
Y736660D03*
Y739160D03*
Y734160D03*
X449190Y734028D03*
X451690D03*
X453810Y1014745D03*
X449992Y1005800D03*
X453732D03*
X443574Y1014745D03*
X446252Y1005800D03*
X442511D03*
X453810Y1023013D03*
X443574D03*
X453810Y1018879D03*
X443574D03*
X453732Y1032431D03*
X442884Y1038766D03*
X442511Y1032431D03*
X442884Y1042766D03*
X446252Y1032431D03*
X449992D03*
X441159Y1051541D03*
X443764Y1179395D03*
X446810Y1565020D03*
X446910Y1562098D03*
X446653Y1573264D03*
X441931Y1581662D03*
X443590Y1593880D03*
X441460Y1596020D03*
X450500Y1612450D03*
X446182Y1625555D03*
X450180Y1614950D03*
X445800Y1633200D03*
Y1636000D03*
X446000Y1650000D03*
X462653Y72525D03*
X470010Y141070D03*
X461997Y166400D03*
X471371Y227764D03*
X461931Y212703D03*
X468574Y213104D03*
X471371Y222764D03*
X464440Y218253D03*
X460567Y225205D03*
Y235442D03*
X460624Y240953D03*
Y230323D03*
X463240Y244980D03*
X456720Y285158D03*
X457248Y280143D03*
Y282643D03*
X470243Y285693D03*
X467545Y356864D03*
X460441Y499842D03*
X457424Y497978D03*
X468638Y514096D03*
X465766Y524991D03*
X458725Y524480D03*
X470331Y566632D03*
X465331D03*
X467831D03*
X462831D03*
X467831Y569132D03*
X470331D03*
X459931Y566632D03*
X457431D03*
X462831Y569132D03*
X457431D03*
X459931D03*
X465331D03*
X470331Y576132D03*
X467831Y571632D03*
X465331D03*
X467831Y576132D03*
X465331D03*
X470331Y571632D03*
X462831D03*
Y576132D03*
X457431Y571632D03*
Y574132D03*
X459931Y571632D03*
Y574132D03*
X457431Y576632D03*
X459931D03*
X462831Y598514D03*
X467831D03*
X470331D03*
X465331D03*
X457711D03*
X460211D03*
X462831Y601014D03*
X467831D03*
X470331D03*
X465331D03*
X457711D03*
X460211D03*
X469955Y672890D03*
X463193Y659315D03*
X468462Y661975D03*
X463193Y661823D03*
X455751Y659778D03*
X459239Y661378D03*
X469955Y670349D03*
X456501Y662346D03*
X466182Y665500D03*
X462490Y731528D03*
Y726528D03*
Y729028D03*
X464990D03*
Y726528D03*
X467486Y724028D03*
X464986D03*
X462486D03*
X467490Y726660D03*
X457472Y1005800D03*
X465965Y1009765D03*
Y1006025D03*
Y1013505D03*
Y1020986D03*
Y1024726D03*
Y1028466D03*
Y1017245D03*
Y1032206D03*
X457472Y1032431D03*
X462215Y1581510D03*
X462753Y1641289D03*
X459500Y1659000D03*
X467500Y1651500D03*
X457000Y1650000D03*
X468075Y1662500D03*
X470463Y1670038D03*
X464925Y1662500D03*
X467500Y1678500D03*
X468575Y1704000D03*
X462500Y1697000D03*
X466000Y1714575D03*
X468575Y1731000D03*
X479400Y90574D03*
Y94574D03*
Y97574D03*
Y110930D03*
X479465Y119644D03*
Y115644D03*
Y123644D03*
X482380Y141942D03*
X483800Y189400D03*
X480200Y191900D03*
X480700Y208200D03*
X480715Y211099D03*
X471371Y235764D03*
X483227Y233000D03*
X487620Y270400D03*
X479870D03*
X483823Y285893D03*
X474808Y291492D03*
X482893Y291293D03*
X479148Y315502D03*
X484063Y305669D03*
X480773Y307153D03*
X471015Y527283D03*
X475731Y566632D03*
X473231D03*
Y569132D03*
X475731D03*
Y574132D03*
Y571632D03*
X473231Y574132D03*
Y571632D03*
X475731Y576632D03*
X473231D03*
X485335Y642536D03*
X480475D03*
X482905D03*
X473445Y642231D03*
X477711Y639101D03*
X475645Y640831D03*
X473445Y639331D03*
X475545Y637831D03*
X473445Y636431D03*
X477711Y636201D03*
X479812Y645240D03*
Y648140D03*
X479058Y702660D03*
Y700160D03*
X484062Y700028D03*
Y702528D03*
X481562D03*
Y700028D03*
X479058Y697528D03*
X481558D03*
X484058D03*
X479058Y717660D03*
Y707660D03*
Y712660D03*
Y710160D03*
Y715160D03*
X484058Y710160D03*
Y712660D03*
X481558Y710160D03*
Y712660D03*
X484058Y715160D03*
X481558D03*
X484062Y707528D03*
X481562D03*
X479058Y705160D03*
X484062Y705028D03*
X481562D03*
X480803Y1015474D03*
Y1022560D03*
Y1019017D03*
X483500Y1658500D03*
X479500Y1666500D03*
X473500Y1662500D03*
X477538Y1661463D03*
X474000Y1704000D03*
X478500Y1697000D03*
Y1710500D03*
Y1733500D03*
X491849Y55095D03*
Y60105D03*
X497885Y51315D03*
X491849Y64965D03*
X500674Y116261D03*
X485780Y141942D03*
X500136Y141058D03*
X495500Y161386D03*
X497700Y157200D03*
X492685Y160994D03*
X486682Y193516D03*
X495232D03*
Y185516D03*
X486682Y189516D03*
X496831Y205030D03*
X499380Y222510D03*
X491635Y225970D03*
X494144Y221370D03*
X487442Y223377D03*
X500209Y227881D03*
X491635Y215652D03*
X500209Y233000D03*
X491859D03*
X500119Y243173D03*
X500209Y238119D03*
X491577Y238120D03*
Y243240D03*
X485962Y290679D03*
X487827Y354017D03*
X490419Y362138D03*
X498500Y419425D03*
X495793Y632815D03*
X495839Y635323D03*
X488351Y633278D03*
X491839Y634878D03*
X489101Y635846D03*
X498782Y639000D03*
X497362Y700028D03*
Y702528D03*
X494862D03*
Y700028D03*
X499858Y697528D03*
X497358D03*
X494858D03*
X499862Y700160D03*
Y702660D03*
X494862Y705028D03*
X497362D03*
X499862Y705160D03*
X488384Y1015474D03*
X495884D03*
X488384Y1022560D03*
Y1019017D03*
X495884Y1022560D03*
Y1019017D03*
X512658Y46613D03*
X504796Y86320D03*
X516020Y105370D03*
Y109270D03*
X513772Y121220D03*
X502750Y111276D03*
X503000Y135600D03*
X509346Y125842D03*
X507945Y160919D03*
X503161Y154620D03*
X500600Y157100D03*
X505315Y196944D03*
X503507Y185516D03*
X504351Y202776D03*
X508238Y199506D03*
X512076Y206404D03*
X511684Y221219D03*
X504351Y215901D03*
X508001Y220166D03*
X515223Y289035D03*
Y313200D03*
Y305145D03*
X513775Y608436D03*
X506745Y608131D03*
X508945Y606731D03*
X506745Y602331D03*
Y605231D03*
X508845Y603731D03*
X511011Y602101D03*
Y605001D03*
X513012Y611040D03*
Y613940D03*
X501062Y635475D03*
X502555Y646390D03*
Y643849D03*
X514162Y673428D03*
Y665928D03*
Y668428D03*
Y670928D03*
X514158Y663428D03*
Y678460D03*
Y683460D03*
Y680960D03*
Y675960D03*
X509572Y865327D03*
X513572D03*
X524713Y33346D03*
X529713D03*
X516058Y46613D03*
X519765Y40328D03*
X523165D03*
X519743Y71436D03*
X523143D03*
X524993Y125914D03*
X521618Y165428D03*
X519268Y167428D03*
X519601Y196117D03*
X518691Y191846D03*
X517314Y200449D03*
X519248Y280721D03*
X516723D03*
X521773D03*
X520273Y289035D03*
X517748D03*
X522798D03*
X520273Y313200D03*
X517748D03*
X520273Y305145D03*
X517748D03*
X515523Y335613D03*
X529317Y403784D03*
X524680Y417602D03*
X529095Y452049D03*
X529153Y598735D03*
X529235Y601543D03*
X521651Y599178D03*
X525139Y600778D03*
X522401Y601746D03*
X516205Y608436D03*
X518635D03*
X529962Y673428D03*
Y670928D03*
Y668428D03*
Y665928D03*
X516662Y673428D03*
Y670928D03*
Y668428D03*
Y665928D03*
X527462Y673428D03*
Y665928D03*
Y668428D03*
Y670928D03*
X516658Y663428D03*
X527458D03*
X529958D03*
X516658Y678460D03*
Y683460D03*
Y680960D03*
X527458Y678460D03*
X516658Y675960D03*
X527458D03*
X529958D03*
Y678460D03*
X526474Y851934D03*
Y849434D03*
X517009Y856494D03*
X523074Y853439D03*
Y855939D03*
X528220Y1167366D03*
X517118D03*
X520818D03*
X539120Y31340D03*
X535117D03*
X544721Y42892D03*
X539721Y42862D03*
X541003Y71436D03*
X544403D03*
X538210Y90618D03*
X540615Y88213D03*
X535170Y111230D03*
Y115130D03*
X530567Y125914D03*
X543408Y133912D03*
X538166Y130698D03*
X541675Y146874D03*
Y151470D03*
Y142021D03*
Y137169D03*
Y156195D03*
X533442Y164428D03*
X532222Y207849D03*
X540695Y217874D03*
X534277Y224930D03*
X538613Y227882D03*
X537051Y211959D03*
X538613Y238119D03*
X534277Y230441D03*
Y235560D03*
X538613Y233000D03*
X539217Y245270D03*
X543780Y294168D03*
X541808Y289743D03*
X544628Y291633D03*
Y289133D03*
X542983Y334531D03*
X533211Y350838D03*
X533543Y404130D03*
X530729Y398634D03*
X543170Y434737D03*
X534455Y428561D03*
X531753Y453232D03*
X540616Y463486D03*
X538067Y592652D03*
X542071Y593089D03*
X535855Y612290D03*
X539657Y607658D03*
X534362Y601375D03*
X535855Y609749D03*
X532082Y604900D03*
X534962Y670960D03*
Y665960D03*
Y668460D03*
X532462D03*
Y665960D03*
Y670960D03*
Y673460D03*
Y663460D03*
X534962D03*
Y673460D03*
Y675960D03*
X532462D03*
X531921Y1167366D03*
X543947Y1516120D03*
Y1512220D03*
X543672Y1519845D03*
X540810Y1521436D03*
X533317Y1511953D03*
Y1514453D03*
Y1516953D03*
X531495Y1519250D03*
X537770Y1519845D03*
X537647Y1516120D03*
Y1512220D03*
X534002Y1521436D03*
X540797Y1516120D03*
Y1512220D03*
X543719Y1549295D03*
Y1546795D03*
X541219D03*
Y1549295D03*
X538719D03*
Y1546795D03*
X531339Y1546481D03*
X553620Y31048D03*
X549919D03*
X554984Y45312D03*
X553651Y48842D03*
X546350Y39562D03*
X550972Y42902D03*
X561721Y41024D03*
X556351Y41538D03*
X548610Y48082D03*
X547821Y79372D03*
X551721D03*
X555176Y71436D03*
X558576D03*
X553780Y121240D03*
Y124640D03*
X559484Y156667D03*
X553757Y160075D03*
X547196Y190256D03*
X550196D03*
X554196D03*
X553578Y193541D03*
X547196Y199256D03*
X550553Y200304D03*
Y197778D03*
X548963Y218441D03*
X549248Y237652D03*
Y230441D03*
X555567Y236970D03*
X549248Y234152D03*
X559774Y243176D03*
X557243Y294693D03*
X561808Y300492D03*
X562030Y372872D03*
X551044Y373085D03*
X562208Y383668D03*
Y404717D03*
X550573Y399586D03*
Y403586D03*
X562208Y397599D03*
X550573Y414274D03*
X549854Y406298D03*
X547529Y425411D03*
X551591Y443665D03*
X552510Y446490D03*
X547751Y472678D03*
X550925Y475178D03*
X553360Y477822D03*
X555727Y479968D03*
X558379Y482096D03*
X549957Y658478D03*
Y661478D03*
X558690Y1226149D03*
X558876Y1454905D03*
Y1458305D03*
X546253Y1454107D03*
Y1457507D03*
X548197Y1514641D03*
X550471Y1513584D03*
Y1511031D03*
X548197Y1512088D03*
X554766Y1523331D03*
Y1526731D03*
X550939Y1536646D03*
X559215Y1530596D03*
X546219Y1549295D03*
Y1541795D03*
Y1546795D03*
Y1544295D03*
X548719Y1549295D03*
Y1546795D03*
Y1541795D03*
Y1544295D03*
X551219D03*
Y1541795D03*
X549674Y1538890D03*
X558089Y1541795D03*
Y1544295D03*
Y1546795D03*
Y1549295D03*
X555589Y1541795D03*
Y1549295D03*
Y1546795D03*
Y1544295D03*
X549759Y1551844D03*
X552177Y1551099D03*
X554682Y1551844D03*
X552177Y1548199D03*
X565185Y47982D03*
X575331Y47672D03*
X573191Y42912D03*
X570209Y47982D03*
X566771Y41133D03*
X564794Y58911D03*
X567997Y58992D03*
X573763Y58688D03*
X562331Y48438D03*
X570860Y121310D03*
Y124710D03*
X563951Y153640D03*
Y148640D03*
Y157494D03*
X572003Y164356D03*
Y169415D03*
X568804Y221926D03*
X571427Y217771D03*
X569004Y225496D03*
X568736Y235821D03*
X565093Y242640D03*
X570823Y294893D03*
X572447Y299470D03*
X569893Y300293D03*
X571063Y314669D03*
X566148Y324502D03*
X567773Y316153D03*
X575913Y413287D03*
X570863Y410728D03*
X572121Y437038D03*
X564407Y431638D03*
X568709Y434227D03*
X563763Y486350D03*
X567297Y487551D03*
X560890Y484664D03*
X569923Y490726D03*
X561346Y1228547D03*
X564669Y1238907D03*
X564283Y1231192D03*
X565537Y1235456D03*
X574200Y1229900D03*
X567127Y1249536D03*
X570775Y1263008D03*
X560589Y1541795D03*
Y1544295D03*
Y1546795D03*
Y1549295D03*
X563089Y1541795D03*
Y1549295D03*
Y1546795D03*
Y1544295D03*
X567214Y1544299D03*
X591938Y46308D03*
X576478Y58563D03*
X591070Y60201D03*
X586953Y63441D03*
X583685Y70678D03*
X586390Y69291D03*
X579561Y73090D03*
X585000Y82500D03*
X584752Y86248D03*
X590501Y86909D03*
X578454Y88926D03*
X586394Y95948D03*
X591811Y97421D03*
X580485Y133056D03*
Y130530D03*
X583485D03*
Y133056D03*
X589203Y164356D03*
X581203D03*
X589203Y169415D03*
X585685Y174975D03*
X581203Y169415D03*
X575425Y189835D03*
X582124Y194150D03*
X588244Y208991D03*
X575440Y200785D03*
X582002Y197481D03*
X582766Y225496D03*
Y221421D03*
X588554Y217277D03*
Y225277D03*
X580343Y217771D03*
X588215Y214079D03*
X588968Y240112D03*
X582816Y228696D03*
X581099Y263680D03*
X586157Y366827D03*
X585585Y372052D03*
X577482Y383668D03*
X581985Y387227D03*
Y376427D03*
X587710Y399287D03*
X581985Y401158D03*
X587710Y404287D03*
X588723Y415846D03*
X588798Y435949D03*
X588723Y427949D03*
X588742Y431976D03*
X577845Y437151D03*
X587829Y445138D03*
X575345Y437151D03*
X580523Y435949D03*
X575075Y451263D03*
X582390Y464701D03*
X589507Y462559D03*
X583116Y476745D03*
X587500Y470308D03*
X587795Y479631D03*
X581335Y472100D03*
X581421Y813078D03*
X588500Y812093D03*
X584271Y1263988D03*
X602837Y32910D03*
X603064Y48023D03*
X599284Y42481D03*
X597956Y48047D03*
X606585Y43529D03*
X601073Y60301D03*
X603350Y73642D03*
X599295Y100747D03*
X606183Y95873D03*
X597275Y94922D03*
X596068Y106798D03*
X591385Y109165D03*
X602328Y109062D03*
X597769Y153640D03*
Y148640D03*
X603344Y139131D03*
X598552Y159066D03*
X600161Y188776D03*
X593661D03*
X604293Y193185D03*
X597293Y193186D03*
X602294Y203786D03*
X598968Y238878D03*
X603526Y229995D03*
X597050Y281950D03*
X602223Y298035D03*
X603723Y289721D03*
X602223Y314145D03*
Y322200D03*
X598414Y372357D03*
X598208Y383668D03*
X599884Y412000D03*
X593758Y415850D03*
X603326Y429530D03*
X590326Y445015D03*
X592529Y461563D03*
X598496Y451421D03*
X597500Y483500D03*
X602833Y791746D03*
X590710Y804192D03*
X603743Y794963D03*
X595619Y806084D03*
X600337Y800649D03*
X596821Y802688D03*
X592572Y809088D03*
X596621Y1240366D03*
X595253Y1266668D03*
X596944Y1270115D03*
X595532Y1262668D03*
X605771Y1263098D03*
X598112Y1264365D03*
X594991Y1285582D03*
Y1289582D03*
X613025Y42725D03*
X612608Y35961D03*
X618732Y39913D03*
X619563Y49193D03*
X615587Y45611D03*
X606263Y60301D03*
X616815Y60277D03*
X611579D03*
X615190Y74533D03*
X615772Y106645D03*
X618182Y100786D03*
X610009Y100748D03*
X614282Y95873D03*
X617420Y119640D03*
X619240Y123232D03*
X605853Y149640D03*
Y145640D03*
Y152140D03*
Y155131D03*
X618801Y165356D03*
Y175534D03*
Y170415D03*
X616357Y182229D03*
X608794Y203786D03*
X607868Y257562D03*
X618705Y285305D03*
X608773Y289721D03*
X609798Y298035D03*
X607273D03*
X606248Y289721D03*
X604748Y298035D03*
X609798Y314145D03*
X607273D03*
X604748D03*
X621585Y331358D03*
X609798Y322200D03*
X607273D03*
X604748D03*
X611118Y359462D03*
X613565Y350819D03*
X619035Y369542D03*
X613482Y383668D03*
X617985Y387227D03*
Y376427D03*
Y401728D03*
X606032Y418968D03*
X617985Y407346D03*
X617998Y415546D03*
X606811Y429528D03*
X611925Y437000D03*
X605769Y442593D03*
X615903Y493474D03*
X608886Y494400D03*
X618680Y511302D03*
X618957Y502306D03*
X616457D03*
X611896Y535178D03*
Y538178D03*
X607091Y528168D03*
X618645Y783582D03*
X609402Y788678D03*
X615571Y788448D03*
X608940Y1265991D03*
X610551Y1262988D03*
X618761Y1266988D03*
X615591Y1282038D03*
X618761Y1278668D03*
X606619Y1278302D03*
X610551Y1269888D03*
X616037Y1367166D03*
X608148Y1373890D03*
X616615Y1386232D03*
X616629Y1375082D03*
X613948Y1641600D03*
X624634Y48104D03*
X628410Y45381D03*
X624689Y58262D03*
X627881Y57120D03*
X622207Y60573D03*
X627496Y74977D03*
X626642Y71365D03*
X622156Y95948D03*
X626208Y100861D03*
X628885Y127057D03*
X630810Y122089D03*
X625532Y146982D03*
X625553Y152683D03*
X625755Y168917D03*
X626372Y193431D03*
X626824Y182080D03*
X620455Y219277D03*
Y228777D03*
X631505Y284355D03*
X626705Y285305D03*
X622705D03*
X626473Y305338D03*
X626388Y330536D03*
X631694Y341300D03*
X626555Y343929D03*
X624133Y346520D03*
X626596Y360196D03*
X636500Y360362D03*
X634105Y404652D03*
X635058Y399700D03*
X627925Y421966D03*
X631075Y429888D03*
X632281Y441904D03*
X622174Y438925D03*
X622197Y436116D03*
X622800Y461348D03*
X627880Y455310D03*
X620800Y474700D03*
X627364Y478823D03*
X632984Y471462D03*
X630758Y505874D03*
X633406Y497964D03*
X624381Y503765D03*
X631510Y510613D03*
X624718Y553428D03*
X634794Y590504D03*
X635567Y671774D03*
X631557Y773359D03*
X631741Y770318D03*
X633406Y1358576D03*
X634776Y1353739D03*
X630477Y1350109D03*
Y1353109D03*
X624795Y1373257D03*
X624976Y1378313D03*
X630195Y1384263D03*
X625195Y1383457D03*
X622352Y1393285D03*
X630523Y1392554D03*
X635849Y1393376D03*
X629808Y1668863D03*
X633422Y1673488D03*
X631643Y1670946D03*
X635491Y1696845D03*
X635472Y1711808D03*
X644963Y29143D03*
X638490Y33340D03*
X642157Y44695D03*
X639876Y49193D03*
X651042Y41545D03*
X647987Y47606D03*
X646042Y41545D03*
X640653Y58274D03*
X640670Y74369D03*
X650846Y74074D03*
X647938Y83795D03*
X644202Y84604D03*
X642607Y94116D03*
X645752Y134988D03*
X643800Y166053D03*
X641111Y158300D03*
X641006Y161829D03*
X643800Y161862D03*
X640923Y169388D03*
X649871Y181942D03*
X641276Y187557D03*
X637804Y235371D03*
X640804D03*
X637804Y239371D03*
X640804D03*
X640084Y227113D03*
X637804Y243371D03*
X640804D03*
X642171Y311280D03*
X641013Y324459D03*
X640922Y360342D03*
X639000Y364862D03*
X642128Y363279D03*
X636579Y366941D03*
X642617Y389299D03*
X637314Y393680D03*
X640784Y395957D03*
X651279Y404458D03*
X637160Y405449D03*
X635243Y433518D03*
X637432Y428935D03*
X642406Y427614D03*
X639211Y433862D03*
Y438191D03*
X635449Y449797D03*
X639002Y449862D03*
X639500Y442362D03*
X639313Y452361D03*
X635690Y461441D03*
X648500Y453862D03*
X635640Y464257D03*
X644849Y495582D03*
X647576Y497964D03*
X643053Y502891D03*
X640076Y497964D03*
X635906D03*
X642310Y535773D03*
X649592Y540078D03*
X639757Y533440D03*
X636055Y528605D03*
X646151Y535227D03*
X648314Y571169D03*
X644414D03*
X638694Y590504D03*
X650258Y590316D03*
X646358D03*
X650228Y674761D03*
X638967Y671774D03*
X646446Y674643D03*
X640271Y763488D03*
X636551Y767900D03*
X642804Y766871D03*
X636247Y771179D03*
X635092Y1277102D03*
X634995Y1384457D03*
X638053Y1384491D03*
X647401Y1384160D03*
X639907Y1570443D03*
X639132Y1573127D03*
X645180Y1597800D03*
X645190Y1595050D03*
X649153Y1625726D03*
X649297Y1623185D03*
X640242Y1639951D03*
X647630Y1641522D03*
X643128Y1639803D03*
X642716Y1653939D03*
X637218Y1654131D03*
X644905Y1646491D03*
X639800Y1646650D03*
X643074Y1668505D03*
X647574D03*
X647460Y1662952D03*
X640846Y1665189D03*
X650158Y1687189D03*
X643041Y1682883D03*
X647500Y1674805D03*
X640600D03*
X643300D03*
X639391Y1700695D03*
X640690Y1703547D03*
X651143Y1706162D03*
X644975Y1725236D03*
X635210Y1718395D03*
X641825Y1730516D03*
X640865Y1719684D03*
X657921Y30864D03*
X654117Y29099D03*
X654582Y45448D03*
X660928Y60707D03*
X651014Y60820D03*
X656600Y60537D03*
X661601Y75562D03*
X656501Y69662D03*
X657166Y79131D03*
X656427Y75431D03*
X661588Y69662D03*
X658228Y88447D03*
X666200Y84862D03*
X654037Y93241D03*
Y96041D03*
X651950Y99890D03*
X658949Y139840D03*
X662881Y149912D03*
Y146912D03*
X654326Y174437D03*
X653700Y179962D03*
X659881Y208262D03*
Y205762D03*
Y210762D03*
X662781Y207862D03*
Y205362D03*
Y210362D03*
X663915Y234476D03*
X659918Y326503D03*
X658905Y341885D03*
X661019Y344831D03*
X663551Y346035D03*
X649500Y373500D03*
X652425Y385924D03*
X659095Y381020D03*
X649495Y385118D03*
X659354Y393938D03*
X653523Y399987D03*
X652954Y394284D03*
X661297Y409857D03*
X662016Y417897D03*
X652027Y415930D03*
X654273Y419251D03*
X662000Y433862D03*
X654248Y422500D03*
X657535Y422694D03*
X666000Y429844D03*
X651432Y433532D03*
X662000Y429844D03*
X652763Y427866D03*
X651384Y445252D03*
X661546Y444497D03*
X662000Y449862D03*
X654441Y449618D03*
X662000Y437844D03*
X657622Y437819D03*
X651853Y439518D03*
X653449Y458542D03*
X662570Y461547D03*
Y457755D03*
X662000Y473862D03*
X666000Y473844D03*
X651072Y465939D03*
X654000Y465824D03*
X654014Y473862D03*
X662000Y465862D03*
X651114Y473884D03*
X662000Y469862D03*
X653266Y479106D03*
X663374Y484295D03*
X652380Y482390D03*
X657520Y486330D03*
X649500Y490260D03*
X660215Y483109D03*
X658758Y497964D03*
X655917D03*
X661718Y498056D03*
X651406Y501178D03*
X650404Y496102D03*
X652576Y497964D03*
X659425Y521075D03*
X665689Y550294D03*
X649922Y545610D03*
X655967Y544375D03*
X658642Y573893D03*
X661718Y579932D03*
X653368Y581468D03*
X655572Y572603D03*
X656832Y577205D03*
X662992Y598660D03*
X658613Y599534D03*
X662628Y674761D03*
X660175Y679517D03*
X657428Y674761D03*
X663580Y731509D03*
X658947Y767300D03*
Y771100D03*
X662600Y1311502D03*
Y1308502D03*
X653376Y1365793D03*
X661719Y1363394D03*
X651973Y1363038D03*
X653149Y1372500D03*
X653101Y1369862D03*
X652651Y1375308D03*
X661813Y1370081D03*
X653117Y1378037D03*
X651877Y1391074D03*
X663160Y1511734D03*
Y1516734D03*
Y1519234D03*
Y1521734D03*
X660660Y1519234D03*
X661710Y1514148D03*
X663160Y1524234D03*
X666092Y1553650D03*
X660953Y1539998D03*
X663133Y1543744D03*
Y1541244D03*
Y1538744D03*
X660953Y1542498D03*
X657430Y1555228D03*
X659532Y1546519D03*
X664246Y1561009D03*
X661731Y1561083D03*
X661156Y1626532D03*
X650966Y1618934D03*
X651870Y1612986D03*
X650753Y1615912D03*
X653542Y1649059D03*
X660058Y1648889D03*
X660389Y1654481D03*
X663431Y1645780D03*
X654712Y1653813D03*
X664315Y1654484D03*
X650074Y1668505D03*
X658648Y1664169D03*
X655683Y1664212D03*
X653154Y1683265D03*
X664159Y1674844D03*
X661528Y1674865D03*
X650200Y1674805D03*
X658491Y1688965D03*
X649464Y1691180D03*
X659837Y1698400D03*
X659557Y1714672D03*
X658759Y1707147D03*
X659028Y1710047D03*
X660930Y1730277D03*
X662120Y1720404D03*
X670613Y42464D03*
X674013D03*
X677476Y33317D03*
X680864Y38190D03*
X666506Y32750D03*
X674647Y38190D03*
X677305Y57947D03*
X665469Y58525D03*
X674036Y74522D03*
X675509Y88173D03*
X667941Y80142D03*
X677561Y118409D03*
X677738Y115428D03*
X665651Y147692D03*
X673011Y169021D03*
X679035Y204181D03*
X678226Y215771D03*
X674348Y218580D03*
X666552Y346115D03*
X677111Y345662D03*
X672111D03*
X674611D03*
X676800Y369362D03*
X672800D03*
X680800Y380280D03*
X672800Y382362D03*
X676000Y378100D03*
X667090Y385150D03*
X671500Y390862D03*
X679940Y400933D03*
X675500Y398862D03*
Y390862D03*
X670018Y418690D03*
X669929Y407999D03*
X666000Y433862D03*
Y425862D03*
X670000Y429864D03*
Y433844D03*
Y425894D03*
X666000Y437844D03*
X670000Y442362D03*
Y437844D03*
X666000Y442362D03*
X670000Y446362D03*
X679062Y455140D03*
X666000Y453844D03*
Y457862D03*
X670000Y453844D03*
X666000Y461862D03*
X670000Y469824D03*
Y477862D03*
X678000D03*
X670000Y482862D03*
X678000D03*
X681213Y495658D03*
X672699Y506907D03*
X664741Y506865D03*
X680488Y504784D03*
X665425Y537000D03*
X664454Y574896D03*
X665774Y571762D03*
X666192Y598660D03*
X679047Y678733D03*
X673287Y733156D03*
X674123Y736083D03*
X667101Y736071D03*
X672505Y766871D03*
X674552Y1342488D03*
Y1344988D03*
X665167Y1380836D03*
Y1376836D03*
X673671Y1431922D03*
X675272Y1434525D03*
X678386Y1507965D03*
X677871Y1522079D03*
X678345Y1516994D03*
X677871Y1519579D03*
X673174Y1515806D03*
X675505Y1512606D03*
X678339Y1510960D03*
X677871Y1524579D03*
X678121Y1528516D03*
X665832Y1527425D03*
X672715Y1526626D03*
Y1530526D03*
X678350Y1567400D03*
X669524Y1560850D03*
X672163Y1560899D03*
X673729Y1556768D03*
X666978Y1560945D03*
X672810Y1571560D03*
X666610Y1571580D03*
X668133Y1625828D03*
X670839Y1620863D03*
X673960Y1633042D03*
X669648Y1640917D03*
X670803Y1654606D03*
X671068Y1650818D03*
X674908Y1644481D03*
X667971Y1654404D03*
X669178Y1646627D03*
X673548Y1669550D03*
X678117Y1662787D03*
X675497Y1687253D03*
X673359Y1674409D03*
X671001Y1696017D03*
X671798Y1704542D03*
X673113Y1716599D03*
X667701Y1705043D03*
X668058Y1720092D03*
X673113Y1727261D03*
X684611Y41857D03*
X682291Y46822D03*
X690476Y32684D03*
X692390Y46939D03*
X692466Y35950D03*
X687835Y37850D03*
X687345Y46940D03*
X687018Y58357D03*
X683369Y58157D03*
X692390Y72692D03*
X690028Y70142D03*
X687665Y73202D03*
X685781Y70022D03*
X680580Y79230D03*
X681054Y104668D03*
X686891Y115868D03*
X687000Y119500D03*
X685500Y124000D03*
X679316Y209861D03*
X680576Y207105D03*
X681333Y212326D03*
X679737Y217763D03*
X693621Y346169D03*
X680828Y363500D03*
X684800Y369362D03*
X680800D03*
X691484Y360643D03*
X691500Y382462D03*
X685200Y377820D03*
X690105Y401775D03*
X687500Y390680D03*
X684794Y402268D03*
X683500Y390862D03*
X679500D03*
X692996Y418358D03*
X694299Y413108D03*
X689269Y410420D03*
X687612Y471850D03*
X691572Y465214D03*
X684800Y477862D03*
X687472Y486994D03*
X684680Y485942D03*
X684800Y481862D03*
X680187Y491243D03*
X690452Y486984D03*
X687310Y500453D03*
X682915Y500568D03*
X683000Y521500D03*
X687310Y522141D03*
X694111Y537881D03*
X690718Y578913D03*
X694996Y575081D03*
X689574Y572866D03*
X681352Y681305D03*
X691417Y680382D03*
X685786Y680936D03*
X686509Y677440D03*
X688648Y767300D03*
Y771100D03*
X687961Y1314308D03*
Y1320308D03*
Y1323308D03*
Y1317308D03*
X684868Y1327117D03*
X682348D03*
Y1339617D03*
X683052Y1342548D03*
X684868Y1329617D03*
X682348D03*
X684868Y1332117D03*
X682348D03*
X684868Y1334617D03*
X682348D03*
X684868Y1337117D03*
Y1339617D03*
X682348Y1337117D03*
X683052Y1345048D03*
X681289Y1418291D03*
X683391Y1420531D03*
X685448Y1423137D03*
X691587Y1429515D03*
X689538Y1427467D03*
X684350Y1448911D03*
X692376Y1438326D03*
X691943Y1441626D03*
X687040Y1452300D03*
X684280Y1452260D03*
X684603Y1507851D03*
X681517Y1508034D03*
X687529Y1508173D03*
X690683Y1508058D03*
X693395D03*
X693532Y1510755D03*
X690820D03*
X687666Y1510870D03*
X687711Y1513612D03*
X690751Y1513750D03*
X693655Y1513818D03*
X693587Y1516470D03*
X690752Y1516516D03*
X683666Y1515189D03*
X680717Y1513292D03*
X684557Y1510685D03*
X681563Y1510708D03*
X693495Y1519305D03*
X679854Y1551492D03*
X679413Y1548843D03*
X680107Y1554330D03*
X681780Y1574280D03*
X684080Y1576500D03*
X686949Y1625144D03*
X689897Y1621781D03*
X692209Y1620037D03*
X691036Y1625508D03*
X686994Y1629077D03*
X693451Y1628733D03*
X686808Y1643500D03*
X685578Y1637479D03*
X683067Y1641758D03*
X686075Y1657082D03*
X679413Y1653251D03*
X685719Y1672391D03*
X685747Y1669303D03*
X693608Y1671081D03*
X685635Y1675310D03*
X691560Y1682047D03*
X693480Y1673940D03*
X692390Y1687594D03*
X705666Y48010D03*
X697678Y47132D03*
X697893Y35950D03*
X702481Y48327D03*
X698462Y60683D03*
X695220Y60455D03*
X704201Y72112D03*
X699476Y69982D03*
X701081Y72450D03*
X694752Y70212D03*
X696701Y72462D03*
X698711Y86035D03*
X696371Y78512D03*
X696728Y81552D03*
Y84052D03*
X706721Y100462D03*
X702721Y102162D03*
X701221Y104862D03*
X697721D03*
X695721Y102162D03*
X694221Y104862D03*
X699221Y102162D03*
X699398Y123668D03*
X704709Y125586D03*
X704771Y171188D03*
Y167788D03*
X703486Y345507D03*
X699813Y344798D03*
X706139Y345597D03*
X695500Y374362D03*
X699500D03*
X703500D03*
X707500D03*
X707943Y360643D03*
X707500Y368862D03*
X696391Y368617D03*
X703477Y369409D03*
X695500Y382362D03*
X700300Y382502D03*
X707500Y382362D03*
X700000Y386790D03*
X707500Y386862D03*
X703700Y386832D03*
X695500Y386862D03*
X699500Y390862D03*
X695500D03*
X707500D03*
X703500Y401290D03*
Y390862D03*
X708584Y404868D03*
X699431Y513344D03*
X703774Y513463D03*
X707664Y513375D03*
X703788Y521817D03*
X696020Y521844D03*
X699800Y521760D03*
X708500Y517362D03*
X708210Y537816D03*
X708500Y529862D03*
X704500D03*
X700790Y537732D03*
X704500Y537862D03*
X708500Y533862D03*
X696829Y533604D03*
X702657Y533695D03*
X697018Y537577D03*
X704500Y545862D03*
X696283Y546530D03*
X710429Y545752D03*
X708500Y555451D03*
X698996Y575081D03*
X704056D03*
X708056D03*
X704056Y583081D03*
X698996D03*
X702806Y613264D03*
X696928Y613207D03*
X706387Y621686D03*
X705158Y645357D03*
X703781Y641805D03*
X704965Y638767D03*
X707833Y655325D03*
X704549Y655238D03*
X701233Y655355D03*
X708418Y650389D03*
X694812Y680188D03*
X698756Y676388D03*
X694837Y676412D03*
X701386Y679683D03*
X703584Y676544D03*
X708012Y676836D03*
X705697Y679533D03*
X697571Y730453D03*
X704598Y732288D03*
X700205Y733211D03*
X702553Y735811D03*
X702206Y766871D03*
X697461Y1314008D03*
Y1320008D03*
Y1323008D03*
X702388Y1327127D03*
X699868D03*
X697461Y1317008D03*
X701771Y1342488D03*
X702388Y1337127D03*
Y1339627D03*
X699868Y1337127D03*
Y1339627D03*
X702388Y1329627D03*
X699868D03*
X702388Y1332127D03*
X699868D03*
X702388Y1334627D03*
X699868D03*
X701771Y1344988D03*
X705657Y1387027D03*
X701689Y1399545D03*
X697731Y1397513D03*
X706351Y1397588D03*
X705657Y1389568D03*
X695162Y1441350D03*
X696237Y1508149D03*
X699247Y1508062D03*
X699049Y1510892D03*
X696374Y1510846D03*
X696329Y1513818D03*
X696330Y1516584D03*
X699140Y1513772D03*
X707050Y1531700D03*
X709150Y1536250D03*
X703290Y1551700D03*
X707050Y1548400D03*
Y1541800D03*
X703290Y1545100D03*
X708500Y1560500D03*
X708994Y1568507D03*
X699500Y1559000D03*
X699610Y1568523D03*
Y1572523D03*
Y1576523D03*
X708600Y1572523D03*
X710420Y1585173D03*
X710550Y1576523D03*
X710080Y1581683D03*
X699610Y1584523D03*
X699500Y1596500D03*
Y1588500D03*
X709836Y1594721D03*
X710360Y1589296D03*
X699000Y1604500D03*
X699500Y1599500D03*
X709382Y1601210D03*
X699500Y1608500D03*
X709020Y1609101D03*
X699424Y1616627D03*
X695933Y1623460D03*
X709260Y1617903D03*
X701114Y1640345D03*
X702683Y1633715D03*
X703563Y1644116D03*
X702402Y1650469D03*
X700528Y1661468D03*
X697503Y1661331D03*
X703102Y1665554D03*
X714471Y46670D03*
X724621Y40062D03*
X719821Y45862D03*
X714322Y56286D03*
X721163Y58588D03*
X714096Y73686D03*
X712717Y68541D03*
X719416Y68738D03*
Y74036D03*
X725016Y86952D03*
X720016D03*
X715745Y86300D03*
X712725Y84714D03*
X712291Y106722D03*
X715934Y117488D03*
Y114588D03*
X712734Y117488D03*
Y114588D03*
X720434Y135088D03*
X717434D03*
X719934Y124488D03*
X723134D03*
X712341Y128093D03*
X710284Y169826D03*
X717021Y220862D03*
X714867Y344943D03*
X717712Y346103D03*
X715500Y374362D03*
X719500D03*
X723531Y368862D03*
X723500Y360862D03*
X711500Y374362D03*
X715500Y360862D03*
X719500Y368862D03*
X715500D03*
X711363Y369274D03*
X711500Y382362D03*
X719640Y386862D03*
X723632D03*
X711500D03*
X715500D03*
X722500Y383162D03*
X723500Y390862D03*
X719500D03*
X715500D03*
X711500D03*
X716500Y521862D03*
X711617Y513531D03*
X724500Y517362D03*
X716500D03*
X720400Y517440D03*
X720452Y513362D03*
X716716Y513368D03*
X720499Y533474D03*
X719841Y537348D03*
X712113Y537797D03*
X720500Y555862D03*
Y546211D03*
X712115Y541872D03*
X712409Y555413D03*
X710464Y557036D03*
X722201Y579306D03*
X723483Y574890D03*
X714583Y590792D03*
X716181Y585562D03*
X715037Y606428D03*
X716313Y610134D03*
X719710Y612831D03*
X720787Y627907D03*
X716721D03*
X713343Y633842D03*
X724000Y633906D03*
X725812Y654713D03*
X715371Y654726D03*
X711702Y646533D03*
X711295Y665117D03*
X718129Y666725D03*
X722129D03*
X712164Y676912D03*
X712120Y680287D03*
X717515Y679833D03*
X720563Y679886D03*
X720613Y677040D03*
X723814Y736782D03*
X718349Y767300D03*
Y771100D03*
X721339Y1314048D03*
X711839Y1314348D03*
X721339Y1323048D03*
Y1320048D03*
Y1317048D03*
X715828Y1327277D03*
X710488Y1327177D03*
X713008D03*
X711839Y1323348D03*
Y1320348D03*
Y1317348D03*
X713008Y1329877D03*
Y1332377D03*
Y1334877D03*
X715828Y1332877D03*
Y1330377D03*
X713008Y1337377D03*
Y1339877D03*
X715828Y1335377D03*
X710288Y1339677D03*
Y1337177D03*
X710221Y1342488D03*
X710288Y1334677D03*
Y1332177D03*
Y1329677D03*
X710221Y1344988D03*
X712419Y1398094D03*
X719861Y1400139D03*
X716373Y1398539D03*
X719111Y1397571D03*
X712419Y1400602D03*
X709430Y1394417D03*
X722877Y1390881D03*
X712099Y1416973D03*
X714599D03*
X717099D03*
X712099Y1414473D03*
X714599D03*
X717099D03*
X709599Y1416973D03*
Y1414473D03*
X717099Y1432773D03*
X712099D03*
X714599D03*
X717099Y1430273D03*
X712099D03*
X714599D03*
X709599Y1432773D03*
Y1427373D03*
Y1424873D03*
Y1430273D03*
Y1419873D03*
Y1422373D03*
X714259Y1447483D03*
X719471Y1467422D03*
X711671D03*
X714271D03*
X716871D03*
X720217Y1472287D03*
X717617D03*
X715017D03*
X720926Y1469814D03*
X718326D03*
X715726D03*
X713126D03*
X716067Y1474792D03*
X718667D03*
X721267D03*
X717358Y1477038D03*
X719958D03*
X714474Y1566333D03*
X724110Y1561825D03*
X714110Y1581475D03*
X714900Y1571273D03*
X721963Y1576932D03*
X719963Y1578932D03*
X721440Y1570963D03*
X719963Y1585790D03*
X721963Y1587790D03*
X723590Y1595323D03*
X718892Y1597152D03*
X714372Y1594679D03*
X723408Y1608740D03*
X720106Y1609542D03*
X717798Y1607335D03*
X713718Y1610235D03*
X717229Y1612376D03*
X718129Y1624330D03*
X722104Y1626253D03*
X715744Y1622842D03*
X722889Y1622491D03*
X711298Y1632534D03*
X718122Y1636332D03*
X718116Y1639129D03*
X713771Y1654927D03*
X722480Y1657616D03*
X719117Y1682722D03*
X723181Y1688825D03*
X725925Y-15571D03*
Y-12171D03*
X740101Y41162D03*
X736621Y45262D03*
X733315Y40862D03*
X728721Y43562D03*
X726789Y60562D03*
X738590Y59868D03*
X730785Y58068D03*
X728285Y58135D03*
X724645Y58362D03*
X734769Y60757D03*
X725769Y69737D03*
X736864Y74943D03*
X731864D03*
X727200Y73210D03*
X729918Y90998D03*
X739824Y91052D03*
X734380Y80518D03*
X729380D03*
X736650Y102350D03*
X735771Y94988D03*
X730660Y108484D03*
X728734Y132088D03*
Y129288D03*
Y126388D03*
X735500Y143000D03*
X724147Y345291D03*
X729211Y346379D03*
X726431Y346384D03*
X738773Y346716D03*
X734463Y346712D03*
X735500Y368862D03*
X734166Y360782D03*
X739500Y368862D03*
X727564D03*
X731500Y360862D03*
X731406Y374331D03*
X731500Y368862D03*
Y386862D03*
X739553Y388270D03*
X735500Y386862D03*
X727500D03*
X735500Y390862D03*
X727500D03*
X735500Y399330D03*
X738672Y494444D03*
X728938Y517520D03*
X724500Y513362D03*
X732500D03*
X739185Y521394D03*
X728500Y521862D03*
X724500D03*
X728500Y513362D03*
X736609Y518426D03*
X728500Y529862D03*
X728576Y537476D03*
X736500Y537862D03*
X724336Y537527D03*
X724433Y530870D03*
X732500Y529862D03*
X736647Y529772D03*
X732580Y537193D03*
X724697Y535053D03*
X728652Y545862D03*
X728695Y550943D03*
X736670Y545864D03*
X740500Y545862D03*
X724684Y545864D03*
X724281Y553438D03*
X728714Y554190D03*
X732520Y545988D03*
X736528Y576480D03*
Y579615D03*
X727253Y610689D03*
X724246Y627939D03*
X736362Y636854D03*
X730770Y644218D03*
X733382Y633574D03*
X729489Y666547D03*
X734442Y675695D03*
X730837Y678940D03*
X738486Y679139D03*
X724931Y678364D03*
X735316Y736742D03*
X725712Y734135D03*
X729391D03*
X727576Y736756D03*
X727448Y766871D03*
X735739Y1314048D03*
Y1320048D03*
Y1317048D03*
X724788Y1327277D03*
X727501Y1327230D03*
X730021D03*
X735739Y1323048D03*
X727401Y1332430D03*
Y1329930D03*
Y1334930D03*
X724788Y1330377D03*
Y1332877D03*
X727401Y1339930D03*
Y1337430D03*
X724788Y1335377D03*
X730021Y1337230D03*
Y1339730D03*
Y1334730D03*
Y1329730D03*
Y1332230D03*
X730795Y1342444D03*
Y1344944D03*
X738439Y1387127D03*
X728198Y1388026D03*
Y1385126D03*
X738439Y1389668D03*
X727737Y1390881D03*
X725307D03*
X734767Y1396986D03*
Y1394086D03*
X732567Y1392586D03*
X732667Y1395586D03*
X730501Y1397216D03*
Y1394316D03*
X734767Y1391186D03*
X735418Y1426122D03*
Y1423122D03*
Y1420122D03*
X732418Y1426122D03*
Y1423122D03*
Y1420122D03*
X735453Y1525368D03*
X737551Y1524008D03*
X727325Y1563400D03*
X727571Y1558353D03*
X736782Y1555496D03*
X730782D03*
X733782D03*
X727571Y1555353D03*
X733782Y1567496D03*
X736782D03*
X730782D03*
X733782Y1558496D03*
Y1561496D03*
X736782Y1558496D03*
Y1561496D03*
X733782Y1564496D03*
X736782D03*
X730782Y1558496D03*
Y1561496D03*
Y1564496D03*
X726475Y1571293D03*
X723963Y1578932D03*
X730782Y1570496D03*
X736782D03*
X733782D03*
X733380Y1577231D03*
X727780Y1582361D03*
Y1577231D03*
X723963Y1585790D03*
X726550Y1599358D03*
X733380Y1587491D03*
X727780D03*
X736998Y1597463D03*
X730998D03*
X733998D03*
X736998Y1594463D03*
X730998D03*
X733998D03*
X736998Y1600463D03*
X730998D03*
X733998D03*
Y1603663D03*
X736998D03*
X733998Y1606663D03*
X736998D03*
X730998Y1603663D03*
Y1606663D03*
X730647Y1623629D03*
X727320Y1623698D03*
X736723Y1623938D03*
X731119Y1647997D03*
X735642Y1648537D03*
X730347Y1682902D03*
X725638Y1682890D03*
X732852Y1695701D03*
X738030Y1723903D03*
Y1726903D03*
X738108Y1721157D03*
X738075Y1718082D03*
X746101Y46262D03*
X745901Y40362D03*
X749478Y59902D03*
X746588Y59754D03*
X740817Y58503D03*
X747488Y71429D03*
X740537Y73564D03*
X750034Y89988D03*
X750701Y106642D03*
X754783Y96553D03*
X750034Y92888D03*
X741309Y108742D03*
X748034Y116288D03*
X748261Y112552D03*
X743050Y139182D03*
X751221Y137864D03*
X743547Y147703D03*
X748915Y158608D03*
X745031Y161463D03*
X748125Y170618D03*
X751575Y184252D03*
X746522Y308804D03*
X750717Y319907D03*
X747594Y319106D03*
X747696Y332772D03*
X751337Y343849D03*
X748752Y343582D03*
X745132Y344964D03*
X752926Y361021D03*
X747500Y368862D03*
X751500D03*
X743500D03*
Y374362D03*
X749389Y360816D03*
X755135Y368907D03*
X754813Y374362D03*
X739500D03*
X747500D03*
X747454Y386817D03*
X751652Y386862D03*
X743500Y386962D03*
X739652Y390862D03*
X743500D03*
X747500D03*
X751500D03*
X747629Y406163D03*
X753252Y495234D03*
X748381Y495244D03*
X752652Y504106D03*
X752500Y517362D03*
X744500Y513362D03*
X748661Y517060D03*
X740500Y513362D03*
X752500D03*
X748500D03*
X753951Y521801D03*
X748077Y521789D03*
X740500Y537862D03*
X752965Y537678D03*
X748143Y530269D03*
X744916Y530268D03*
X752500Y529862D03*
X748000Y537862D03*
X741851Y553544D03*
X745645Y545880D03*
X752500Y545862D03*
X745091Y553563D03*
X748500Y545862D03*
X752195Y554761D03*
X748482Y557085D03*
X751731Y557714D03*
X739128Y566639D03*
X741624Y580707D03*
X741200Y577470D03*
X749131Y570340D03*
X750062Y655415D03*
X753309Y655515D03*
X750074Y648739D03*
X753483Y648749D03*
X751885Y666724D03*
X753231Y678679D03*
X742579Y676093D03*
X746665Y678879D03*
X750168Y675833D03*
X748049Y767300D03*
Y771100D03*
X745439Y1314048D03*
X748188Y1327317D03*
X745491Y1327124D03*
X742971D03*
X745439Y1323048D03*
Y1320048D03*
Y1317048D03*
X745691Y1332424D03*
Y1329924D03*
Y1334924D03*
X748188Y1333017D03*
Y1330517D03*
X745691Y1339924D03*
Y1337424D03*
X748188Y1335517D03*
X742971Y1337124D03*
Y1339624D03*
Y1334624D03*
Y1329624D03*
Y1332124D03*
X739501Y1342244D03*
Y1344744D03*
X739932Y1398042D03*
X745201Y1398194D03*
X752643Y1400239D03*
X749155Y1398639D03*
X751893Y1397671D03*
X745201Y1400702D03*
X742212Y1394517D03*
X739611Y1458211D03*
X750418Y1468893D03*
X750968Y1482349D03*
X746111Y1504125D03*
X745984Y1501052D03*
X745001Y1516471D03*
X750205Y1512307D03*
X750155Y1516451D03*
X739900Y1523152D03*
X748782Y1555496D03*
X742782D03*
X739782D03*
X745782D03*
X739782Y1558496D03*
Y1561496D03*
Y1564496D03*
X745782Y1558496D03*
X742782D03*
X745782Y1561496D03*
X742782D03*
X745782Y1564496D03*
X742782D03*
X739782Y1567496D03*
X742782D03*
X748782Y1558496D03*
Y1561496D03*
Y1564496D03*
X747110Y1575863D03*
X747150Y1583247D03*
X747110Y1579863D03*
X739782Y1570496D03*
X742782D03*
X738880Y1582361D03*
Y1577231D03*
X747160Y1587773D03*
X749167Y1591967D03*
X754635Y1592571D03*
X738880Y1587491D03*
X745998Y1597463D03*
X742998D03*
X745998Y1594463D03*
X742998D03*
X739998Y1597463D03*
Y1594463D03*
X745998Y1600463D03*
X742998D03*
X739998D03*
X745998Y1603663D03*
X742998D03*
X739998D03*
X745998Y1606663D03*
X742998D03*
X739998D03*
X743664Y1626945D03*
X753770Y1636083D03*
X751521Y1656008D03*
X739880Y1648046D03*
X742792Y1647982D03*
X745075Y1665675D03*
X754030Y1669256D03*
X748254Y1674771D03*
X752187Y1682994D03*
X748413Y1679367D03*
X746766Y1696036D03*
X740328Y1698376D03*
X747289Y1693063D03*
X752187Y1691058D03*
X741030Y1723903D03*
Y1726903D03*
X741160Y1721150D03*
X741025Y1718195D03*
X757721Y62132D03*
X760221D03*
X762721D03*
X755621Y51602D03*
X758621D03*
X757721Y64632D03*
X760221D03*
X763221Y65132D03*
X757188Y91829D03*
X757694Y98108D03*
Y100653D03*
X760193Y106500D03*
X757576Y112575D03*
X756000Y145500D03*
X754825Y163397D03*
X756303Y158417D03*
X765950Y190669D03*
X765000Y186500D03*
X754737Y185469D03*
X757629Y239295D03*
X761067Y280355D03*
X763384Y279231D03*
X763508Y284404D03*
X763463Y281840D03*
X760614Y284100D03*
X754759Y281007D03*
X758510Y298620D03*
X760462Y295662D03*
X757937Y303908D03*
X768130Y335363D03*
X758245Y343763D03*
X764331Y374401D03*
X756347Y360851D03*
X764983Y368052D03*
X766304Y372862D03*
X768304Y374362D03*
X759652D03*
X755500Y386862D03*
X759500D03*
X763500D03*
X767500D03*
X759500Y390791D03*
X755500Y390862D03*
X759500Y402098D03*
X767500Y401470D03*
Y390862D03*
X763500D03*
X757258Y408763D03*
X765975Y414414D03*
X769648Y430511D03*
X770530Y423460D03*
X768301Y438223D03*
X770918Y442510D03*
X770042Y446829D03*
X770590Y470940D03*
X762800Y493654D03*
X764500Y521862D03*
X756500Y513340D03*
X764500D03*
X756800Y517050D03*
X760500Y521189D03*
X764600Y517022D03*
X756186Y529888D03*
X764500Y529862D03*
X760500Y529845D03*
X757860Y537859D03*
X760660Y537862D03*
X756500Y545862D03*
X764500D03*
X759568Y545867D03*
X768340Y563678D03*
X765809Y563410D03*
X758103Y556873D03*
X765041Y565867D03*
X762530Y565340D03*
X757745Y655353D03*
X755765Y666904D03*
X762656Y667835D03*
X756936Y676319D03*
X768565Y677573D03*
X760529Y677715D03*
X764401Y676968D03*
X762396Y732915D03*
X754532Y735859D03*
X760425Y736233D03*
X764568Y736183D03*
X761608Y766871D03*
X759839Y1313948D03*
Y1319948D03*
X760204Y1327314D03*
X762754D03*
X759839Y1316948D03*
X757638Y1327317D03*
X759839Y1322948D03*
X760204Y1332514D03*
Y1330014D03*
Y1335014D03*
X757638Y1333017D03*
Y1330517D03*
X760194Y1340024D03*
Y1337524D03*
X757638Y1335517D03*
X762844Y1337324D03*
Y1339824D03*
X762754Y1334814D03*
Y1329814D03*
Y1332314D03*
X762261Y1343424D03*
Y1345924D03*
X760980Y1385146D03*
Y1388046D03*
X758089Y1390981D03*
X760519D03*
X755659D03*
X767549Y1391286D03*
Y1397086D03*
Y1394186D03*
X765349Y1392686D03*
X765449Y1395686D03*
X763283Y1397316D03*
Y1394416D03*
X758163Y1490789D03*
Y1498663D03*
Y1494726D03*
Y1502600D03*
Y1506538D03*
Y1522286D03*
Y1510474D03*
X757826Y1514412D03*
X758056Y1518349D03*
X760650Y1570633D03*
Y1578733D03*
Y1574733D03*
X757610Y1576023D03*
X766212Y1568043D03*
X757650Y1580023D03*
X766950Y1581233D03*
X757610Y1584023D03*
X767750Y1584108D03*
X757610Y1589023D03*
X760650Y1587733D03*
X760521Y1595500D03*
X759723Y1626161D03*
X755261Y1628208D03*
X758030Y1668583D03*
X754839Y1678069D03*
X768463Y1687769D03*
X757161Y1696424D03*
X768733Y1694485D03*
X781441Y118637D03*
X782819Y149471D03*
X780159Y146961D03*
X772270Y153728D03*
X771427Y158026D03*
X782712Y260466D03*
X777408Y256648D03*
X777421Y277962D03*
X779884Y281705D03*
X769790Y296231D03*
X777468Y296315D03*
X769861Y302462D03*
X782641Y310888D03*
X779681Y313053D03*
X770190Y312563D03*
X779121Y303410D03*
Y308755D03*
X780046Y328268D03*
X772119Y333537D03*
X771964Y339716D03*
X781812Y341863D03*
X779118Y341749D03*
X769000Y364000D03*
X776500Y371000D03*
X784500Y367500D03*
X771512Y386862D03*
X775388Y390862D03*
X770000Y380787D03*
X777612Y403505D03*
X771512Y390862D03*
X780295Y403538D03*
X784498Y396353D03*
X782700Y415284D03*
X773181Y415197D03*
X773233Y409154D03*
X783256Y409340D03*
X770159Y410257D03*
X783770Y422454D03*
X772610Y434690D03*
X780877Y427344D03*
X771718Y426804D03*
X780877Y423344D03*
X783821Y431534D03*
X780877Y431368D03*
X772677Y451374D03*
X780577Y435564D03*
X780877Y443344D03*
Y447344D03*
X780977Y459524D03*
X780877Y463344D03*
Y455344D03*
X783377Y451344D03*
X780877Y475344D03*
X780759Y479344D03*
X783877Y475344D03*
X772427D03*
X783759Y479344D03*
X780877Y483344D03*
X772390Y491047D03*
X772427Y487344D03*
X783358Y495344D03*
X783351Y499221D03*
X771039Y511292D03*
X775100Y502504D03*
X772427Y495344D03*
X777166Y504477D03*
X774998Y511306D03*
X774964Y514204D03*
X772100Y532700D03*
X777200Y530250D03*
X772000Y529862D03*
X781699Y536425D03*
X772000Y545862D03*
X776345Y545733D03*
X777754Y558740D03*
X773463Y563455D03*
X778747Y572269D03*
X779448Y632498D03*
X772459Y655290D03*
X771553Y677963D03*
X777750Y767300D03*
Y771100D03*
X783280Y1296009D03*
X778030Y1296259D03*
X780530D03*
X783280Y1298509D03*
X785520Y1292160D03*
X769439Y1313948D03*
X783280Y1301009D03*
X769439Y1319948D03*
Y1322948D03*
Y1316948D03*
X770881Y1343344D03*
X782115Y1334173D03*
X770881Y1345844D03*
X774646Y1516441D03*
X772906Y1522901D03*
X774616Y1520361D03*
X778850Y1556133D03*
X781850D03*
Y1559133D03*
Y1562133D03*
Y1565133D03*
X778850Y1559133D03*
Y1562133D03*
Y1565133D03*
X771450Y1577333D03*
X781850Y1568133D03*
Y1571133D03*
X778850Y1568133D03*
Y1571133D03*
X779977Y1577233D03*
Y1582363D03*
X771550Y1587133D03*
X774420Y1587284D03*
X779977Y1587493D03*
X779550Y1594533D03*
X782550D03*
X776550Y1597533D03*
Y1594533D03*
X779550Y1597533D03*
X782550D03*
Y1600533D03*
X776550D03*
X779550D03*
Y1606533D03*
X782550Y1603533D03*
X779550D03*
X776550Y1606533D03*
Y1603533D03*
X782550Y1606533D03*
X785181Y120947D03*
X792681D03*
X790181D03*
X787681D03*
X783941Y118637D03*
X786441D03*
X788941D03*
X785529Y270459D03*
X798205Y279146D03*
X794058Y301569D03*
X793221Y296062D03*
X793897Y309026D03*
X793855Y305316D03*
X798493Y301377D03*
X795921Y312662D03*
X787500Y328362D03*
X799226Y328467D03*
X791726D03*
X783726D03*
X785674Y342279D03*
X788806Y342236D03*
X791403Y342262D03*
X793951Y342224D03*
X795685Y357498D03*
X792302Y357537D03*
X798312Y372571D03*
X796021Y395924D03*
X797000Y404000D03*
X786571Y403455D03*
X785923Y419194D03*
X787000Y407500D03*
X796283Y415344D03*
Y419344D03*
X786877Y427344D03*
X796283Y423344D03*
Y431344D03*
X783877Y427344D03*
X796283D03*
X786999Y435476D03*
X797252Y443344D03*
X786877D03*
X796333Y435344D03*
X786203Y447054D03*
X783877Y435444D03*
X797197Y447344D03*
X786887Y451344D03*
X797252D03*
X797322Y463344D03*
X786825Y459518D03*
X786755Y455524D03*
X797252Y455344D03*
X797326Y479344D03*
X786877Y471344D03*
X797463Y476159D03*
X786877Y475344D03*
X786440Y480769D03*
X797405Y487464D03*
X797326Y483344D03*
X787092Y490681D03*
X786358Y483566D03*
X786102Y507536D03*
X787446Y495344D03*
X787279Y499238D03*
X790503Y501826D03*
X799450Y511801D03*
X800674Y504130D03*
X789125Y529425D03*
X800500Y540500D03*
X794357Y559996D03*
X785919Y559660D03*
X792782Y565323D03*
X791723Y574946D03*
X799742Y628983D03*
X789135Y617097D03*
X783653Y631671D03*
X787591Y631785D03*
X788537Y734410D03*
X793131Y734310D03*
X784543Y734510D03*
X791308Y766871D03*
X789020Y1292160D03*
X792520D03*
X796020D03*
X794273Y1354600D03*
Y1357600D03*
Y1364500D03*
Y1361500D03*
X784669Y1462178D03*
X796955Y1487468D03*
X788710Y1488821D03*
X784277Y1504569D03*
Y1500632D03*
Y1508506D03*
Y1512443D03*
X791867Y1524254D03*
X784850Y1556133D03*
X796850D03*
X790850D03*
X787850D03*
X793850D03*
X784850Y1559133D03*
Y1562133D03*
Y1565133D03*
X796850Y1559133D03*
Y1562133D03*
Y1565133D03*
X787850Y1559133D03*
Y1562133D03*
Y1565133D03*
X793850Y1559133D03*
X790850D03*
X793850Y1562133D03*
X790850D03*
X793850Y1565133D03*
X790850D03*
X799150Y1581379D03*
X784850Y1568133D03*
Y1571133D03*
X787850Y1568133D03*
Y1571133D03*
X793850Y1568133D03*
X790850D03*
X793850Y1571133D03*
X790850D03*
X791077Y1577233D03*
X785577D03*
X791077Y1582363D03*
X796650Y1583347D03*
X785577Y1587493D03*
X791077D03*
X791550Y1597533D03*
X785550Y1594533D03*
X788550D03*
X791550D03*
X785550Y1597533D03*
X788550D03*
X785550Y1600533D03*
X788550D03*
X791550D03*
Y1606533D03*
X788550D03*
X785550D03*
X791550Y1603533D03*
X788550D03*
X785550D03*
X803302Y265848D03*
X812867Y278860D03*
X810139Y274098D03*
X804330Y281380D03*
X801341Y279141D03*
X799935Y286823D03*
X799113Y297733D03*
X803893Y301969D03*
X805871Y304812D03*
X806461Y310610D03*
X808617Y330102D03*
X806117D03*
X812070Y341590D03*
X803410Y341572D03*
X803500Y366000D03*
X802660Y381020D03*
X802462Y387756D03*
X807564Y403805D03*
X811224Y395974D03*
X803412Y403978D03*
X813148Y403908D03*
X805425Y395502D03*
X813252Y427060D03*
X802270Y435372D03*
X802459Y443218D03*
X813208Y435344D03*
X812895Y449802D03*
X813114Y443344D03*
X802533Y449802D03*
X812983Y463578D03*
X813114Y459344D03*
X801552Y463318D03*
X802752Y459344D03*
X813114Y455344D03*
X812983Y471344D03*
Y476159D03*
X801874Y471344D03*
X802752Y480159D03*
X812983D03*
X813000Y484862D03*
X801762Y495344D03*
X802752Y487344D03*
X801753Y491344D03*
X813187Y498362D03*
X813114Y495344D03*
X802250Y500504D03*
X801857Y508031D03*
X805940Y534500D03*
X805341Y578059D03*
X805199Y620347D03*
X804863Y626789D03*
X805150Y623843D03*
X807451Y767299D03*
X807127Y770958D03*
X799280Y1296009D03*
X802030Y1296259D03*
X804530D03*
X807601Y1299241D03*
X799280Y1298509D03*
Y1301009D03*
X801614Y1339062D03*
X811771Y1355488D03*
X799071Y1350088D03*
X807866Y1369177D03*
X805366Y1367093D03*
X802866D03*
X807866Y1366677D03*
X808714Y1490376D03*
Y1487376D03*
Y1506784D03*
Y1519784D03*
Y1509784D03*
Y1516784D03*
X802150Y1570633D03*
Y1578633D03*
Y1582833D03*
X810150Y1574633D03*
X813150Y1579410D03*
Y1570633D03*
X810050Y1584033D03*
X802150Y1594633D03*
X810850Y1587733D03*
X810150Y1590633D03*
X813049D03*
X802700Y1587183D03*
X810150Y1602633D03*
Y1598633D03*
X802150Y1606633D03*
X819321Y56961D03*
X823115Y115223D03*
X820901Y147112D03*
X814571Y145952D03*
X814532Y139851D03*
X822635Y165468D03*
X825332Y166862D03*
X813676Y266065D03*
X823067Y273225D03*
X823038Y276301D03*
X819828Y288063D03*
X827621Y302962D03*
X822689Y305148D03*
X826915Y311842D03*
X822252Y309973D03*
X816232Y341584D03*
X818677Y356405D03*
X826765Y356334D03*
X817780Y366905D03*
X823778Y376378D03*
X818157Y381020D03*
X816991Y395337D03*
X820018Y403710D03*
X816281Y403814D03*
X828286Y401567D03*
X824653Y405347D03*
X817497Y415344D03*
X827341Y419344D03*
X817497D03*
X827341Y415344D03*
X817497Y427060D03*
X826474Y431344D03*
X816239Y435344D03*
X817497Y431060D03*
X826474Y435344D03*
X816117Y443552D03*
X816236Y439279D03*
X816109Y449802D03*
X822878Y446425D03*
X816109Y455344D03*
X816000Y463578D03*
X816170Y458524D03*
X826912Y475989D03*
X816109Y471344D03*
X816409Y467568D03*
X817393Y491594D03*
X830212Y483892D03*
X826472Y483896D03*
X827000Y489055D03*
X817996Y496219D03*
X828259Y501027D03*
X824380Y517595D03*
X827237Y550771D03*
X817849Y550871D03*
X820620Y550846D03*
X824366Y552444D03*
X827832Y554269D03*
X814489Y558082D03*
X825200Y580300D03*
X815287Y580401D03*
X820617Y641273D03*
X816732Y629198D03*
X815753Y644219D03*
X817900Y649012D03*
X822579Y760169D03*
X822218Y756979D03*
X822794Y767511D03*
X825390Y770020D03*
X822794Y777511D03*
X816550Y766871D03*
X822625Y763529D03*
X822794Y772511D03*
Y775011D03*
X825061Y764884D03*
X822864Y783262D03*
X822772Y788359D03*
X822790Y785838D03*
X822883Y780334D03*
X822982Y791245D03*
X822555Y807409D03*
X822794Y797511D03*
Y800011D03*
Y795011D03*
X822494Y802941D03*
X823927Y907676D03*
X823958Y936140D03*
X826958D03*
X823958Y939140D03*
X826958D03*
X827088Y933387D03*
X824036Y933394D03*
X826953Y930432D03*
X824003Y930319D03*
X828109Y1234504D03*
X826728Y1246315D03*
X824444Y1249420D03*
X828246Y1266501D03*
X824714Y1490376D03*
Y1487376D03*
X816690Y1490376D03*
Y1487376D03*
X824714Y1500376D03*
Y1497376D03*
Y1506784D03*
X816717Y1500388D03*
X816729Y1497364D03*
X816693Y1506784D03*
X824714Y1519784D03*
Y1509784D03*
Y1516784D03*
X816706Y1519820D03*
X816693Y1516784D03*
X816694Y1509796D03*
X824714Y1529784D03*
Y1526784D03*
X816714Y1529784D03*
Y1526784D03*
X823850Y1556133D03*
X820850D03*
X826850D03*
X820850Y1565133D03*
Y1562133D03*
Y1559133D03*
X826850Y1565133D03*
X823850D03*
X826850Y1562133D03*
Y1559133D03*
X823850Y1562133D03*
Y1559133D03*
X820850Y1571133D03*
Y1568133D03*
X826850Y1571133D03*
Y1568133D03*
X823850Y1571133D03*
Y1568133D03*
X821977Y1577233D03*
X827577D03*
X821977Y1582363D03*
X816150Y1587284D03*
X821977Y1587493D03*
X827577D03*
X821550Y1594533D03*
X827550Y1597533D03*
Y1594533D03*
X824550Y1597533D03*
Y1594533D03*
X821550Y1597533D03*
Y1600533D03*
X827550D03*
X824550D03*
X815550Y1606533D03*
X818550D03*
X821550Y1603533D03*
X818550D03*
X827550Y1606533D03*
X824550D03*
X821550D03*
X827550Y1603533D03*
X824550D03*
X842320Y11689D03*
Y8289D03*
X828601Y61752D03*
X836780Y68008D03*
X839899Y87248D03*
X841585Y94181D03*
X837251Y93221D03*
X839361Y114862D03*
X835115Y115223D03*
X845221Y135862D03*
Y129362D03*
X829115Y147123D03*
X838221Y163862D03*
X835221D03*
X842721Y181362D03*
X837161Y213207D03*
X844527Y204968D03*
X838821Y206872D03*
X837161Y218212D03*
X837501Y229642D03*
X836305Y268624D03*
X836181Y275686D03*
X830418Y311865D03*
X837754Y335345D03*
X829800Y331013D03*
X840457Y335368D03*
X842257Y350376D03*
X829344Y356224D03*
X833219Y375992D03*
X840357Y382813D03*
X833097Y393000D03*
X837912Y401545D03*
X834426Y401504D03*
X833000Y409500D03*
X838500D03*
X837847Y405347D03*
X833807Y423257D03*
X841809Y423219D03*
X838000Y423362D03*
X829106Y439279D03*
X842825Y448739D03*
X828979Y449802D03*
X834106Y439279D03*
X828714Y443552D03*
X833800Y444700D03*
X828751Y455344D03*
Y463578D03*
X834251Y455578D03*
X828751Y459344D03*
X832224Y450328D03*
X831381Y455167D03*
X833751Y463578D03*
X842825Y452739D03*
X828751Y471344D03*
Y467568D03*
X838575Y477554D03*
X839200Y467900D03*
X830046Y476031D03*
X838561Y484071D03*
X841854Y504972D03*
X833000Y503500D03*
X831798Y515314D03*
X838342Y514610D03*
X839061Y555808D03*
X841660Y558200D03*
X835519Y580056D03*
X831018Y583076D03*
X835059Y660940D03*
X837391Y659820D03*
X831505Y897291D03*
X831582Y905153D03*
X832347Y1251703D03*
X844250Y1266759D03*
X832274Y1277301D03*
X832342Y1274626D03*
X833756Y1330156D03*
X834017Y1336252D03*
X833963Y1339464D03*
X838963Y1345974D03*
X833853Y1345833D03*
X841039Y1358082D03*
X839244Y1352094D03*
X841472Y1365050D03*
X835850Y1556133D03*
X829850D03*
X832850D03*
X838850D03*
X832850Y1565133D03*
X835850D03*
X832850Y1562133D03*
X835850D03*
X832850Y1559133D03*
X835850D03*
X829850Y1565133D03*
Y1562133D03*
Y1559133D03*
X838850Y1565133D03*
Y1562133D03*
Y1559133D03*
X841150Y1581379D03*
X832850Y1571133D03*
X835850D03*
X832850Y1568133D03*
X835850D03*
X829850Y1571133D03*
Y1568133D03*
X833077Y1577233D03*
Y1582363D03*
X838650Y1583347D03*
X833077Y1587493D03*
X830550Y1597533D03*
X833550D03*
X830550Y1594533D03*
X833550D03*
X830550Y1600533D03*
X833550D03*
X830550Y1603533D03*
X836550Y1606533D03*
Y1603533D03*
X833550D03*
X830550Y1606533D03*
X833550D03*
X850016Y87341D03*
X843856Y87711D03*
X847473Y94754D03*
X854221Y135862D03*
Y129362D03*
X854201Y143062D03*
X848745Y160137D03*
X845721Y181362D03*
X856213Y191545D03*
X855859Y212425D03*
X855934Y215375D03*
X847581Y232222D03*
X853621Y269057D03*
X853829Y262057D03*
X846189Y281419D03*
X856244Y286447D03*
X843504Y287602D03*
X855481Y299692D03*
X860071Y304850D03*
X843308Y335550D03*
X857187Y342210D03*
X848030Y338461D03*
X850155Y335042D03*
X852303Y337488D03*
X852177Y341882D03*
X848425Y378089D03*
X854552Y381000D03*
X854190Y404035D03*
X855722Y416606D03*
X846000Y418862D03*
X854239Y412911D03*
X851517Y411745D03*
X846000Y423362D03*
X845986Y429413D03*
X857942Y448575D03*
X845100Y440100D03*
X857887Y459847D03*
X848500Y452128D03*
X847686Y475915D03*
X847303Y485788D03*
X846104Y494661D03*
X847518Y490905D03*
X846411Y482128D03*
X849772Y494585D03*
X852209Y507211D03*
X855497Y507205D03*
X849351Y499070D03*
X848097Y503315D03*
X855837Y519713D03*
X847941Y538325D03*
X845094Y535110D03*
X844741Y543864D03*
X843655Y555683D03*
X847435Y555496D03*
X856647Y616786D03*
X854484Y647436D03*
X848999Y644995D03*
X846931Y1291468D03*
X846895Y1295981D03*
X845801Y1287776D03*
X851500Y1302000D03*
X851400Y1305499D03*
X852811Y1313450D03*
X850684Y1310000D03*
X852955Y1320320D03*
X856500Y1321500D03*
X853100Y1331688D03*
X856500Y1330500D03*
X852780Y1338365D03*
X856500Y1339500D03*
Y1348500D03*
X844150Y1578633D03*
Y1570633D03*
Y1582833D03*
X852150Y1574633D03*
X855150Y1579410D03*
Y1570633D03*
X852050Y1584033D03*
X844150Y1594633D03*
X852850Y1587733D03*
X852150Y1590633D03*
X855049D03*
X844700Y1587183D03*
X852150Y1602633D03*
Y1598633D03*
X844150Y1606633D03*
X857550Y1606533D03*
X858630Y60293D03*
X863343Y90021D03*
X865912Y89252D03*
X870892Y131868D03*
X871145Y163862D03*
X875170Y185113D03*
X867529Y231788D03*
X863104Y273103D03*
X868104D03*
X867701Y267537D03*
X863230Y280001D03*
X866619Y286801D03*
X870672Y295485D03*
X870008Y302273D03*
X872508D03*
X871099Y323000D03*
X864342Y330858D03*
X860942D03*
X860587Y342210D03*
X860372Y375195D03*
X866168Y374774D03*
X871190Y382230D03*
X858925Y398537D03*
X864826Y411557D03*
X870220Y430424D03*
X870826Y423423D03*
X870064Y427703D03*
X859500Y429362D03*
X863420D03*
X859469Y425293D03*
X860541Y446089D03*
X860328Y475162D03*
X858288Y467048D03*
X860280Y488636D03*
X860299Y491620D03*
X864361Y493001D03*
X860508Y497772D03*
X862987Y507305D03*
X860341Y503154D03*
X860658Y515961D03*
X867356Y558714D03*
X867733Y575522D03*
X864590Y642420D03*
X870590D03*
X866727Y650739D03*
X866549Y748027D03*
X869275Y750472D03*
X873175D03*
X868496Y776516D03*
X868539Y790882D03*
X870591Y785437D03*
X865466Y790581D03*
Y785581D03*
Y788081D03*
Y783081D03*
X865394Y801244D03*
X865466Y793081D03*
Y795581D03*
Y798081D03*
X865569Y806045D03*
Y808545D03*
X863369Y827461D03*
X863344Y824713D03*
X863372Y833469D03*
Y830718D03*
X867651Y836820D03*
X867646Y833388D03*
X863671Y839062D03*
X865601Y841219D03*
X865109Y850795D03*
X864768Y844815D03*
X864140Y856052D03*
X864020Y859972D03*
X864106Y863534D03*
X864003Y866609D03*
X866005Y941554D03*
X863055Y941441D03*
X863010Y947262D03*
X866010D03*
X863010Y950262D03*
X866010D03*
X866140Y944509D03*
X863088Y944516D03*
X862044Y1249687D03*
X866294Y1255903D03*
X874989Y1410441D03*
X863745Y1444560D03*
X871214Y1466542D03*
X865850Y1556133D03*
X871850D03*
X862850D03*
X868850D03*
X865850Y1565133D03*
Y1562133D03*
Y1559133D03*
X862850Y1565133D03*
Y1562133D03*
Y1559133D03*
X868850Y1565133D03*
X871850D03*
X868850Y1562133D03*
X871850D03*
X868850Y1559133D03*
X871850D03*
X865850Y1571133D03*
Y1568133D03*
X862850Y1571133D03*
Y1568133D03*
X868850Y1571133D03*
X871850D03*
X868850Y1568133D03*
X871850D03*
X863977Y1577233D03*
Y1582363D03*
X869577Y1577233D03*
X858150Y1587284D03*
X863977Y1587493D03*
X869577D03*
X863550Y1597533D03*
X866550Y1594533D03*
Y1597533D03*
X869550Y1594533D03*
Y1597533D03*
X863550Y1594533D03*
X872550D03*
Y1597533D03*
X866550Y1600533D03*
X869550D03*
X863550D03*
X872550D03*
Y1606533D03*
Y1603533D03*
X863550Y1606533D03*
X866550D03*
X869550D03*
X860550D03*
X869550Y1603533D03*
X866550D03*
X863550D03*
X860550D03*
X876696Y176862D03*
Y171362D03*
X887521D03*
Y176862D03*
X889351Y195489D03*
X878328Y183169D03*
X878221Y187449D03*
X887130Y183169D03*
X884986Y198829D03*
X881354Y267407D03*
X884004Y278712D03*
Y274482D03*
X885764Y284361D03*
X877448Y284825D03*
X884004Y271332D03*
X874244Y287047D03*
X873172Y295485D03*
X888000Y293000D03*
X877640Y315789D03*
X873884Y447991D03*
Y450491D03*
X885916Y653912D03*
X883731Y651690D03*
X884410Y794332D03*
X883633Y790336D03*
X883776Y786814D03*
X877459Y802356D03*
X875412Y797350D03*
X882582Y1075083D03*
X879582D03*
X876582D03*
X873582D03*
X882582Y1061983D03*
X879582D03*
X876582D03*
Y1071533D03*
Y1068533D03*
Y1065533D03*
X873582D03*
Y1068533D03*
Y1071533D03*
Y1061983D03*
X886707Y1229920D03*
Y1232920D03*
X881807Y1238920D03*
X876923Y1239520D03*
X886707Y1235920D03*
X881694Y1229763D03*
Y1232763D03*
Y1235763D03*
X876907Y1235586D03*
Y1232586D03*
Y1229586D03*
X881807Y1241920D03*
X877936Y1312336D03*
X883379Y1417881D03*
X875039Y1407246D03*
X886362Y1428973D03*
X884399Y1431507D03*
X879424Y1425001D03*
X883279Y1421726D03*
X883562Y1440356D03*
X881987Y1449608D03*
X887519Y1444625D03*
X877226Y1441585D03*
X887117Y1436735D03*
X877850Y1556133D03*
X874850D03*
X880850D03*
X874850Y1565133D03*
X877850D03*
X880850D03*
X874850Y1562133D03*
X877850D03*
X880850D03*
X874850Y1559133D03*
X877850D03*
X880850D03*
X886150Y1578633D03*
Y1570633D03*
Y1582833D03*
X883150Y1581379D03*
X874850Y1571133D03*
X877850D03*
X874850Y1568133D03*
X877850D03*
X875077Y1577233D03*
Y1582363D03*
X886150Y1594633D03*
X880650Y1583347D03*
X886700Y1587183D03*
X875077Y1587493D03*
X875550Y1597533D03*
Y1594533D03*
X886150Y1606633D03*
X875550Y1600533D03*
Y1606533D03*
X878550D03*
Y1603533D03*
X875550D03*
X891621Y207162D03*
X888930Y206823D03*
X891621Y209662D03*
X888930Y209323D03*
X896621Y207162D03*
X894121D03*
Y209662D03*
X896621D03*
X892376Y466430D03*
X899000Y481038D03*
X888372Y547518D03*
X902376Y590172D03*
X900323Y604377D03*
X900301Y828248D03*
Y831221D03*
X899500Y853000D03*
X901000Y909000D03*
X901842Y936863D03*
X903925Y948500D03*
X889273Y1134470D03*
X902382Y1137558D03*
X891996Y1149707D03*
X900280Y1150769D03*
X902482Y1140558D03*
X888247Y1219520D03*
Y1222520D03*
X891247D03*
Y1219520D03*
X888247Y1225520D03*
X896974Y1232869D03*
Y1235869D03*
X896907Y1238920D03*
X896974Y1229869D03*
X891247Y1225520D03*
X896907Y1241920D03*
X892000Y1307500D03*
X888854Y1337936D03*
X890620Y1342990D03*
X900885Y1435041D03*
X900808Y1437798D03*
X902377Y1456465D03*
X904850Y1556133D03*
X894150Y1574633D03*
X897150Y1579410D03*
Y1570633D03*
X894050Y1584033D03*
X894150Y1590633D03*
X894850Y1587733D03*
X897049Y1590633D03*
X900150Y1587284D03*
X894150Y1602633D03*
Y1598633D03*
X899550Y1606533D03*
X902550Y1603533D03*
Y1606533D03*
X917387Y184114D03*
X908621Y188899D03*
X910267Y242658D03*
X910093Y246015D03*
X916268Y269859D03*
X909023Y294734D03*
X910752Y286141D03*
X913512Y486743D03*
X903340Y505105D03*
X917582Y549564D03*
X909747Y579695D03*
X911980Y585280D03*
X910731Y590251D03*
X905526Y594657D03*
X910535Y619251D03*
X906706Y614062D03*
X909747Y628426D03*
X915334Y639166D03*
X908823Y655116D03*
X906274Y654921D03*
X909320Y663930D03*
X907207Y667646D03*
X906345Y742414D03*
X904535Y744639D03*
X906387Y821221D03*
Y815721D03*
X906313Y825095D03*
X903149Y825094D03*
X917000Y853000D03*
X907000Y899777D03*
X913000Y909000D03*
X917000D03*
Y918500D03*
X905000D03*
X915575Y948500D03*
X910000Y954500D03*
X912425Y948500D03*
X907075D03*
X910000Y957500D03*
X912500Y963309D03*
X907500D03*
X909000Y974000D03*
Y982000D03*
X911041Y979459D03*
X909000Y977491D03*
X919779Y1155658D03*
X915053Y1219520D03*
Y1222520D03*
X912053D03*
Y1219520D03*
Y1225520D03*
X915053D03*
X910707Y1229920D03*
Y1232920D03*
X905007Y1238920D03*
X910707Y1235920D03*
X905008Y1229940D03*
Y1232940D03*
Y1235940D03*
X905007Y1241920D03*
X917112Y1266300D03*
X917127Y1275251D03*
X917396Y1271025D03*
X917158Y1279451D03*
X917341Y1283775D03*
X916895Y1292330D03*
X916945Y1296713D03*
X917034Y1288235D03*
X912500Y1310000D03*
X914333Y1322700D03*
X914462Y1329351D03*
X914355Y1340726D03*
X914276Y1347550D03*
X913270Y1440429D03*
X910041Y1440536D03*
X907031Y1457231D03*
X909473Y1448779D03*
X910850Y1556133D03*
X907850D03*
X916850D03*
X913850D03*
X907850Y1559133D03*
Y1562133D03*
X910850Y1559133D03*
Y1562133D03*
X907850Y1565133D03*
X910850D03*
X904850Y1559133D03*
Y1562133D03*
Y1565133D03*
X913850Y1559133D03*
Y1562133D03*
Y1565133D03*
X916850Y1559133D03*
Y1562133D03*
Y1565133D03*
X907850Y1568133D03*
Y1571133D03*
X910850Y1568133D03*
Y1571133D03*
X904850Y1568133D03*
Y1571133D03*
X913850Y1568133D03*
Y1571133D03*
X916850Y1568133D03*
Y1571133D03*
X905977Y1577233D03*
Y1582363D03*
X911577Y1577233D03*
X917077D03*
Y1582363D03*
X905977Y1587493D03*
X911577D03*
X917077D03*
X914550Y1597533D03*
Y1594533D03*
X905550D03*
X911550Y1597533D03*
Y1594533D03*
X908550Y1597533D03*
Y1594533D03*
X905550Y1597533D03*
X917550D03*
Y1594533D03*
X914550Y1600533D03*
X905550D03*
X911550D03*
X908550D03*
X917550D03*
X914550Y1603533D03*
Y1606533D03*
X905550Y1603533D03*
X908550D03*
X911550D03*
Y1606533D03*
X908550D03*
X905550D03*
X917550Y1603533D03*
Y1606533D03*
X915991Y1667328D03*
X922128Y182486D03*
X923386Y193563D03*
X932129Y244103D03*
X922341Y263875D03*
X923103Y362852D03*
X924724Y372211D03*
X919294Y374503D03*
X921318Y372475D03*
X920018Y362877D03*
X921430Y507156D03*
X921367Y503407D03*
X924430Y507156D03*
X924367Y503407D03*
X922591Y496671D03*
X926730Y540897D03*
X921318Y549357D03*
X920031Y577846D03*
X926449Y577806D03*
X930406Y577308D03*
X923747Y584945D03*
X920989Y614132D03*
X925643Y616620D03*
X920989Y617692D03*
X924987Y622523D03*
X932000Y850500D03*
X920234Y843349D03*
X927777Y843416D03*
X930575Y864075D03*
X918500Y860075D03*
X920897Y881879D03*
X929603Y879000D03*
X920000Y895500D03*
X923000D03*
X925500Y907500D03*
X921000Y921925D03*
X925500Y916500D03*
X929500D03*
X932500Y941500D03*
X919500D03*
X928500D03*
X923500D03*
X926000Y949500D03*
Y946500D03*
X919272Y986782D03*
X920107Y1235920D03*
Y1232920D03*
Y1238920D03*
Y1229920D03*
Y1241920D03*
X924500Y1306000D03*
Y1302000D03*
X918000Y1312500D03*
Y1321500D03*
X925459Y1315352D03*
X925500Y1319000D03*
X922000Y1324000D03*
Y1328000D03*
X931326Y1328467D03*
X931216Y1323050D03*
X918000Y1330500D03*
Y1339500D03*
X922000Y1342000D03*
X925500Y1333000D03*
Y1337000D03*
X922000Y1346000D03*
X922850Y1556133D03*
X919850D03*
X922850Y1559133D03*
Y1562133D03*
Y1565133D03*
X919850Y1559133D03*
Y1562133D03*
Y1565133D03*
X925650Y1581379D03*
X919850Y1568133D03*
Y1571133D03*
X922650Y1583347D03*
X920550Y1603533D03*
Y1606533D03*
X921289Y1666337D03*
X927798Y1660762D03*
X945721Y173389D03*
X943221D03*
Y176389D03*
X945721D03*
X935551Y173329D03*
X938161Y173389D03*
Y176389D03*
X935591Y176049D03*
X940721Y173389D03*
Y176389D03*
X939271Y191419D03*
X935771D03*
X944520Y182094D03*
X936454Y184015D03*
X937267Y189010D03*
X945120Y193264D03*
X938570Y233152D03*
X945380Y233962D03*
X949181Y280131D03*
X939938Y386423D03*
X933390Y386405D03*
X944112Y386593D03*
X941764Y420403D03*
X944264D03*
X933390Y559943D03*
X939613Y562031D03*
X937310Y580755D03*
X941764Y587884D03*
X944264D03*
X935766Y587692D03*
X939511Y597073D03*
X935746Y611573D03*
X935783Y631192D03*
X937580Y655946D03*
X945602Y664653D03*
X934539Y664648D03*
X934339Y668533D03*
X941478Y668648D03*
X939216Y664767D03*
X948644Y811190D03*
X938000Y862620D03*
X943000Y862823D03*
X934925Y891425D03*
X945075Y891500D03*
X938500Y907500D03*
X946500Y915988D03*
X938500Y916500D03*
X934500D03*
X942500Y916340D03*
X942631Y943162D03*
X936960Y942898D03*
X935368Y939182D03*
X944515Y939850D03*
X940000Y973500D03*
Y986500D03*
Y982500D03*
Y977500D03*
X937148Y1134343D03*
X933234Y1145058D03*
X936393Y1148087D03*
X947305Y1150769D03*
X943101Y1219520D03*
Y1222520D03*
X946101D03*
Y1219520D03*
X943101Y1225520D03*
X946101D03*
X945691Y1229920D03*
Y1232920D03*
X940791Y1238920D03*
X935907Y1239520D03*
X945691Y1235920D03*
X940678Y1229763D03*
Y1232763D03*
Y1235763D03*
X935891Y1235586D03*
Y1232586D03*
Y1229586D03*
X940791Y1241920D03*
X940994Y1265636D03*
X941011Y1269499D03*
X941500Y1278059D03*
X941033Y1282115D03*
X946730Y1293219D03*
Y1290719D03*
X940919Y1290152D03*
X940937Y1294191D03*
X941083Y1286156D03*
X947135Y1287403D03*
X945872Y1304541D03*
Y1301500D03*
X945617Y1309500D03*
X935028Y1313769D03*
X935300Y1317525D03*
X939071Y1448219D03*
X949216Y1448337D03*
X944105Y1448317D03*
X946402Y1491204D03*
X943902D03*
X936402D03*
X938902D03*
X941402D03*
X933778D03*
X946402Y1501204D03*
Y1498704D03*
Y1496204D03*
Y1493704D03*
X943902D03*
Y1496204D03*
Y1498704D03*
Y1501204D03*
X936402Y1493704D03*
Y1496204D03*
Y1498704D03*
Y1501204D03*
X938902Y1493704D03*
Y1496204D03*
Y1498704D03*
Y1501204D03*
X941402Y1493704D03*
Y1496204D03*
Y1498704D03*
Y1501204D03*
X933778Y1493704D03*
Y1496204D03*
Y1498704D03*
Y1501204D03*
X936150Y1582233D03*
Y1578233D03*
Y1590233D03*
Y1586233D03*
X943798Y1660762D03*
X948401Y176499D03*
X961407Y205125D03*
X950950Y284662D03*
X947821Y386567D03*
X958158Y449020D03*
X958049Y453912D03*
X958101Y457846D03*
X958255Y465811D03*
X959033Y487289D03*
X957380Y515233D03*
X960054Y516982D03*
X962035Y518988D03*
X954757Y593045D03*
X948156Y593912D03*
X952497Y614080D03*
X951102Y628662D03*
X954362Y633314D03*
Y630061D03*
X954259Y657371D03*
X958299Y659886D03*
X954361Y660215D03*
X957462Y668700D03*
X951886Y804495D03*
X951895Y808163D03*
X951466Y816400D03*
X961592Y821737D03*
X949000Y850500D03*
X951000Y855425D03*
X958000Y865500D03*
Y862000D03*
X949500Y870500D03*
Y886500D03*
X953925Y900500D03*
X951169Y910425D03*
X957075Y906500D03*
X960925D03*
X954500Y915988D03*
X950500Y916150D03*
X948500Y937000D03*
X949407Y1137558D03*
X949507Y1140558D03*
X955958Y1232869D03*
Y1235869D03*
X955891Y1238920D03*
X955958Y1229869D03*
X955891Y1241920D03*
X964669Y1271000D03*
X963500Y1275000D03*
X955000Y1283000D03*
Y1287000D03*
X947650Y1314500D03*
Y1319000D03*
Y1323500D03*
Y1328000D03*
Y1337000D03*
Y1332500D03*
Y1341500D03*
Y1346000D03*
X960313Y1362654D03*
X958306Y1448056D03*
X954541Y1448307D03*
X961566Y1448341D03*
X953902Y1491204D03*
X951402D03*
X948902D03*
X956402D03*
X958902D03*
X961402D03*
X953902Y1501204D03*
Y1498704D03*
Y1496204D03*
Y1493704D03*
X951402Y1501204D03*
Y1498704D03*
Y1496204D03*
Y1493704D03*
X948902Y1501204D03*
Y1498704D03*
Y1496204D03*
Y1493704D03*
X956402D03*
X958902D03*
X961402D03*
X963402Y1501204D03*
X958402D03*
X959584Y1550824D03*
X949195Y1655145D03*
X951798Y1660762D03*
X975691Y161220D03*
X962673Y170263D03*
Y167763D03*
X967943Y204813D03*
X971943D03*
X975749Y202049D03*
X977221Y205399D03*
X964807Y205125D03*
X973997Y320848D03*
X966278Y556736D03*
X964114Y554704D03*
X976528Y801041D03*
Y803541D03*
Y806041D03*
Y808541D03*
X963500Y854719D03*
X973562Y859767D03*
X964075Y900500D03*
X966804Y1155658D03*
X969907Y1219520D03*
Y1222520D03*
X966907D03*
Y1219520D03*
Y1225520D03*
X969907D03*
X969691Y1229920D03*
Y1232920D03*
X963991Y1238920D03*
X969691Y1235920D03*
X963992Y1229940D03*
Y1232940D03*
Y1235940D03*
X979091Y1229920D03*
X963991Y1241920D03*
X964000Y1267000D03*
X966441Y1278145D03*
X972408Y1312557D03*
X973650Y1431424D03*
X969785Y1447987D03*
X967002Y1448013D03*
X964503Y1448097D03*
X969519Y1452784D03*
X973255Y1456714D03*
X975703Y1451367D03*
X967268Y1491204D03*
X969768D03*
X972268D03*
X974768D03*
X977268D03*
X963902D03*
X967268Y1501204D03*
Y1498704D03*
Y1496204D03*
Y1493704D03*
X969768D03*
Y1496204D03*
Y1498704D03*
Y1501204D03*
X972268Y1493704D03*
Y1496204D03*
Y1498704D03*
Y1501204D03*
X974768Y1493704D03*
Y1496204D03*
Y1498704D03*
Y1501204D03*
X977268Y1493704D03*
Y1496204D03*
Y1498704D03*
Y1501204D03*
X963902Y1493704D03*
X962584Y1550824D03*
X990579Y155248D03*
X981112Y161204D03*
X988751Y167541D03*
X986447Y158209D03*
X989605Y175400D03*
X985922Y171861D03*
X985445Y185389D03*
X986021Y195099D03*
X979849Y202049D03*
X983879Y202162D03*
X990221Y199699D03*
X987321Y198599D03*
Y202099D03*
X990221Y206699D03*
Y203199D03*
X987321Y205599D03*
X980406Y218283D03*
X980377Y215740D03*
X978269Y264929D03*
X982455Y260781D03*
Y271443D03*
X978827Y303412D03*
X984509Y303623D03*
X989582Y303563D03*
X988460Y358405D03*
X993460D03*
X984272Y349293D03*
X980346Y353527D03*
X981019Y349387D03*
X992460Y370659D03*
X985668Y389311D03*
X980690Y387784D03*
X984605Y408480D03*
X987581Y408332D03*
X988190Y424626D03*
X983358Y449026D03*
X991664Y446372D03*
X993650Y465315D03*
X988650D03*
X991270Y470212D03*
X990292Y494420D03*
X988125Y485193D03*
X986790Y480140D03*
X987440Y504742D03*
X982806Y498606D03*
X986056Y516014D03*
X994056Y521014D03*
Y516014D03*
Y526074D03*
Y531074D03*
X992125Y1061434D03*
X989125D03*
X986125D03*
X983125D03*
X992125Y1064984D03*
Y1067984D03*
X989125D03*
Y1064984D03*
X992125Y1074534D03*
Y1070984D03*
X989125D03*
Y1074534D03*
X986125D03*
X983125D03*
X979091Y1235920D03*
Y1232920D03*
Y1238920D03*
Y1241920D03*
X985396Y1268154D03*
X982665Y1265474D03*
X978318Y1263128D03*
X988242Y1273193D03*
X979228Y1297918D03*
X982000Y1307500D03*
X978026Y1459998D03*
X980779Y1451545D03*
X990634Y1491204D03*
X979768D03*
X982268D03*
X984768D03*
X987268D03*
X990634Y1493704D03*
Y1496204D03*
Y1498704D03*
Y1501204D03*
X979768Y1493704D03*
X982268D03*
X984768D03*
X987268D03*
X986768Y1501204D03*
X981768D03*
X991196Y1550840D03*
X1006221Y164799D03*
X1002721D03*
X1005307Y155043D03*
X995181Y157689D03*
X999580Y154895D03*
X994257D03*
X996416Y176579D03*
X1002921Y178799D03*
X1002827Y172479D03*
X999221Y189299D03*
X1002721D03*
X1006161Y189019D03*
X1008918Y192994D03*
X1008121Y203525D03*
X1000611Y215039D03*
X1005641Y214969D03*
X1001196Y223898D03*
X1008707Y230423D03*
X997300Y234876D03*
X1006468Y301857D03*
X1003460Y358405D03*
X998460D03*
X994409Y349813D03*
X1000460Y369535D03*
X996889Y374156D03*
X1007080Y367087D03*
X999320Y394480D03*
X1006763Y396206D03*
X1003651Y433426D03*
X998859Y437141D03*
X998359Y451675D03*
X994900Y446192D03*
X998359Y462675D03*
Y457175D03*
X1003909Y454662D03*
Y460162D03*
X998359Y479175D03*
Y468175D03*
Y473675D03*
X996320Y470364D03*
X998359Y484675D03*
X1007077Y484937D03*
X998326Y499675D03*
X995530Y500034D03*
X1006206Y510304D03*
X1002056Y521014D03*
Y516014D03*
Y526074D03*
Y531074D03*
X1004527Y541924D03*
Y553224D03*
X1005270Y625710D03*
X1003090Y1037329D03*
X999350Y1310500D03*
Y1315000D03*
Y1319420D03*
Y1323840D03*
Y1328260D03*
Y1332740D03*
Y1341580D03*
Y1337160D03*
Y1346000D03*
X995500Y1368000D03*
X998000Y1365500D03*
X995000Y1362000D03*
X1000634Y1491204D03*
X998134D03*
X995634D03*
X993134D03*
X1003134D03*
X1005634D03*
X993134Y1496204D03*
Y1493704D03*
X1003134D03*
X1005634D03*
X1000634Y1501204D03*
Y1498704D03*
Y1496204D03*
Y1493704D03*
X998134Y1501204D03*
Y1498704D03*
Y1496204D03*
Y1493704D03*
X995634Y1501204D03*
Y1498704D03*
Y1496204D03*
Y1493704D03*
X993134Y1501204D03*
Y1498704D03*
X1005134Y1501204D03*
X994196Y1550840D03*
X1009721Y164799D03*
X1013221D03*
X1014301Y179699D03*
X1017201D03*
X1019901Y179799D03*
X1011991Y189019D03*
X1014901Y189299D03*
X1017701Y189059D03*
X1011120Y198114D03*
X1020521Y194499D03*
X1011068Y207667D03*
X1021440Y226423D03*
X1019356Y222423D03*
X1010909Y213708D03*
X1011721Y233699D03*
X1019531Y230423D03*
X1018220Y243638D03*
X1015220D03*
X1009220D03*
X1014828Y268427D03*
Y258970D03*
X1013396Y280806D03*
X1011423Y282889D03*
X1023110Y287311D03*
X1017835Y291236D03*
X1023000Y298311D03*
X1016764Y350082D03*
X1010252Y363440D03*
X1009815Y404896D03*
X1020748Y420902D03*
Y425902D03*
X1023420Y462921D03*
X1017220Y464155D03*
X1023515Y454397D03*
X1019205Y457687D03*
X1023420Y468039D03*
X1017350Y472155D03*
X1022874Y474545D03*
X1019210Y480155D03*
X1013306Y518146D03*
Y532501D03*
X1017718Y541201D03*
X1019161Y554757D03*
X1024161D03*
X1017961Y545074D03*
X1009611Y550074D03*
Y545074D03*
X1021425Y568614D03*
X1012925Y558000D03*
X1011602Y568473D03*
X1016000Y563107D03*
X1019261Y571324D03*
X1007587Y761546D03*
Y772480D03*
Y775880D03*
Y764946D03*
Y783482D03*
Y786882D03*
Y794484D03*
Y797884D03*
X1016000Y1303000D03*
X1009905Y1305500D03*
X1009896Y1301500D03*
X1013605Y1316050D03*
X1013529Y1318950D03*
X1012500Y1322500D03*
Y1328500D03*
Y1341580D03*
X1013500Y1332740D03*
Y1337160D03*
X1016000Y1361000D03*
X1012500Y1347500D03*
X1021500Y1491204D03*
X1019000D03*
X1016500D03*
X1014000D03*
X1008134D03*
X1010634D03*
X1021500Y1501204D03*
Y1498704D03*
Y1496204D03*
Y1493704D03*
X1019000Y1501204D03*
Y1498704D03*
Y1496204D03*
Y1493704D03*
X1016500Y1501204D03*
Y1498704D03*
Y1496204D03*
Y1493704D03*
X1014000D03*
Y1496204D03*
Y1498704D03*
Y1501204D03*
X1008134Y1493704D03*
X1010634D03*
X1010134Y1501204D03*
X1022796Y1550840D03*
X1022801Y179799D03*
X1027690Y237902D03*
X1024220Y243638D03*
X1033590Y298311D03*
Y287311D03*
X1029200Y351614D03*
X1022674Y357848D03*
X1028146Y355960D03*
X1034214Y351601D03*
X1029601Y394387D03*
X1034855Y411704D03*
X1034409Y429618D03*
X1024443Y424051D03*
X1039015Y444404D03*
X1034899D03*
X1025830Y449022D03*
X1023320Y451112D03*
X1035860Y485976D03*
X1027504Y485637D03*
X1024509Y500168D03*
X1024546Y511254D03*
X1037254Y521014D03*
X1036708Y514883D03*
X1037254Y526074D03*
X1025631Y540104D03*
X1036021Y534990D03*
X1030000Y554500D03*
X1034412Y567416D03*
X1031000Y568500D03*
X1028500Y563000D03*
X1024000D03*
X1029431Y587342D03*
X1032055Y587260D03*
X1028540Y621000D03*
X1035269Y735474D03*
X1032736Y735320D03*
X1030190Y735023D03*
X1025493Y761819D03*
X1035026Y756009D03*
X1036427Y770532D03*
X1038867Y774960D03*
X1025493Y765719D03*
X1033236Y1279287D03*
X1033184Y1275996D03*
X1036411Y1275658D03*
X1036463Y1278949D03*
X1024000Y1491204D03*
X1026500D03*
X1029000D03*
X1031500D03*
X1034000D03*
X1024000Y1501204D03*
Y1498704D03*
Y1496204D03*
Y1493704D03*
X1026500D03*
X1029000D03*
X1031500D03*
X1034000D03*
X1033500Y1501204D03*
X1028500D03*
X1025796Y1550840D03*
X1046384Y269814D03*
X1049451Y266747D03*
X1040060Y313528D03*
X1051873Y305482D03*
X1049573Y406586D03*
X1042015Y444404D03*
X1047515D03*
X1043377Y452740D03*
X1040836Y510894D03*
X1045254Y516014D03*
Y534074D03*
Y526074D03*
X1043991Y540979D03*
X1047335Y549574D03*
X1047200Y543090D03*
X1037301Y539685D03*
X1039407Y547723D03*
X1039000Y555000D03*
X1039718Y563268D03*
X1042628Y556845D03*
X1050956Y591090D03*
X1040626Y668441D03*
X1042389Y733426D03*
X1044056Y736188D03*
X1040915Y766870D03*
X1037566Y1047135D03*
X1037895Y1251517D03*
X1039546Y1275474D03*
X1039598Y1278765D03*
X1042855Y1275552D03*
X1042649Y1279152D03*
X1047366Y1491204D03*
X1044866D03*
X1037366D03*
X1042366D03*
X1039866D03*
X1049866D03*
X1047366Y1498704D03*
Y1496204D03*
Y1493704D03*
X1044866Y1496204D03*
Y1493704D03*
X1037366D03*
Y1496204D03*
Y1498704D03*
X1047366Y1501204D03*
X1044866D03*
Y1498704D03*
X1042366Y1501204D03*
Y1498704D03*
Y1496204D03*
Y1493704D03*
X1039866Y1501204D03*
Y1498704D03*
Y1496204D03*
Y1493704D03*
X1037366Y1501204D03*
X1049866Y1493704D03*
X1051866Y1501204D03*
X1053290Y1652082D03*
X1045545Y1663089D03*
X1066231Y165078D03*
Y167578D03*
X1062704Y270875D03*
X1056941Y259176D03*
X1054613Y261586D03*
X1062923Y295053D03*
X1063356Y318297D03*
X1055934Y388988D03*
X1068143Y380188D03*
X1055934Y381988D03*
X1052505Y406576D03*
X1057798Y427059D03*
Y429618D03*
X1062642Y444859D03*
X1062640Y449155D03*
X1062741Y457959D03*
X1057276Y458155D03*
X1062173Y479655D03*
X1062873Y490180D03*
X1055905Y492537D03*
X1062250Y484672D03*
X1056960Y482262D03*
X1057450Y509242D03*
X1058231Y523238D03*
X1060719Y512359D03*
Y516059D03*
X1061817Y736362D03*
X1065154Y736282D03*
X1057057Y767299D03*
Y771099D03*
X1055171Y1307203D03*
Y1311203D03*
X1058143Y1433809D03*
X1065732Y1491204D03*
X1063232D03*
X1060732D03*
X1052366D03*
X1054866D03*
X1057366D03*
X1065732Y1501204D03*
Y1498704D03*
Y1496204D03*
Y1493704D03*
X1063232Y1501204D03*
Y1498704D03*
Y1496204D03*
Y1493704D03*
X1060732D03*
Y1496204D03*
Y1498704D03*
Y1501204D03*
X1052366Y1493704D03*
X1054866D03*
X1057366D03*
X1056866Y1501204D03*
X1057396Y1550840D03*
X1054396D03*
X1071698Y270702D03*
X1078823Y269400D03*
X1071656Y366726D03*
X1078400Y391226D03*
X1074654Y380188D03*
X1078400Y383226D03*
X1074249Y387795D03*
X1082866Y403068D03*
X1074736Y396929D03*
X1072135Y396908D03*
X1072738Y411322D03*
Y416763D03*
Y421922D03*
X1072673Y428791D03*
X1077873Y463444D03*
X1080453Y457959D03*
X1071470Y475525D03*
X1080640Y467000D03*
X1080574Y471500D03*
X1071667D03*
Y467000D03*
X1080416Y482772D03*
X1080420Y487782D03*
X1071710Y483655D03*
Y488782D03*
X1081730Y509172D03*
X1078499Y648202D03*
X1072232Y667749D03*
X1068378Y736795D03*
X1070616Y766870D03*
X1076903Y1300361D03*
Y1302861D03*
X1079403D03*
Y1300361D03*
X1074403Y1302861D03*
Y1300361D03*
X1076903Y1305361D03*
X1079403D03*
X1074403D03*
Y1307861D03*
Y1310361D03*
Y1312861D03*
X1079403Y1307861D03*
Y1310361D03*
Y1312861D03*
X1076903D03*
Y1310361D03*
Y1307861D03*
X1079403Y1315361D03*
X1076903D03*
Y1317861D03*
X1079403D03*
X1074403D03*
Y1315361D03*
X1069839Y1368999D03*
Y1371540D03*
X1076601Y1382574D03*
X1071332Y1379914D03*
X1076601Y1380066D03*
X1080555Y1380511D03*
X1073612Y1376389D03*
X1081005Y1425458D03*
X1071117Y1445005D03*
X1077031Y1451498D03*
X1070312Y1452028D03*
X1073307Y1451931D03*
X1070732Y1491204D03*
X1068232D03*
X1073232D03*
X1075732D03*
X1078232D03*
X1080732D03*
X1070732Y1501204D03*
Y1498704D03*
Y1496204D03*
Y1493704D03*
X1068232Y1501204D03*
Y1498704D03*
Y1496204D03*
Y1493704D03*
X1073232D03*
X1075732D03*
X1078232D03*
X1080732D03*
X1080232Y1501204D03*
X1075232D03*
X1072134Y1647920D03*
X1081011Y1685499D03*
X1078011D03*
X1081011Y1682499D03*
X1078011D03*
X1077172Y1676686D03*
X1077881Y1688252D03*
X1080933Y1688245D03*
X1078016Y1691207D03*
X1080966Y1691320D03*
X1087421Y149716D03*
X1086714Y353515D03*
X1090086Y370417D03*
X1090061Y428019D03*
X1087963Y440605D03*
Y446105D03*
X1084840Y438234D03*
Y443515D03*
X1087963Y462605D03*
Y457105D03*
X1087940Y452110D03*
X1084840Y460005D03*
X1085851Y465978D03*
X1087963Y468105D03*
X1095448Y479426D03*
X1084000Y477500D03*
X1090000D03*
X1087963Y484605D03*
Y494641D03*
Y489641D03*
X1083434Y481500D03*
X1085730Y509362D03*
X1091730D03*
X1095730D03*
X1082622Y520652D03*
X1082438Y524033D03*
X1085438D03*
X1085622Y520652D03*
X1083281Y651601D03*
X1091270Y668286D03*
X1086758Y767299D03*
Y771099D03*
X1090203Y1307861D03*
Y1310361D03*
Y1312861D03*
X1092703D03*
Y1310361D03*
Y1307861D03*
Y1300361D03*
Y1302861D03*
X1090203D03*
Y1300361D03*
X1095203Y1302861D03*
Y1300361D03*
X1092703Y1305361D03*
X1090203D03*
X1095203D03*
Y1307861D03*
Y1310361D03*
Y1312861D03*
X1090203Y1315361D03*
X1092703D03*
Y1317861D03*
X1090203D03*
X1095203D03*
Y1315361D03*
X1087059Y1372853D03*
X1089489D03*
X1091919D03*
X1092889Y1367278D03*
Y1370178D03*
X1084043Y1382111D03*
X1083293Y1379543D03*
X1094683Y1379188D03*
Y1376288D03*
X1091598Y1491204D03*
X1089098D03*
X1086598D03*
X1084098D03*
X1091598Y1501204D03*
Y1498704D03*
Y1496204D03*
Y1493704D03*
X1089098Y1501204D03*
Y1498704D03*
Y1496204D03*
Y1493704D03*
X1086598Y1501204D03*
Y1498704D03*
Y1496204D03*
Y1493704D03*
X1084098D03*
Y1498704D03*
Y1501204D03*
Y1496204D03*
X1089934Y1550784D03*
X1092934D03*
X1097000Y1629500D03*
X1096500Y1639000D03*
X1096768Y1635080D03*
X1090958Y1646528D03*
Y1649928D03*
X1084629Y1673002D03*
X1087141Y1688914D03*
X1092980Y1699179D03*
X1089030Y1717841D03*
Y1722841D03*
X1099500Y318000D03*
X1111001Y361272D03*
X1107300Y456944D03*
X1111076Y464388D03*
X1108076Y646774D03*
X1104443Y646983D03*
X1100316Y766870D03*
X1109503Y1302861D03*
X1107003D03*
Y1300361D03*
X1109503Y1305361D03*
X1107003D03*
Y1307861D03*
Y1310361D03*
Y1312861D03*
X1109503Y1307861D03*
Y1310361D03*
Y1312861D03*
Y1300361D03*
Y1315361D03*
Y1317861D03*
X1107003D03*
Y1315361D03*
X1102439Y1368999D03*
Y1371540D03*
X1098949Y1373158D03*
X1109201Y1382574D03*
X1103932Y1379914D03*
X1109201Y1380066D03*
X1106212Y1376389D03*
X1098949Y1378958D03*
X1096849Y1377558D03*
X1098949Y1376058D03*
X1096749Y1374558D03*
X1099098Y1501204D03*
X1102248Y1496186D03*
X1106700Y1526591D03*
X1112529Y1547661D03*
X1111701Y1558640D03*
X1107181Y1615917D03*
X1109811D03*
X1098549Y1625749D03*
X1100961Y1622543D03*
X1109000Y1671107D03*
X1105148Y1696029D03*
X1099108Y1691229D03*
X1100998Y1715841D03*
Y1725991D03*
X1119676Y54132D03*
X1124834Y56805D03*
X1124270Y404640D03*
X1121628Y401915D03*
X1121077Y511498D03*
X1125077D03*
X1126387Y615658D03*
X1118435Y625307D03*
X1114467Y640802D03*
X1120321Y635832D03*
X1116540Y651070D03*
X1112190Y651962D03*
X1116459Y767299D03*
Y771099D03*
X1112003Y1302861D03*
Y1300361D03*
Y1305361D03*
X1122803Y1307861D03*
X1125303D03*
Y1310361D03*
Y1312861D03*
X1122803D03*
Y1310361D03*
X1112003Y1312861D03*
Y1310361D03*
Y1307861D03*
X1125303Y1300361D03*
Y1302861D03*
X1122803D03*
Y1300361D03*
X1125303Y1305361D03*
X1122803D03*
X1125303Y1315361D03*
X1122803D03*
X1112003D03*
Y1317861D03*
X1125303D03*
X1122803D03*
X1124519Y1372853D03*
X1119659D03*
X1122089D03*
X1125469Y1367108D03*
Y1370008D03*
X1116643Y1382111D03*
X1113155Y1380511D03*
X1115893Y1379543D03*
X1124375Y1423488D03*
X1124415Y1426168D03*
Y1428668D03*
Y1431168D03*
Y1433668D03*
X1115098Y1468871D03*
Y1472271D03*
X1124875Y1490042D03*
X1125498Y1487292D03*
X1116917Y1506823D03*
X1119912Y1506936D03*
X1116917Y1509898D03*
X1119912Y1509891D03*
Y1515644D03*
X1116917D03*
X1119912Y1512644D03*
X1116917D03*
X1114617Y1526318D03*
X1113887Y1543447D03*
X1119459Y1556343D03*
X1118133Y1587998D03*
Y1591398D03*
X1115027Y1598788D03*
X1117247Y1604554D03*
X1113847D03*
X1124532Y1634915D03*
X1114286Y1630507D03*
X1117136Y1630441D03*
X1113490Y1651862D03*
X1112500Y1671107D03*
X1125784Y1662705D03*
X1124394Y1658967D03*
X1120595D03*
X1126000Y1672419D03*
X1122610Y1677976D03*
X1124091Y1683983D03*
X1114414Y1698859D03*
X1114394Y1695936D03*
X1119361Y1713734D03*
X1113948Y1711244D03*
X1126902Y60805D03*
X1142144Y63186D03*
X1132340Y468202D03*
Y471702D03*
X1141267Y500296D03*
X1134567Y513870D03*
X1139360Y516031D03*
X1129387Y615658D03*
X1138387D03*
X1132855Y609373D03*
X1135387Y615658D03*
X1130017Y766870D03*
X1127803Y1302861D03*
Y1300361D03*
Y1305361D03*
Y1307861D03*
Y1310361D03*
Y1312861D03*
X1139703Y1302861D03*
Y1300361D03*
Y1305361D03*
Y1307861D03*
Y1310361D03*
Y1312861D03*
X1127803Y1317861D03*
Y1315361D03*
X1139703Y1317861D03*
Y1315361D03*
X1135139Y1368999D03*
Y1371540D03*
X1131549Y1373158D03*
X1136632Y1379914D03*
X1138912Y1376389D03*
X1127283Y1379188D03*
X1129449Y1377558D03*
X1127283Y1376288D03*
X1129349Y1374558D03*
X1131549Y1378958D03*
Y1376058D03*
X1129965Y1403877D03*
X1127465D03*
X1129965Y1401377D03*
X1127465D03*
X1132465Y1403877D03*
Y1401377D03*
X1129925Y1398737D03*
X1127425D03*
X1134925D03*
X1132425D03*
X1137425D03*
X1137465Y1401377D03*
X1134965D03*
Y1403877D03*
X1137465D03*
X1137275Y1424138D03*
X1134775D03*
X1132275D03*
X1126875Y1423488D03*
X1129775Y1424138D03*
X1140175Y1423488D03*
X1140215Y1428668D03*
Y1426168D03*
X1134815Y1433668D03*
X1137315D03*
X1140215D03*
Y1431168D03*
X1132315Y1433668D03*
X1137315Y1426818D03*
X1134815D03*
X1137345Y1431058D03*
X1134845D03*
X1132315Y1426818D03*
X1132345Y1431058D03*
X1126915Y1428668D03*
Y1426168D03*
X1129815Y1433668D03*
X1126915D03*
Y1431168D03*
X1129815Y1426818D03*
X1129845Y1431058D03*
X1131478Y1485427D03*
X1134183Y1483926D03*
X1126951Y1484646D03*
X1140960Y1489434D03*
Y1491934D03*
X1141045Y1534952D03*
Y1537452D03*
Y1544952D03*
Y1542452D03*
Y1539952D03*
X1135033Y1556112D03*
X1142639Y1562789D03*
X1133765Y1568952D03*
X1140655Y1569256D03*
X1137755Y1569543D03*
X1138480Y1576364D03*
X1140422Y1595455D03*
X1139037Y1611383D03*
X1131824Y1600593D03*
Y1603993D03*
X1140325Y1598697D03*
X1139037Y1614153D03*
X1139142Y1618859D03*
X1139188Y1621603D03*
X1132981Y1634531D03*
X1141084Y1646672D03*
Y1643272D03*
X1137542Y1647925D03*
X1134207Y1669230D03*
X1129184Y1662705D03*
X1132406Y1658967D03*
X1136575Y1676239D03*
X1141356Y1676542D03*
X1133206Y1675383D03*
X1132176Y1690038D03*
X1142643Y74738D03*
X1151679Y72258D03*
X1150118Y207344D03*
X1155268D03*
Y212344D03*
X1150118D03*
X1155890Y478812D03*
X1150577Y478840D03*
X1144663Y492319D03*
Y500319D03*
X1151036Y501627D03*
X1143060Y516476D03*
X1154145Y583339D03*
Y586339D03*
X1146160Y767299D03*
Y771099D03*
X1155282Y766806D03*
X1142203Y1300361D03*
Y1302861D03*
X1144703D03*
Y1300361D03*
X1142203Y1305361D03*
X1144703D03*
X1155503Y1312861D03*
Y1310361D03*
Y1307861D03*
X1142203D03*
Y1310361D03*
Y1312861D03*
X1144703D03*
Y1310361D03*
Y1307861D03*
X1155503Y1302861D03*
Y1300361D03*
Y1305361D03*
Y1315361D03*
X1142203D03*
X1144703D03*
X1142203Y1317861D03*
X1144703D03*
X1155503D03*
X1152359Y1372853D03*
X1154789D03*
X1141901Y1382574D03*
Y1380066D03*
X1149343Y1382111D03*
X1145855Y1380511D03*
X1148593Y1379543D03*
X1142675Y1423488D03*
X1145715Y1423555D03*
X1145755Y1426235D03*
Y1428735D03*
Y1431235D03*
Y1433735D03*
X1142715Y1426168D03*
Y1428668D03*
Y1431168D03*
Y1433668D03*
X1150718Y1462792D03*
X1153724Y1462695D03*
X1154824Y1471134D03*
X1145960Y1491934D03*
X1148460D03*
X1150960D03*
X1153460D03*
X1155960D03*
X1145960Y1489434D03*
X1148460D03*
X1150960D03*
X1153460D03*
X1155960D03*
X1143460D03*
Y1491934D03*
X1153545Y1534952D03*
X1151045D03*
X1148545D03*
X1146045D03*
X1143545D03*
X1153545Y1537452D03*
X1151045D03*
X1148545D03*
X1146045D03*
X1143545D03*
X1151045Y1544952D03*
X1148545D03*
X1146045D03*
X1143545D03*
X1153545D03*
X1143545Y1542452D03*
X1146045D03*
X1148545D03*
X1151045D03*
X1153545D03*
Y1539952D03*
X1151045D03*
X1148545D03*
X1146045D03*
X1143545D03*
X1155253Y1559176D03*
X1147814Y1562823D03*
X1154336Y1555979D03*
X1149467Y1568988D03*
X1142917Y1583314D03*
Y1586714D03*
X1155180Y1655534D03*
X1146501Y1655608D03*
Y1652208D03*
X1158343Y1658514D03*
X1152198Y1669629D03*
X1151985Y1666685D03*
X1151707Y1663655D03*
X1152114Y1672517D03*
X1154500Y1677000D03*
X1142033Y1682412D03*
X1152211Y1682373D03*
X1162086Y76509D03*
X1162144Y487630D03*
X1158764Y489516D03*
X1162067Y570050D03*
X1166131Y580602D03*
X1157038Y583298D03*
Y586298D03*
X1166026Y669006D03*
X1159718Y766870D03*
X1158003Y1307861D03*
Y1310361D03*
Y1312861D03*
Y1300361D03*
Y1302861D03*
Y1305361D03*
X1160503Y1302861D03*
Y1300361D03*
Y1305361D03*
Y1307861D03*
Y1310361D03*
Y1312861D03*
X1158003Y1315361D03*
Y1317861D03*
X1160503D03*
Y1315361D03*
X1168039Y1368999D03*
Y1371540D03*
X1157219Y1372853D03*
X1158059Y1367018D03*
Y1369918D03*
X1164249Y1373158D03*
X1169532Y1379914D03*
X1164249Y1376058D03*
X1159983Y1376288D03*
X1162049Y1374558D03*
X1164249Y1378958D03*
X1159983Y1379188D03*
X1162149Y1377558D03*
X1160163Y1445627D03*
X1163422Y1445000D03*
X1166350Y1454234D03*
X1160750Y1463250D03*
X1164300Y1463300D03*
X1159283Y1471132D03*
X1158460Y1491934D03*
Y1489434D03*
X1169061Y1543800D03*
X1170061Y1551040D03*
X1163485Y1546195D03*
X1161492Y1551175D03*
X1164528Y1565578D03*
X1170404Y1556331D03*
Y1559731D03*
X1166873Y1561431D03*
X1157255Y1556000D03*
X1170539Y1595621D03*
X1168023Y1586251D03*
X1170539Y1588751D03*
X1168023D03*
X1170539Y1586251D03*
Y1583751D03*
Y1600621D03*
Y1598121D03*
X1170339Y1603121D03*
X1165806Y1658934D03*
X1159688Y1665427D03*
X1169098Y1666278D03*
X1159703Y1673000D03*
X1159500Y1679000D03*
Y1682500D03*
X1177404Y11689D03*
Y8289D03*
X1184194Y57015D03*
Y61515D03*
X1185913Y93634D03*
X1174031Y403519D03*
X1181000Y402500D03*
X1175181Y447841D03*
Y442341D03*
X1185952Y444202D03*
Y436202D03*
X1178340Y447734D03*
Y442234D03*
X1176000Y436500D03*
X1180000Y436000D03*
X1175181Y458841D03*
Y464341D03*
Y453341D03*
X1185952Y452202D03*
X1178340Y458734D03*
X1178254Y453142D03*
X1178340Y461615D03*
X1175181Y469841D03*
X1186040Y481691D03*
X1178340Y467165D03*
X1175181Y481691D03*
X1182950Y577030D03*
X1178000Y572602D03*
X1182594Y587759D03*
X1178000Y592673D03*
X1183811Y640682D03*
X1182256Y632368D03*
X1182713Y733815D03*
X1175860Y767299D03*
Y771099D03*
X1184960Y766870D03*
X1172603Y1302861D03*
Y1300361D03*
Y1305361D03*
Y1307861D03*
Y1310361D03*
Y1312861D03*
X1175103Y1300361D03*
Y1302861D03*
X1177603D03*
Y1300361D03*
X1175103Y1305361D03*
X1177603D03*
X1175103Y1307861D03*
Y1310361D03*
Y1312861D03*
X1177603D03*
Y1310361D03*
Y1307861D03*
X1175103Y1315361D03*
X1177603D03*
X1172603Y1317861D03*
Y1315361D03*
X1175103Y1317861D03*
X1177603D03*
X1185259Y1372853D03*
X1174801Y1382574D03*
Y1380066D03*
X1182243Y1382111D03*
X1178755Y1380511D03*
X1181493Y1379543D03*
X1171812Y1376389D03*
X1184900Y1428500D03*
X1183000Y1422900D03*
X1184175Y1435600D03*
X1176500Y1457071D03*
X1180200Y1457100D03*
X1178039Y1595621D03*
X1175539D03*
X1173039D03*
X1180923Y1588751D03*
Y1586251D03*
X1173039Y1588751D03*
X1175539D03*
X1178039D03*
Y1586251D03*
X1175539D03*
X1173039D03*
X1178039Y1583751D03*
X1175539D03*
X1173039D03*
X1178039Y1600621D03*
X1175539D03*
X1173039D03*
X1178039Y1598121D03*
X1175539D03*
X1173039D03*
X1175339Y1603121D03*
X1172839D03*
X1177839D03*
X1184362Y1670254D03*
X1181385Y1670312D03*
X1175726Y1686726D03*
X1195488Y93550D03*
X1190587Y99694D03*
X1199756Y128748D03*
X1189727Y164987D03*
Y160987D03*
X1200037Y177187D03*
X1200012Y181187D03*
X1186821Y185430D03*
Y181930D03*
X1195767Y460202D03*
Y470392D03*
Y465272D03*
X1193040Y481691D03*
X1191087Y573809D03*
X1199370Y578154D03*
X1195236Y581407D03*
X1188267Y571807D03*
X1199392Y590500D03*
X1195336Y586606D03*
X1200923Y601734D03*
Y606134D03*
X1199539Y638492D03*
X1197039D03*
X1194539D03*
X1192039D03*
X1195108Y668148D03*
X1198456Y668138D03*
X1190903Y1307861D03*
Y1310361D03*
Y1312861D03*
X1188403D03*
Y1310361D03*
Y1307861D03*
Y1302861D03*
Y1300361D03*
Y1305361D03*
X1190903Y1300361D03*
Y1302861D03*
X1193403D03*
Y1300361D03*
X1190903Y1305361D03*
X1193403D03*
Y1307861D03*
Y1310361D03*
Y1312861D03*
X1190903Y1315361D03*
X1188403D03*
Y1317861D03*
X1190903D03*
X1193403D03*
Y1315361D03*
X1200839Y1368999D03*
Y1371540D03*
X1190119Y1372853D03*
X1191049Y1367188D03*
Y1370088D03*
X1187689Y1372853D03*
X1197149Y1373158D03*
X1192883Y1379188D03*
X1195049Y1377558D03*
X1197149Y1378958D03*
X1192883Y1376288D03*
X1194949Y1374558D03*
X1197149Y1376058D03*
X1194296Y1396500D03*
X1194000Y1401000D03*
Y1414500D03*
X1203242Y1417440D03*
X1194366Y1405500D03*
X1193929Y1410000D03*
X1202548Y1407453D03*
X1202857Y1412454D03*
X1191000Y1425900D03*
X1198800Y1421500D03*
X1202411Y1427410D03*
X1194000Y1424000D03*
X1203117Y1422452D03*
X1202475Y1432468D03*
X1188000Y1419800D03*
X1194000Y1437500D03*
X1203040D03*
X1194000Y1442500D03*
Y1447500D03*
X1188960Y1609135D03*
X1186455Y1608390D03*
Y1602590D03*
Y1605490D03*
X1190174Y1615418D03*
X1190616Y1670641D03*
X1190314Y1661630D03*
X1199299Y1675517D03*
X1197746Y1680914D03*
X1199272Y1683025D03*
X1189263Y1682551D03*
X1190830Y1675710D03*
X1197612Y1703334D03*
X1192612D03*
X1199612Y1691366D03*
X1189462Y1700334D03*
X1194478Y1699936D03*
X1189407Y1717518D03*
X1205929Y86872D03*
X1206580Y94846D03*
X1208431Y133866D03*
Y128748D03*
X1214094Y258633D03*
Y269008D03*
Y282948D03*
Y287948D03*
X1205625Y313758D03*
X1210698Y313671D03*
X1207447Y341381D03*
X1202508Y341424D03*
X1212700Y475712D03*
X1206590Y481403D03*
X1203269Y481237D03*
X1212051Y559827D03*
X1208733Y585986D03*
X1205900Y582443D03*
X1206191Y588400D03*
X1205679Y594148D03*
X1209796Y668115D03*
X1204334Y668138D03*
X1205630Y766600D03*
X1207903Y1300361D03*
Y1302861D03*
X1210403D03*
Y1300361D03*
X1207903Y1305361D03*
X1210403D03*
X1207903Y1307861D03*
Y1310361D03*
Y1312861D03*
X1210403D03*
Y1310361D03*
Y1307861D03*
X1205403Y1302861D03*
Y1300361D03*
Y1305361D03*
Y1307861D03*
Y1310361D03*
Y1312861D03*
X1207903Y1315361D03*
X1210403D03*
X1205403Y1317861D03*
Y1315361D03*
X1207903Y1317861D03*
X1210403D03*
X1202332Y1379914D03*
X1207601Y1380066D03*
X1215043Y1382111D03*
X1211555Y1380511D03*
X1214293Y1379543D03*
X1207601Y1382574D03*
X1204612Y1376389D03*
X1211000Y1392125D03*
X1211075Y1395200D03*
X1210100Y1436500D03*
X1213000Y1435000D03*
X1210400Y1440000D03*
X1214900Y1439800D03*
X1202697Y1673059D03*
X1205604Y1685400D03*
Y1682200D03*
Y1679000D03*
Y1675800D03*
X1212954Y1703343D03*
X1214954Y1691375D03*
X1204804Y1700343D03*
X1207954Y1703343D03*
X1207770Y1706861D03*
Y1720861D03*
X1205638Y1732766D03*
X1227803Y94210D03*
X1221411Y134230D03*
X1221512Y128239D03*
X1220931Y131307D03*
X1222094Y258633D03*
X1230094D03*
Y269008D03*
X1222094D03*
X1230094Y287948D03*
Y282948D03*
X1222094D03*
Y297066D03*
Y292066D03*
Y314216D03*
Y305216D03*
X1226094Y314216D03*
X1218430Y421012D03*
X1219325Y438151D03*
X1216300Y475682D03*
X1228372Y688501D03*
X1221203Y1312861D03*
Y1310361D03*
Y1307861D03*
X1223703D03*
Y1310361D03*
Y1312861D03*
Y1300361D03*
Y1302861D03*
Y1305361D03*
X1221203Y1302861D03*
Y1300361D03*
Y1305361D03*
Y1315361D03*
X1223703D03*
Y1317861D03*
X1221203D03*
X1222919Y1372853D03*
X1220489D03*
X1223889Y1367188D03*
Y1370088D03*
X1218059Y1372853D03*
X1229949Y1373158D03*
X1228800Y1391300D03*
X1225683Y1379188D03*
X1227849Y1377558D03*
X1225683Y1376288D03*
X1227749Y1374558D03*
X1229949Y1378958D03*
Y1376058D03*
X1227000Y1401300D03*
X1219650Y1392050D03*
X1219500Y1398900D03*
X1224200Y1393500D03*
X1227000Y1404500D03*
X1219500Y1436000D03*
X1221837Y1438800D03*
X1229661Y1442000D03*
X1226200Y1444300D03*
X1222700Y1446300D03*
X1220200Y1449100D03*
X1219738Y1713861D03*
Y1708861D03*
X1216738Y1717011D03*
X1219738Y1722861D03*
Y1727861D03*
X1216738Y1731011D03*
X1238769Y75320D03*
X1233668Y132739D03*
Y128239D03*
X1247834Y159844D03*
X1238094Y258633D03*
X1246094Y269008D03*
X1238094D03*
X1234000Y385500D03*
X1233468Y419742D03*
X1242429Y431255D03*
Y427255D03*
Y435255D03*
X1236879Y449755D03*
X1242429Y439255D03*
X1232081Y460580D03*
X1242692Y483435D03*
X1236100Y773844D03*
X1233084Y772582D03*
X1235215Y777213D03*
X1231397Y769667D03*
X1243207Y779428D03*
X1241057Y782278D03*
X1244986Y787578D03*
X1244127Y784598D03*
X1238257Y779728D03*
X1243294Y1269197D03*
Y1266697D03*
Y1261697D03*
Y1264197D03*
X1243308Y1271754D03*
X1238830Y1322853D03*
Y1325394D03*
X1240323Y1333768D03*
X1245592Y1333920D03*
Y1336428D03*
X1242603Y1330243D03*
X1239800Y1389500D03*
X1235400Y1391200D03*
X1238500Y1400900D03*
X1234900Y1404400D03*
X1233700Y1395600D03*
X1238200Y1395500D03*
X1244300Y1403500D03*
X1235679Y1418908D03*
X1239242Y1418462D03*
X1238731Y1422362D03*
X1239550Y1437050D03*
X1245840Y-28311D03*
Y-31711D03*
X1249152Y72895D03*
X1253152Y84895D03*
X1255661Y90470D03*
X1253152Y95525D03*
X1259472Y92864D03*
X1252693Y124739D03*
X1249431Y137739D03*
X1249065Y241594D03*
Y236594D03*
Y251594D03*
Y246594D03*
X1246094Y258633D03*
X1254094D03*
X1262094Y269008D03*
X1254094D03*
X1262094Y282948D03*
X1254094D03*
X1262094Y287948D03*
X1250285Y303307D03*
X1259659Y389456D03*
X1260107Y399125D03*
X1260227Y415128D03*
X1256137Y459182D03*
Y453872D03*
X1245752Y470733D03*
X1250975Y474945D03*
X1248130Y783354D03*
X1251177Y784488D03*
X1254981Y787578D03*
X1256447Y798828D03*
X1259297Y798784D03*
X1251177Y794878D03*
X1257527Y808938D03*
X1260427Y809008D03*
X1259194Y1251697D03*
Y1246697D03*
Y1254197D03*
Y1249197D03*
X1248294Y1259197D03*
Y1256697D03*
X1245794Y1259197D03*
X1259194Y1269215D03*
Y1261715D03*
Y1264215D03*
Y1266715D03*
X1245894Y1269215D03*
X1248394D03*
X1245894Y1261715D03*
Y1264215D03*
Y1266715D03*
X1248394D03*
Y1264215D03*
Y1261715D03*
X1259194Y1256697D03*
Y1259197D03*
X1248308Y1271754D03*
X1245808D03*
X1259108D03*
X1256050Y1326707D03*
X1258480D03*
X1253034Y1335965D03*
X1249546Y1334365D03*
X1252284Y1333397D03*
X1249600Y1403425D03*
X1257594Y1417000D03*
X1253100Y1413500D03*
X1256224Y1430075D03*
X1256600Y1434500D03*
X1275981Y85114D03*
X1263472Y92864D03*
X1269146Y121022D03*
X1263146D03*
X1267037Y180565D03*
Y175030D03*
X1268941Y206017D03*
X1269360Y219632D03*
X1261969Y219505D03*
X1262094Y258633D03*
X1270094D03*
Y269008D03*
Y282948D03*
Y292066D03*
X1268174Y395125D03*
X1275585Y393597D03*
X1269840Y411128D03*
X1270483Y433148D03*
Y435648D03*
X1265227Y454372D03*
X1262457Y798814D03*
X1266677Y802988D03*
X1266568Y809078D03*
X1275177Y808963D03*
X1263647Y809118D03*
X1271177Y808963D03*
X1261694Y1251697D03*
X1264194D03*
Y1246697D03*
X1261694D03*
Y1254197D03*
X1264194D03*
X1261694Y1249197D03*
X1264194D03*
X1261694Y1269215D03*
Y1266715D03*
Y1264215D03*
Y1261715D03*
X1264194Y1269197D03*
Y1256697D03*
Y1259197D03*
Y1261697D03*
X1261694Y1256697D03*
Y1259197D03*
X1264194Y1264197D03*
Y1266697D03*
X1264108Y1271754D03*
X1261608D03*
X1271726Y1322825D03*
Y1325366D03*
X1260910Y1326707D03*
X1262050Y1320878D03*
Y1323778D03*
X1267940Y1327012D03*
X1265740Y1328412D03*
X1273219Y1333740D03*
X1275499Y1330215D03*
X1267940Y1332812D03*
Y1329912D03*
X1265840Y1331412D03*
X1263674Y1330142D03*
Y1333042D03*
X1271042Y1418748D03*
X1266996Y1423617D03*
X1262310Y1428303D03*
X1275195Y1552250D03*
X1275170Y1579519D03*
X1269310Y1583170D03*
X1287486Y134165D03*
X1278050Y152912D03*
X1278137Y166051D03*
X1278211Y161030D03*
Y156030D03*
X1278137Y180565D03*
Y176051D03*
Y171551D03*
Y184987D03*
X1279447Y213292D03*
X1286094Y258633D03*
X1278094D03*
Y269008D03*
X1286094D03*
X1278094Y282948D03*
X1286094D03*
X1278094Y287948D03*
X1286094Y292066D03*
X1290127Y401125D03*
Y410635D03*
X1289352Y418550D03*
Y421950D03*
X1281190Y1254112D03*
X1276190D03*
X1278690D03*
X1281190Y1249112D03*
Y1251612D03*
X1276190D03*
X1278690D03*
X1276190Y1249112D03*
X1278690D03*
X1281190Y1246612D03*
X1276190D03*
X1278690D03*
X1276190Y1269112D03*
Y1266612D03*
X1281190Y1259112D03*
Y1256612D03*
X1276190D03*
Y1259112D03*
Y1261612D03*
Y1264112D03*
X1278690Y1256612D03*
Y1259112D03*
X1278790Y1269130D03*
X1281290D03*
X1278790Y1261630D03*
Y1264130D03*
Y1266630D03*
X1281290D03*
Y1264130D03*
Y1261630D03*
X1281204Y1271669D03*
X1278704D03*
X1276204D03*
X1288946Y1326679D03*
X1278488Y1333892D03*
X1285930Y1335937D03*
X1282442Y1334337D03*
X1285180Y1333369D03*
X1278488Y1336400D03*
X1287600Y1423100D03*
Y1427600D03*
X1276500Y1432000D03*
X1279525D03*
X1287700Y1431700D03*
X1287961Y1542469D03*
X1287372Y1552845D03*
X1287647Y1545220D03*
Y1549120D03*
X1277017Y1544953D03*
Y1547453D03*
Y1549953D03*
X1281470Y1552845D03*
X1281347Y1549120D03*
Y1545220D03*
X1284497Y1549120D03*
Y1545220D03*
X1284510Y1554436D03*
X1277702D03*
X1289919Y1582295D03*
Y1574795D03*
Y1579795D03*
Y1577295D03*
X1287419Y1582295D03*
Y1579795D03*
X1284919D03*
Y1582295D03*
X1282419D03*
Y1579795D03*
X1299196Y76209D03*
X1305685Y74748D03*
X1296200Y66911D03*
X1305091Y123680D03*
Y127830D03*
Y131750D03*
X1301582Y166051D03*
X1301743Y162055D03*
X1301582Y171551D03*
Y184051D03*
X1302094Y258633D03*
X1294094D03*
Y269008D03*
X1302094D03*
X1294094Y287948D03*
Y282948D03*
X1302094D03*
Y292066D03*
X1302069Y303184D03*
X1299026Y389355D03*
X1302226D03*
X1295519Y389561D03*
X1304347Y523237D03*
X1302160Y524916D03*
X1304566Y525743D03*
X1301642Y537299D03*
X1293581Y542716D03*
X1294938Y561331D03*
X1300400Y599413D03*
X1297400D03*
X1298000Y657500D03*
X1303250Y655149D03*
X1295000Y655200D03*
X1292297Y657206D03*
X1302500Y664500D03*
X1305100Y662100D03*
X1301900Y660699D03*
X1294590Y1254112D03*
X1297090D03*
X1292090D03*
Y1249112D03*
X1294590D03*
X1297090D03*
X1292090Y1251612D03*
X1294590D03*
X1297090D03*
X1292090Y1246612D03*
X1297090D03*
X1294590D03*
X1292090Y1269130D03*
X1294590D03*
X1292090Y1261630D03*
Y1264130D03*
Y1266630D03*
X1294590D03*
Y1264130D03*
Y1261630D03*
X1297090Y1269112D03*
Y1256612D03*
Y1259112D03*
Y1261612D03*
X1294590Y1256612D03*
Y1259112D03*
X1297090Y1264112D03*
Y1266612D03*
X1292090Y1256612D03*
Y1259112D03*
X1297004Y1271669D03*
X1292004D03*
X1294504D03*
X1304630Y1322768D03*
Y1325309D03*
X1293806Y1326679D03*
X1291376D03*
X1294956Y1320934D03*
Y1323834D03*
X1300836Y1326984D03*
X1298636Y1328384D03*
X1296570Y1330114D03*
Y1333014D03*
X1298736Y1331384D03*
X1300836Y1329884D03*
Y1332784D03*
X1296000Y1427700D03*
X1301900D03*
X1295700Y1421800D03*
X1300800D03*
X1291700Y1431700D03*
X1302390Y1530430D03*
X1297490Y1526910D03*
X1297620Y1529534D03*
X1291897Y1545076D03*
X1290461Y1542469D03*
X1291897Y1547576D03*
X1302915Y1563596D03*
X1298466Y1556331D03*
Y1559731D03*
X1292419Y1582295D03*
Y1579795D03*
Y1574795D03*
Y1577295D03*
X1294919D03*
Y1574795D03*
X1294387Y1571682D03*
X1291887D03*
X1301789Y1574795D03*
X1304289D03*
X1301789Y1577295D03*
X1304289D03*
Y1579795D03*
X1301789D03*
X1304289Y1582295D03*
X1301789D03*
X1299289Y1574795D03*
Y1582295D03*
Y1579795D03*
Y1577295D03*
X1295877Y1581199D03*
X1298382Y1584844D03*
X1295877Y1584099D03*
X1293459Y1584844D03*
X1320020Y66979D03*
X1308110Y66911D03*
X1307857Y103353D03*
X1313951Y104739D03*
X1311045D03*
X1313011Y135820D03*
Y139845D03*
X1306300Y203917D03*
X1318094Y258633D03*
X1310094D03*
Y269008D03*
X1318094D03*
X1310094Y287948D03*
Y282948D03*
X1318094D03*
X1305426Y389355D03*
X1308926Y524111D03*
X1306815Y522726D03*
X1307117Y525897D03*
X1309870Y552788D03*
X1309776Y559831D03*
X1317266Y597213D03*
X1310544Y613100D03*
X1313544Y610100D03*
X1310544D03*
X1313544Y607100D03*
X1310544D03*
X1313544Y604100D03*
X1310544D03*
X1307544Y610100D03*
Y613100D03*
Y604100D03*
Y607100D03*
X1317266Y600213D03*
X1309166Y601713D03*
X1308776Y599181D03*
X1313544Y613100D03*
X1310544Y616100D03*
X1313544D03*
X1307544D03*
X1308800Y619200D03*
Y622200D03*
Y625200D03*
X1318300D03*
Y622200D03*
Y619200D03*
X1307700Y664600D03*
X1309600Y667700D03*
X1315657Y1199532D03*
Y1196132D03*
X1311715Y1221042D03*
X1318776Y1219566D03*
X1311594Y1251612D03*
X1309094D03*
X1311594Y1254112D03*
X1309094D03*
X1311594Y1246612D03*
X1309094D03*
X1311594Y1249112D03*
X1309094D03*
X1314094Y1246612D03*
Y1251612D03*
Y1249112D03*
Y1254112D03*
X1309090Y1269169D03*
Y1266669D03*
Y1261669D03*
Y1264169D03*
X1314194Y1269130D03*
Y1266630D03*
Y1264130D03*
Y1261630D03*
X1311694Y1269130D03*
Y1261630D03*
Y1264130D03*
Y1266630D03*
X1311594Y1259112D03*
Y1256612D03*
X1309094Y1259112D03*
Y1256612D03*
X1314094D03*
Y1259112D03*
X1309090Y1271669D03*
X1311590D03*
X1314090D03*
X1306123Y1333683D03*
X1311392Y1333835D03*
X1318834Y1335880D03*
X1315346Y1334280D03*
X1318084Y1333312D03*
X1311392Y1336343D03*
X1308403Y1330158D03*
X1308900Y1525510D03*
X1306789Y1574795D03*
Y1582295D03*
Y1579795D03*
Y1577295D03*
X1310914Y1577299D03*
X1331930Y66945D03*
X1327541Y105227D03*
X1337399Y98084D03*
X1333399D03*
X1334094Y258633D03*
X1326094D03*
Y269008D03*
X1334094D03*
Y287948D03*
X1326094Y282948D03*
X1334094D03*
X1326094Y292066D03*
X1328427Y349452D03*
X1329585Y561806D03*
X1325366Y597213D03*
Y600213D03*
X1321300Y619200D03*
Y622200D03*
Y625200D03*
X1326636Y656800D03*
X1322420Y656867D03*
X1332812Y856383D03*
X1325543Y871161D03*
X1329244D03*
X1334301Y867765D03*
X1328992Y1209788D03*
X1327029Y1206788D03*
X1331202Y1206478D03*
X1323169Y1208995D03*
X1333977Y1222158D03*
X1325137Y1210653D03*
X1324901Y1216419D03*
X1322141Y1217365D03*
X1327494Y1246612D03*
Y1251612D03*
Y1249112D03*
Y1254112D03*
X1324994Y1246612D03*
Y1251612D03*
Y1249112D03*
Y1254112D03*
X1329994Y1246612D03*
Y1251612D03*
Y1249112D03*
Y1254112D03*
X1324994Y1269130D03*
Y1261630D03*
Y1264130D03*
Y1266630D03*
X1327494Y1269130D03*
Y1266630D03*
Y1264130D03*
Y1261630D03*
Y1259112D03*
Y1256612D03*
X1324994Y1259112D03*
Y1256612D03*
X1329994Y1259112D03*
Y1256612D03*
Y1266612D03*
Y1264112D03*
Y1261612D03*
Y1269112D03*
X1327490Y1271669D03*
X1324990D03*
X1329990D03*
X1326710Y1326622D03*
X1324280D03*
X1321850D03*
X1327876Y1320934D03*
Y1323834D03*
X1333740Y1326927D03*
X1331540Y1328327D03*
X1333740Y1329827D03*
Y1332727D03*
X1331640Y1331327D03*
X1329474Y1330057D03*
Y1332957D03*
X1322539Y1411278D03*
X1322499Y1413788D03*
X1325499D03*
X1325539Y1411278D03*
Y1416446D03*
X1322539D03*
X1328539Y1411278D03*
X1328499Y1413788D03*
X1328539Y1416446D03*
X1331509Y1416486D03*
X1334509D03*
X1331509Y1408818D03*
X1334509Y1411318D03*
X1334469Y1413828D03*
X1334509Y1408818D03*
X1331469Y1413828D03*
X1331509Y1411318D03*
X1325579Y1418976D03*
X1322579D03*
X1325609Y1421496D03*
X1322609D03*
X1328579Y1418976D03*
X1328609Y1421496D03*
X1331579Y1421536D03*
X1331549Y1419016D03*
X1334579Y1421536D03*
X1334549Y1419016D03*
X1343840Y66911D03*
X1341399Y98084D03*
X1348199D03*
X1342094Y258633D03*
Y269008D03*
X1350094D03*
Y287948D03*
X1342094Y282948D03*
X1350094D03*
X1342094Y292066D03*
X1340257Y677765D03*
Y675111D03*
X1336812Y856383D03*
X1341301Y867765D03*
X1337801D03*
X1341301Y871265D03*
X1344801D03*
X1348301D03*
X1340948Y1177681D03*
X1342507Y1187848D03*
X1340948Y1181681D03*
X1349012Y1204971D03*
X1342036Y1206429D03*
Y1203029D03*
X1346063Y1217729D03*
Y1214329D03*
X1341590Y1254169D03*
Y1251669D03*
Y1249169D03*
Y1246669D03*
X1344090Y1254169D03*
Y1251669D03*
Y1249169D03*
Y1246669D03*
X1346590Y1254169D03*
Y1249169D03*
Y1251669D03*
Y1246669D03*
X1341690Y1269269D03*
Y1264269D03*
Y1266769D03*
Y1261769D03*
X1341590Y1256669D03*
Y1259169D03*
X1344190Y1269187D03*
X1346690D03*
X1344190Y1261687D03*
Y1264187D03*
Y1266687D03*
X1346690D03*
Y1264187D03*
Y1261687D03*
X1344090Y1256669D03*
Y1259169D03*
X1346590D03*
Y1256669D03*
X1341690Y1271769D03*
X1346690D03*
X1344190D03*
X1337430Y1322968D03*
Y1325509D03*
X1338923Y1333883D03*
X1344192Y1334035D03*
X1348146Y1334480D03*
X1344192Y1336543D03*
X1341203Y1330358D03*
X1340556Y1383674D03*
Y1386674D03*
X1337556D03*
Y1383674D03*
X1346556Y1386674D03*
Y1383674D03*
X1343556Y1386674D03*
Y1383674D03*
X1349556D03*
Y1386674D03*
X1337555Y1389658D03*
X1343712Y1389804D03*
X1348712D03*
X1346212D03*
X1341212D03*
X1348823Y1409626D03*
X1348853Y1413866D03*
X1346323Y1409626D03*
X1346353Y1413866D03*
X1343823Y1409626D03*
X1343853Y1413866D03*
X1346509Y1416486D03*
X1349509D03*
X1343509D03*
X1341323Y1409626D03*
X1341353Y1413866D03*
X1337509Y1416486D03*
Y1411318D03*
X1337469Y1413828D03*
X1337509Y1408818D03*
X1340509Y1416486D03*
X1349579Y1421536D03*
X1349549Y1419016D03*
X1346579Y1421536D03*
X1346549Y1419016D03*
X1343549D03*
X1343579Y1421536D03*
X1337579D03*
X1337549Y1419016D03*
X1340579Y1421536D03*
X1340549Y1419016D03*
X1355750Y66886D03*
X1360109Y98050D03*
X1352199D03*
X1364369Y120380D03*
X1358094Y258633D03*
X1350094D03*
X1358094Y269008D03*
X1366094D03*
Y287948D03*
X1358094Y282948D03*
X1366094D03*
X1358094Y292066D03*
X1363857Y626579D03*
X1361427D03*
X1354397Y623374D03*
Y626274D03*
X1356597Y624874D03*
X1358663Y623144D03*
X1356497Y621874D03*
X1354397Y620474D03*
X1358663Y620244D03*
X1360964Y629514D03*
Y632414D03*
X1358461Y684151D03*
Y686651D03*
X1360961Y684073D03*
Y686573D03*
X1363461D03*
Y684073D03*
X1363435Y681573D03*
X1358435D03*
X1360935D03*
X1358461Y694151D03*
X1363461D03*
X1360961D03*
X1358461Y689151D03*
Y691651D03*
X1363461Y696651D03*
X1360961D03*
X1363461Y699151D03*
X1360961Y691573D03*
X1363461D03*
X1360961Y689073D03*
X1363461D03*
X1362523Y1015473D03*
Y1022559D03*
Y1019016D03*
X1355222Y1200561D03*
X1361285Y1206718D03*
X1355641Y1210674D03*
X1362810Y1211071D03*
X1357490Y1254169D03*
Y1249169D03*
Y1251669D03*
Y1246669D03*
X1359990Y1254169D03*
X1362490D03*
X1359990Y1249169D03*
X1362490D03*
X1359990Y1251669D03*
X1362490D03*
Y1246669D03*
X1359990D03*
Y1269187D03*
Y1266687D03*
Y1264187D03*
Y1261687D03*
X1357490Y1269187D03*
Y1261687D03*
Y1264187D03*
Y1266687D03*
Y1256669D03*
Y1259169D03*
X1362490Y1269269D03*
Y1261769D03*
Y1266769D03*
Y1264269D03*
Y1256669D03*
Y1259169D03*
X1359990Y1256669D03*
Y1259169D03*
X1357490Y1271769D03*
X1362490D03*
X1359990D03*
X1359510Y1326822D03*
X1360724Y1321184D03*
Y1324084D03*
X1357080Y1326822D03*
X1354650D03*
X1364340Y1328527D03*
X1351634Y1336080D03*
X1350884Y1333512D03*
X1364440Y1337527D03*
Y1331527D03*
Y1334527D03*
X1362274Y1330257D03*
Y1333157D03*
Y1336057D03*
X1352226Y1386804D03*
Y1383804D03*
X1352225Y1389788D03*
X1358509Y1416486D03*
Y1413818D03*
Y1411318D03*
Y1408818D03*
X1352509Y1416486D03*
Y1411318D03*
Y1413818D03*
Y1408818D03*
X1355509Y1416486D03*
Y1411318D03*
Y1413818D03*
Y1408818D03*
X1352579Y1421536D03*
X1352549Y1419016D03*
X1355549D03*
X1367950Y66886D03*
X1377682Y87587D03*
X1368109Y98000D03*
X1366094Y258633D03*
X1373862Y485552D03*
Y511052D03*
X1381457Y511050D03*
X1376757Y619497D03*
X1369303Y617321D03*
X1372791Y618921D03*
X1370053Y619889D03*
X1376745Y616858D03*
X1379734Y623043D03*
X1366287Y626579D03*
X1376761Y686573D03*
Y684073D03*
X1374261D03*
Y686573D03*
X1374245Y681573D03*
X1376745D03*
X1376761Y694151D03*
X1374261D03*
X1376761Y696651D03*
X1374261D03*
X1376761Y699151D03*
X1374261D03*
X1376761Y701651D03*
X1374261D03*
X1376761Y691573D03*
Y689073D03*
X1374261Y691573D03*
Y689073D03*
X1376761Y706651D03*
Y704151D03*
X1374261Y706651D03*
Y704151D03*
X1377483Y1015473D03*
X1370003D03*
X1377483Y1022559D03*
Y1019016D03*
X1370003Y1022559D03*
Y1019016D03*
X1370685Y1223032D03*
Y1226432D03*
X1374476Y1266143D03*
X1376976D03*
X1379476D03*
X1374476Y1268643D03*
X1376976D03*
X1379476D03*
X1374476Y1273643D03*
Y1271143D03*
X1374576Y1283743D03*
Y1281243D03*
X1374476Y1276143D03*
Y1278643D03*
X1376976Y1273643D03*
Y1271143D03*
X1379476Y1273643D03*
Y1271143D03*
X1377076Y1281161D03*
Y1283661D03*
X1379576D03*
Y1281161D03*
X1376976Y1276143D03*
Y1278643D03*
X1379476D03*
Y1276143D03*
X1379576Y1288661D03*
X1377076Y1286161D03*
X1379576D03*
X1377076Y1288661D03*
X1379576Y1291243D03*
X1377076D03*
X1374576Y1288743D03*
Y1286243D03*
Y1291243D03*
X1370012Y1342299D03*
X1371505Y1353214D03*
X1376774Y1353366D03*
X1370012Y1344840D03*
X1376774Y1355874D03*
X1373785Y1349689D03*
X1382045Y1700038D03*
X1379804Y1733118D03*
X1383715Y236594D03*
Y241594D03*
X1381457Y485550D03*
X1382014Y619518D03*
X1383507Y627892D03*
Y630433D03*
X1387097Y656274D03*
X1389297Y657774D03*
X1391363Y656044D03*
X1387097Y653374D03*
X1389197Y654774D03*
X1391363Y653144D03*
X1394127Y659479D03*
X1387097Y659174D03*
X1393664Y662384D03*
Y665284D03*
X1393343Y716971D03*
X1390807Y717053D03*
X1390817Y714471D03*
X1393317D03*
X1393343Y719471D03*
X1390807Y719553D03*
X1393367Y727023D03*
Y729523D03*
X1393343Y724471D03*
Y721971D03*
X1390807Y722053D03*
Y724553D03*
X1390853Y727053D03*
X1391460Y1009764D03*
Y1006024D03*
Y1013504D03*
Y1020985D03*
Y1024725D03*
Y1028465D03*
Y1017244D03*
X1390376Y1268643D03*
X1392876D03*
Y1283661D03*
Y1281161D03*
X1390376D03*
Y1283661D03*
Y1273643D03*
Y1271143D03*
Y1276143D03*
Y1278643D03*
X1392876Y1273643D03*
Y1271143D03*
Y1276143D03*
Y1278643D03*
Y1288661D03*
Y1286161D03*
X1390376Y1288661D03*
Y1286161D03*
Y1291243D03*
X1392876D03*
X1393306Y1340515D03*
Y1343415D03*
X1384216Y1355411D03*
X1380728Y1353811D03*
X1383466Y1352843D03*
X1392092Y1346153D03*
X1389662D03*
X1387232D03*
X1385068Y1664907D03*
X1390738Y1664938D03*
X1392068Y1676875D03*
X1381918D03*
X1391750Y1697747D03*
X1382045Y1704038D03*
X1390045Y1712038D03*
X1390179Y1733118D03*
X1404917Y116911D03*
X1395302Y251136D03*
Y256136D03*
X1411000Y460362D03*
X1406500Y458362D03*
X1400500Y458377D03*
X1409445Y652266D03*
X1402003Y650221D03*
X1405491Y651821D03*
X1402753Y652789D03*
X1409445Y649758D03*
X1398987Y659479D03*
X1396557D03*
X1409143Y716971D03*
X1395843D03*
X1406643D03*
X1409127Y714471D03*
X1395817D03*
X1406627D03*
X1409143Y719471D03*
X1395843D03*
X1406643D03*
X1395867Y732023D03*
Y727023D03*
Y729523D03*
X1406667Y727023D03*
X1409167Y732023D03*
Y729523D03*
X1406667Y732023D03*
Y729523D03*
X1409167Y727023D03*
X1409143Y724471D03*
Y721971D03*
X1395843Y724471D03*
Y721971D03*
X1406643Y724471D03*
Y721971D03*
X1409167Y739523D03*
Y734523D03*
Y737023D03*
X1406667Y734523D03*
Y737023D03*
Y739523D03*
X1401015Y1014744D03*
X1399953Y1005799D03*
X1403693D03*
X1407433D03*
X1401015Y1023012D03*
Y1018878D03*
X1407433Y1032430D03*
X1403693D03*
X1395060Y1032205D03*
X1399953Y1032430D03*
X1395376Y1268643D03*
Y1273643D03*
Y1271143D03*
Y1281243D03*
Y1283743D03*
Y1276143D03*
Y1278643D03*
Y1288743D03*
Y1286243D03*
Y1291243D03*
X1399122Y1352258D03*
X1394856Y1352488D03*
X1399122Y1346458D03*
Y1349358D03*
X1396922Y1347858D03*
X1394856Y1349588D03*
X1397022Y1350858D03*
X1405811Y1430021D03*
X1409532Y1552845D03*
X1409409Y1549120D03*
Y1545220D03*
X1403257Y1552250D03*
X1405079Y1549953D03*
Y1544953D03*
Y1547453D03*
X1405764Y1554436D03*
X1403232Y1579519D03*
X1397030Y1594060D03*
X1409286Y1605796D03*
X1406666Y1616332D03*
X1400029Y1615796D03*
X1406447Y1619572D03*
X1396783Y1617170D03*
X1408023Y1638705D03*
X1398058Y1628651D03*
X1408208D03*
X1406814Y1652439D03*
X1399599Y1657583D03*
X1398883Y1680341D03*
X1410750Y244583D03*
X1417000Y460362D03*
X1419335Y533958D03*
X1414714Y653008D03*
X1412434Y655943D03*
X1416207Y663333D03*
Y660792D03*
X1421797Y687354D03*
X1423963Y685724D03*
X1419697Y685954D03*
X1421897Y690354D03*
X1423963Y688624D03*
X1419697Y688854D03*
Y691754D03*
X1423417Y747051D03*
X1423407Y757133D03*
Y749633D03*
Y752133D03*
Y754633D03*
X1416301Y970340D03*
Y977840D03*
Y985340D03*
X1414576Y989765D03*
X1414501Y993765D03*
Y997765D03*
X1410858Y1014744D03*
X1418653Y1005799D03*
X1414913D03*
X1411173D03*
X1414501Y1001765D03*
X1419716Y1014744D03*
X1422394Y1005799D03*
X1410858Y1023012D03*
X1419716D03*
X1410858Y1018878D03*
X1419716D03*
X1422394Y1032430D03*
X1419026Y1038765D03*
Y1042765D03*
X1414913Y1032430D03*
X1418653D03*
X1411173D03*
X1417301Y1051540D03*
X1418982Y1175144D03*
X1414165Y1289564D03*
X1414172Y1286188D03*
X1415434Y1552845D03*
X1415709Y1545220D03*
Y1549120D03*
X1418523Y1542469D03*
X1419959Y1545076D03*
Y1547576D03*
X1416023Y1542469D03*
X1412559Y1549120D03*
Y1545220D03*
X1412572Y1554436D03*
X1417981Y1568680D03*
X1423531Y1574795D03*
Y1582295D03*
Y1579795D03*
Y1577295D03*
X1424621Y1571911D03*
Y1569411D03*
X1416862Y1582871D03*
X1419811Y1599084D03*
X1416709Y1592819D03*
X1413836Y1586944D03*
X1412467Y1602234D03*
X1419914Y1602777D03*
X1418000Y1607500D03*
X1422154Y1626270D03*
X1423722Y1616780D03*
X1419622Y1616000D03*
X1422266Y1628947D03*
X1411113Y1637767D03*
X1421890Y1635500D03*
X1418755Y1654999D03*
X1410315Y1646967D03*
X1424315D03*
X1436263Y-28311D03*
Y-31711D03*
X1434262Y52892D03*
X1438262D03*
X1431262Y61392D03*
X1439049Y107443D03*
X1429169Y107313D03*
X1431300Y538800D03*
X1435400Y536200D03*
X1431400Y533400D03*
X1435400Y530800D03*
X1434603Y682801D03*
X1438091Y684401D03*
X1435353Y685369D03*
X1431617Y692359D03*
X1429187D03*
X1426757D03*
X1426264Y694954D03*
Y697854D03*
X1439227Y747051D03*
X1425917D03*
X1428417D03*
X1428407Y762133D03*
Y759633D03*
X1425907D03*
X1439257Y762133D03*
Y759633D03*
X1425943Y757051D03*
X1428443D03*
X1425943Y749551D03*
Y752051D03*
Y754551D03*
X1428443D03*
Y752051D03*
Y749551D03*
X1439243Y757051D03*
Y749551D03*
Y752051D03*
Y754551D03*
X1439257Y764633D03*
Y769633D03*
Y767133D03*
X1429952Y1014744D03*
X1433614Y1005799D03*
X1426134D03*
X1429874D03*
X1429952Y1023012D03*
Y1018878D03*
X1426134Y1032430D03*
X1433614D03*
X1429874D03*
X1434235Y1550240D03*
X1433235Y1543800D03*
X1430735D03*
X1431735Y1550240D03*
X1434578Y1556331D03*
Y1559731D03*
X1430213Y1553652D03*
X1427713D03*
X1426031Y1582295D03*
X1431031Y1574795D03*
Y1577295D03*
X1426031Y1579795D03*
Y1577295D03*
Y1574795D03*
X1428531D03*
Y1577295D03*
Y1579795D03*
Y1582295D03*
X1430431Y1570595D03*
X1427931D03*
X1437901Y1579795D03*
Y1577295D03*
Y1574795D03*
Y1582295D03*
X1435401D03*
Y1579795D03*
Y1577295D03*
Y1574795D03*
X1431989Y1581199D03*
X1434494Y1584844D03*
X1431989Y1584099D03*
X1429571Y1584844D03*
X1430244Y1609966D03*
X1438565Y1612583D03*
X1434316Y1616909D03*
X1430238Y1617137D03*
X1437594Y1616845D03*
X1426899Y1616990D03*
X1429072Y1643655D03*
X1433911Y1649037D03*
X1433618Y1659331D03*
X1433157Y1651977D03*
X1436311Y1665948D03*
X1438078Y1669992D03*
X1439316Y1675080D03*
X1435904Y1694335D03*
X1443049Y107443D03*
X1448549Y114643D03*
X1446040Y120218D03*
X1452040Y113018D03*
X1440871Y152166D03*
X1454769Y163842D03*
X1444769D03*
Y174217D03*
X1453974Y174414D03*
X1449769Y174217D03*
X1439769D03*
Y182217D03*
X1449769D03*
X1456500Y457000D03*
X1441053Y560535D03*
X1441898Y576755D03*
X1452708Y610954D03*
Y607954D03*
X1449708Y610954D03*
X1446708D03*
Y607954D03*
X1449708D03*
X1440708Y610954D03*
X1443708D03*
X1440708Y607954D03*
X1443708D03*
X1452708Y613954D03*
X1446708Y616954D03*
Y619954D03*
X1440708D03*
Y616954D03*
X1443708D03*
Y619954D03*
X1449708Y613954D03*
X1446708D03*
X1440708D03*
X1443708D03*
X1446708Y622954D03*
X1440708D03*
X1443708D03*
X1452938Y617364D03*
X1450438D03*
X1452898Y621844D03*
X1450398D03*
X1448996Y645270D03*
Y647770D03*
X1451496Y645270D03*
X1453996D03*
Y647770D03*
X1451496D03*
X1449046Y650370D03*
X1454046D03*
X1451546D03*
X1446426D03*
X1443926D03*
X1443876Y645270D03*
Y647770D03*
X1446376Y645270D03*
Y647770D03*
X1447314Y684998D03*
X1442091Y684846D03*
X1442045Y682338D03*
X1448807Y695913D03*
Y693372D03*
X1445034Y688523D03*
X1452615Y705531D03*
X1441727Y747051D03*
X1444257Y757133D03*
Y759633D03*
Y762133D03*
X1441757Y759633D03*
Y762133D03*
X1441743Y757051D03*
Y754551D03*
Y752051D03*
Y749551D03*
X1444257Y772133D03*
Y764633D03*
Y769633D03*
Y767133D03*
X1441757Y772133D03*
Y764633D03*
Y769633D03*
Y767133D03*
X1442107Y1013504D03*
Y1009764D03*
Y1006024D03*
Y1020985D03*
Y1024725D03*
Y1028465D03*
Y1017244D03*
Y1032205D03*
X1439850Y1541470D03*
X1440401Y1574795D03*
Y1582295D03*
Y1579795D03*
Y1577295D03*
X1442901Y1582295D03*
Y1579795D03*
Y1577295D03*
Y1574795D03*
X1447026Y1577299D03*
X1448061Y1593055D03*
X1451000Y1601000D03*
X1446000Y1600500D03*
X1450500Y1614500D03*
Y1624000D03*
X1445500Y1614500D03*
X1441000D03*
X1440027Y1667945D03*
X1455579Y1665701D03*
X1453553Y1686892D03*
X1445079Y1686678D03*
X1449070Y1686722D03*
X1448000Y1676000D03*
X1464830Y59054D03*
X1466681Y78590D03*
X1454549Y107443D03*
X1455667Y125733D03*
X1463017Y139518D03*
X1456226Y152166D03*
X1462682Y450372D03*
X1456982Y437362D03*
X1466609Y458608D03*
X1465395Y487582D03*
X1465832Y530656D03*
X1463647Y544977D03*
X1464257Y560977D03*
Y557498D03*
X1462497Y555021D03*
X1464257Y568977D03*
Y572977D03*
Y580977D03*
Y576977D03*
X1467708Y610954D03*
Y607954D03*
X1464708Y610954D03*
Y607954D03*
X1458708Y610954D03*
X1455708D03*
X1461708D03*
Y607954D03*
X1455708D03*
X1458708D03*
X1467708Y616954D03*
Y619954D03*
Y613954D03*
X1461708Y616954D03*
Y619954D03*
X1464708Y616954D03*
Y619954D03*
Y613954D03*
X1458708D03*
X1455708D03*
X1461708D03*
X1467708Y622954D03*
X1461708D03*
X1464708D03*
X1455438Y617364D03*
X1457938D03*
X1455398Y621844D03*
X1457898D03*
X1456496Y645270D03*
X1459396D03*
X1456496Y647770D03*
X1459396D03*
X1456546Y650370D03*
X1459446D03*
X1467521Y702378D03*
X1454715Y700931D03*
X1468271Y704946D03*
X1462045Y711826D03*
X1464475D03*
X1459615D03*
X1456881Y708201D03*
Y705301D03*
X1454715Y706931D03*
Y703931D03*
X1454815Y709931D03*
X1458777Y714194D03*
Y717094D03*
X1456335Y771710D03*
Y766628D03*
X1458861Y776628D03*
X1461361D03*
X1458861Y769128D03*
Y771628D03*
Y774128D03*
X1461361D03*
Y771628D03*
Y769128D03*
X1461335Y766628D03*
X1458835D03*
X1456335Y776710D03*
Y774210D03*
Y769210D03*
X1461371Y791696D03*
Y789196D03*
X1458871Y779196D03*
X1461371D03*
X1458871Y784196D03*
Y781696D03*
Y786696D03*
X1461371Y784196D03*
Y786696D03*
Y781696D03*
X1456371Y779210D03*
Y781710D03*
Y784210D03*
X1456945Y1015473D03*
X1464526D03*
X1456945Y1019016D03*
Y1022559D03*
X1464526Y1019016D03*
Y1022559D03*
X1468102Y1670817D03*
X1458795Y1687083D03*
X1457940Y1675710D03*
X1463038Y1687060D03*
X1466111Y1685098D03*
X1472129Y56083D03*
X1483820Y132405D03*
X1471395Y487582D03*
X1473947Y492169D03*
X1472647Y539478D03*
X1475257Y530656D03*
X1473444Y555208D03*
X1473408Y547948D03*
X1478147Y547728D03*
X1478257Y543977D03*
X1481257Y544977D03*
X1482044Y542517D03*
X1472257Y551241D03*
X1472757Y561264D03*
X1473362Y558380D03*
X1472257Y564977D03*
X1481898Y585476D03*
X1484347Y580388D03*
X1478258Y588108D03*
Y584142D03*
X1474963Y701915D03*
X1480232Y704575D03*
X1475009Y704488D03*
X1481725Y715490D03*
X1471009Y703978D03*
X1481725Y712949D03*
X1477952Y708100D03*
X1477171Y774196D03*
Y771696D03*
Y769196D03*
Y776696D03*
X1474661Y776628D03*
Y774128D03*
Y771628D03*
Y769128D03*
X1472161Y776628D03*
Y769128D03*
Y771628D03*
Y774128D03*
X1472145Y766628D03*
X1474645D03*
X1477145D03*
X1477171Y791696D03*
X1474671D03*
X1472171D03*
X1477171Y786696D03*
X1474671D03*
X1477171Y781696D03*
X1474671D03*
X1472171Y789196D03*
Y779196D03*
Y784196D03*
Y786696D03*
Y781696D03*
X1477171Y789196D03*
X1474671D03*
X1477171Y779196D03*
X1474671D03*
X1477171Y784196D03*
X1474671D03*
X1481177Y803488D03*
X1469950Y813232D03*
X1473728Y813552D03*
X1480677Y813488D03*
X1484177Y812988D03*
X1474177Y816872D03*
X1471526Y1015473D03*
Y1019016D03*
Y1022559D03*
X1482798Y1685982D03*
X1469588Y1673342D03*
X1486000Y1686000D03*
X1470500Y1685500D03*
X1494891Y121171D03*
X1488647Y134562D03*
X1497386Y464980D03*
X1495682Y473302D03*
X1484395Y487582D03*
X1492514Y539657D03*
X1484416Y541658D03*
X1488510Y542816D03*
X1490602Y544755D03*
X1497310Y543960D03*
X1494967Y541898D03*
X1487660Y585748D03*
X1491677Y583588D03*
X1490677Y580688D03*
X1492789Y576602D03*
X1495236Y612838D03*
X1495486Y599938D03*
X1497986Y602438D03*
Y599938D03*
X1495236Y605338D03*
X1495486Y602438D03*
X1495236Y607838D03*
Y610338D03*
X1492636Y605258D03*
Y607758D03*
Y610258D03*
Y612758D03*
X1497986Y612838D03*
Y605338D03*
Y607838D03*
Y610338D03*
X1495486Y615988D03*
Y618488D03*
X1497986Y615988D03*
Y618488D03*
X1492886Y618408D03*
Y615908D03*
X1497587Y711636D03*
X1495157D03*
X1492727D03*
X1489963Y705301D03*
X1487797Y706931D03*
X1487897Y709931D03*
X1489963Y708201D03*
X1485697Y708431D03*
Y705531D03*
Y711331D03*
X1492264Y714544D03*
Y717444D03*
X1491943Y776628D03*
X1494443D03*
X1491943Y769128D03*
Y771628D03*
Y774128D03*
X1494443D03*
Y771628D03*
Y769128D03*
X1494417Y766628D03*
X1491917D03*
X1489417Y776710D03*
Y774210D03*
Y769210D03*
Y771710D03*
Y766628D03*
X1494487Y779210D03*
Y784210D03*
Y786710D03*
Y781710D03*
X1491987Y779210D03*
Y784210D03*
Y786710D03*
Y781710D03*
X1489487Y779210D03*
Y784210D03*
Y786710D03*
Y781710D03*
X1500500Y809063D03*
X1496532Y803513D03*
X1485177Y803488D03*
X1489177Y812988D03*
X1487923Y816770D03*
X1490973Y825557D03*
X1498177Y829359D03*
X1495670Y826073D03*
X1486761Y826279D03*
X1493260Y1167390D03*
X1496960D03*
X1488875Y1677385D03*
X1503785Y464815D03*
X1505974Y470636D03*
X1511917Y483878D03*
X1499752Y488424D03*
X1502085Y545432D03*
X1507109Y550059D03*
X1507644Y554372D03*
X1507468Y564357D03*
X1506337Y561677D03*
X1502757Y570977D03*
X1508281Y559390D03*
X1509757Y575477D03*
X1501821Y577664D03*
X1502986Y602438D03*
Y599938D03*
X1500486Y602438D03*
Y599938D03*
X1502486Y605338D03*
Y607838D03*
Y610338D03*
Y612838D03*
X1500486Y615988D03*
Y618488D03*
X1502986Y615988D03*
Y618488D03*
X1500603Y702378D03*
X1508045Y701915D03*
X1513314Y704575D03*
X1508045Y704423D03*
X1504091Y703978D03*
X1501353Y704946D03*
X1511034Y708100D03*
X1510287Y771710D03*
Y769210D03*
Y774210D03*
Y776710D03*
X1507743Y776628D03*
Y774128D03*
Y771628D03*
Y769128D03*
X1505243Y776628D03*
Y769128D03*
Y771628D03*
Y774128D03*
X1505227Y766628D03*
X1507727D03*
X1510227D03*
X1507787Y786710D03*
Y781710D03*
X1505287Y779210D03*
Y784210D03*
Y786710D03*
Y781710D03*
X1510287Y779210D03*
Y784210D03*
Y786710D03*
Y781710D03*
X1507787Y779210D03*
Y784210D03*
X1508177Y803488D03*
X1501500Y799948D03*
X1510261Y814611D03*
X1500422Y814180D03*
X1512523Y809679D03*
X1502177Y817013D03*
X1512539Y812920D03*
X1505016Y817107D03*
X1501636Y828796D03*
X1499469Y860322D03*
Y863322D03*
X1504362Y1167390D03*
X1508063D03*
X1515854Y119810D03*
X1517708Y216505D03*
X1527392Y238017D03*
X1519120Y479215D03*
X1515936Y484412D03*
X1516757Y537477D03*
X1516257Y547977D03*
X1516336Y551977D03*
X1519457Y556338D03*
X1519317Y561977D03*
X1527853Y560264D03*
X1524777Y605488D03*
Y607988D03*
X1527277Y605488D03*
Y607988D03*
X1524777Y610588D03*
X1527277D03*
X1524777Y613088D03*
X1527277D03*
X1524777Y615618D03*
X1527277D03*
X1524777Y618118D03*
X1527277D03*
X1514807Y715490D03*
Y712949D03*
X1525527Y711636D03*
X1527957D03*
X1522763Y708201D03*
Y705301D03*
X1518497Y705531D03*
X1520597Y706931D03*
X1518497Y708431D03*
X1520697Y709931D03*
X1518497Y711331D03*
X1525064Y714544D03*
Y717444D03*
X1522217Y771710D03*
X1527217Y766628D03*
X1522217Y769210D03*
X1524717Y766628D03*
X1522217D03*
Y774210D03*
Y776710D03*
X1524743Y776628D03*
X1527243D03*
X1524743Y769128D03*
Y771628D03*
Y774128D03*
X1527243D03*
Y771628D03*
Y769128D03*
X1527217Y779210D03*
Y784210D03*
Y786710D03*
Y781710D03*
X1524717Y779210D03*
X1522217D03*
X1524717Y784210D03*
Y786710D03*
X1522217Y784210D03*
Y786710D03*
X1524717Y781710D03*
X1522217D03*
X1517431Y811466D03*
X1521003Y1169488D03*
X1521217Y1190088D03*
X1524425Y1185241D03*
X1539134Y-35912D03*
Y-32512D03*
X1538342Y28406D03*
X1540342Y48720D03*
X1537450Y226293D03*
X1533160Y231250D03*
X1536538Y296819D03*
X1536422Y292816D03*
X1536542Y308819D03*
X1534584Y467067D03*
X1539693Y543613D03*
X1532824Y555981D03*
X1539693Y558943D03*
X1532730Y562949D03*
X1534565Y564945D03*
X1533403Y702378D03*
X1540845Y701915D03*
Y704423D03*
X1536891Y703978D03*
X1534153Y704946D03*
X1543834Y708100D03*
X1530387Y711636D03*
X1538027Y766628D03*
X1540527D03*
X1540543Y776628D03*
Y774128D03*
Y771628D03*
Y769128D03*
X1538043Y776628D03*
Y769128D03*
Y771628D03*
Y774128D03*
X1538027Y784710D03*
Y779210D03*
X1540527D03*
X1538027Y781710D03*
X1540527D03*
X1539972Y807319D03*
X1529306Y1177468D03*
X1540801Y1178265D03*
X1537301D03*
X1539301Y1175765D03*
X1532896Y1234836D03*
X1542747Y1253602D03*
X1538587Y1245065D03*
X1543772Y1241016D03*
X1543519Y1248205D03*
X1536916Y1240844D03*
X1543582Y1524562D03*
X1541191Y1544953D03*
Y1547453D03*
Y1549953D03*
X1539369Y1552250D03*
X1541876Y1554436D03*
X1539344Y1579519D03*
X1554360Y207251D03*
X1556960Y287478D03*
X1551900Y287288D03*
X1544489Y288816D03*
X1546789Y287116D03*
X1548772Y291916D03*
X1553154Y479063D03*
X1558198Y486791D03*
X1551779Y530698D03*
X1546149Y541169D03*
X1545987Y562012D03*
X1553657Y678965D03*
X1553827Y687991D03*
X1556027Y680391D03*
X1555893Y686261D03*
Y683361D03*
X1553657Y681965D03*
X1553727Y684991D03*
X1558657Y689696D03*
X1558194Y695501D03*
Y692501D03*
X1546114Y704575D03*
X1547607Y715490D03*
Y712949D03*
X1556708Y747282D03*
X1556688Y744688D03*
X1556708Y749782D03*
Y754782D03*
Y752282D03*
Y757282D03*
Y762282D03*
Y759782D03*
Y764782D03*
Y769782D03*
Y767282D03*
X1556121Y798542D03*
X1551124Y801289D03*
X1551961Y807269D03*
X1556361D03*
X1547561D03*
X1551113Y1238088D03*
X1548360Y1234750D03*
X1550517Y1232905D03*
X1545627Y1254068D03*
X1545480Y1245090D03*
X1544911Y1260654D03*
X1543980Y1258312D03*
X1554692Y1269688D03*
X1557559Y1269095D03*
X1557510Y1280291D03*
X1554377Y1278763D03*
X1560454Y1279004D03*
X1553226Y1288814D03*
X1553548Y1284991D03*
X1556515Y1292232D03*
X1555222Y1302757D03*
X1547195Y1478165D03*
X1547216Y1480812D03*
X1545473Y1522117D03*
X1547548Y1520070D03*
X1551821Y1549120D03*
Y1545220D03*
X1551546Y1552845D03*
X1556071Y1547576D03*
X1554635Y1542469D03*
X1552135D03*
X1556071Y1545076D03*
X1545644Y1552845D03*
X1545521Y1549120D03*
Y1545220D03*
X1548671Y1549120D03*
Y1545220D03*
X1548684Y1554436D03*
X1554093Y1582295D03*
Y1574795D03*
Y1579795D03*
Y1577295D03*
X1551593Y1582295D03*
Y1579795D03*
X1556593Y1582295D03*
Y1579795D03*
Y1574795D03*
Y1577295D03*
X1549093Y1579795D03*
Y1582295D03*
X1546593D03*
Y1579795D03*
X1558560Y1571682D03*
X1556060D03*
X1557633Y1584844D03*
X1572502Y254250D03*
X1572549Y257491D03*
X1566442Y294816D03*
X1564506Y310334D03*
Y313734D03*
X1571516Y319099D03*
X1568070Y497847D03*
X1573070D03*
X1570570D03*
X1570068Y534095D03*
X1573326Y543351D03*
X1573487Y546996D03*
X1572436Y578933D03*
X1568446Y582733D03*
X1572436Y582433D03*
X1564946Y582733D03*
X1561246Y580393D03*
X1572436Y574022D03*
X1568936Y585933D03*
Y589433D03*
X1565436Y585933D03*
Y589433D03*
X1562016Y584283D03*
Y587783D03*
X1572436Y589433D03*
Y585933D03*
X1566533Y680438D03*
X1570021Y682038D03*
X1567283Y683006D03*
X1563517Y689696D03*
X1561087D03*
X1572514Y747188D03*
X1561714D03*
X1559214D03*
X1561688Y744688D03*
X1559188D03*
X1572498D03*
X1572588Y757282D03*
Y759782D03*
X1561708Y757282D03*
X1559208D03*
X1561708Y759782D03*
X1559208D03*
X1561708Y762282D03*
X1559208D03*
X1572514Y752188D03*
Y749688D03*
Y754688D03*
X1561714Y749688D03*
Y752188D03*
X1559214D03*
Y749688D03*
X1561714Y754688D03*
X1559214D03*
X1561708Y769782D03*
X1559208D03*
X1561708Y767282D03*
X1559208D03*
X1561708Y764782D03*
X1559208D03*
X1570583Y800104D03*
X1572668Y806778D03*
X1567737Y1271411D03*
X1561927Y1269901D03*
X1559181Y1287165D03*
X1568100Y1290418D03*
X1567000Y1293446D03*
X1562820Y1309360D03*
X1568456Y1311533D03*
X1572416Y1303160D03*
X1564268Y1338440D03*
X1562937Y1341609D03*
X1572331Y1348205D03*
X1566901Y1347726D03*
X1564758Y1367834D03*
X1572906Y1366759D03*
X1563967Y1363205D03*
X1567089Y1563596D03*
X1562640Y1556331D03*
Y1559731D03*
X1559093Y1577295D03*
Y1574795D03*
X1565963D03*
X1568463D03*
X1565963Y1577295D03*
X1568463D03*
Y1579795D03*
X1565963D03*
X1568463Y1582295D03*
X1565963D03*
X1570963Y1574795D03*
Y1582295D03*
Y1579795D03*
Y1577295D03*
X1563463Y1574795D03*
Y1582295D03*
Y1579795D03*
Y1577295D03*
X1560051Y1581199D03*
X1574966Y1577038D03*
X1562556Y1584844D03*
X1560051Y1584099D03*
X1586291Y303596D03*
X1586621Y484304D03*
X1580519Y497650D03*
X1575570Y497847D03*
X1584397Y655622D03*
X1586497Y651222D03*
X1586597Y654222D03*
X1584397Y652722D03*
Y649822D03*
X1573975Y679975D03*
X1579244Y682635D03*
X1573975Y682483D03*
X1576964Y686160D03*
X1580737Y693550D03*
Y691009D03*
X1577588Y747282D03*
X1575014Y747188D03*
X1577498Y744688D03*
X1574998D03*
X1575088Y757282D03*
X1577588Y749782D03*
Y754782D03*
Y752282D03*
X1575014Y749688D03*
Y752188D03*
Y754688D03*
X1578690Y1283310D03*
X1585290Y1285098D03*
X1574168Y1283300D03*
X1577077Y1270937D03*
X1580577D03*
X1584068Y1271198D03*
X1580010Y1296100D03*
X1574560Y1296410D03*
X1580520Y1289900D03*
X1586167Y1295478D03*
X1575024Y1306373D03*
X1586557Y1304509D03*
X1578336Y1359253D03*
X1578411Y1348623D03*
X1578020Y1344773D03*
X1584156Y1381419D03*
X1586000Y1387641D03*
X1590723Y1381589D03*
X1603970Y222956D03*
X1593303Y234250D03*
Y239250D03*
X1598303Y234250D03*
X1596462Y229790D03*
X1593658Y252010D03*
X1593303Y244250D03*
X1593349Y248160D03*
X1597481Y271991D03*
X1600918Y521688D03*
X1604890Y531226D03*
X1596299Y536344D03*
X1599303Y646669D03*
X1602791Y648269D03*
X1600053Y649237D03*
X1596287Y655927D03*
X1591427D03*
X1593857D03*
X1588663Y649592D03*
Y652492D03*
X1590964Y661741D03*
Y658741D03*
X1594844Y713419D03*
Y715919D03*
X1592344D03*
Y713419D03*
X1594818Y710919D03*
X1594844Y718419D03*
X1592344D03*
X1594844Y720919D03*
X1592344D03*
X1594688Y723512D03*
Y726012D03*
Y728512D03*
Y731012D03*
X1592188Y723512D03*
Y726012D03*
Y728512D03*
Y731012D03*
X1594688Y736012D03*
X1592188D03*
X1594688Y733512D03*
X1592188D03*
X1594900Y780112D03*
X1598467Y1267539D03*
X1588832Y1269083D03*
X1597177Y1282288D03*
X1594152Y1282578D03*
X1598883Y1270766D03*
X1590827Y1271378D03*
X1593397Y1271458D03*
X1596273Y1271472D03*
X1591005Y1288892D03*
X1596363Y1286296D03*
X1590921Y1309276D03*
X1599241Y1306622D03*
X1589845Y1305289D03*
X1599007Y1309762D03*
X1597621Y1365384D03*
X1595438Y1370603D03*
X1592788Y1388318D03*
X1597234Y1382689D03*
X1600531Y1404710D03*
X1597992Y1433183D03*
X1595716Y1431861D03*
X1602782Y1435920D03*
X1600442Y1434535D03*
X1615020Y183050D03*
X1619909Y298742D03*
Y293742D03*
X1612144Y418552D03*
X1614701Y422587D03*
X1616464Y457509D03*
X1616250Y465042D03*
X1609166Y527300D03*
X1611775D03*
X1609166Y524700D03*
X1611775D03*
X1613169Y531819D03*
X1604991Y536344D03*
X1616084Y549105D03*
X1616198Y556364D03*
X1618859Y542820D03*
X1618356Y612137D03*
Y609137D03*
X1618434Y605753D03*
X1609044Y600986D03*
X1617397Y630822D03*
Y636622D03*
Y633722D03*
X1606745Y646206D03*
X1612014Y648866D03*
X1606745Y648714D03*
X1613507Y657240D03*
X1609734Y652391D03*
X1613507Y659781D03*
X1605644Y715919D03*
Y713419D03*
X1608144D03*
Y715919D03*
X1605628Y710919D03*
X1608128D03*
X1610628D03*
X1610718Y713513D03*
Y716013D03*
X1605644Y718419D03*
Y720919D03*
X1608144Y718419D03*
Y720919D03*
X1610718Y721013D03*
Y718513D03*
X1608118Y723512D03*
X1605618D03*
X1608118Y726012D03*
X1605618D03*
X1610618Y723512D03*
X1605618Y728512D03*
X1617200Y766870D03*
X1607267Y1271978D03*
X1604137Y1271358D03*
X1605801Y1286168D03*
X1608901Y1285887D03*
X1605360Y1294595D03*
X1608652Y1303338D03*
X1608341Y1313269D03*
X1608418Y1333589D03*
Y1331089D03*
X1614767Y1443512D03*
X1605648Y1437305D03*
X1622329Y28261D03*
X1623189Y48720D03*
X1631200Y164110D03*
X1631455Y167875D03*
X1627152Y168920D03*
X1629597Y227157D03*
X1627156Y238303D03*
X1627986Y282728D03*
X1627909Y286742D03*
Y298742D03*
Y294742D03*
Y290742D03*
X1619909Y303596D03*
X1627909Y302742D03*
X1621680Y366920D03*
X1625000Y383399D03*
X1631657Y392925D03*
X1632012Y603015D03*
X1621512D03*
X1625012D03*
X1628512D03*
X1632303Y627669D03*
X1633053Y630237D03*
X1626857Y636927D03*
X1629287D03*
X1624427D03*
X1621663Y630592D03*
X1619597Y635222D03*
X1621663Y633492D03*
X1619497Y632222D03*
X1623964Y642741D03*
Y639741D03*
X1627643Y694419D03*
Y696919D03*
Y699419D03*
X1625143D03*
Y696919D03*
Y694419D03*
X1627643Y701919D03*
X1625143D03*
X1627617Y691919D03*
X1625117D03*
Y709512D03*
Y704512D03*
Y707012D03*
Y712012D03*
X1627617Y709512D03*
Y704512D03*
Y707012D03*
Y712012D03*
X1628046Y763765D03*
X1626928Y1260917D03*
X1629428D03*
X1631928D03*
X1626333Y1311091D03*
Y1308091D03*
X1627174Y1420450D03*
X1625285Y1433384D03*
X1635281Y1422450D03*
X1627217Y1428366D03*
X1622697Y1440797D03*
X1625170Y1444016D03*
X1635227Y1436528D03*
X1636047Y224597D03*
Y229912D03*
X1647310Y408922D03*
Y411422D03*
X1635697Y561253D03*
X1635944Y609510D03*
Y612510D03*
X1636022Y606126D03*
X1647158Y618971D03*
X1639745Y627206D03*
X1646507Y640781D03*
X1645014Y629866D03*
X1639745Y629714D03*
X1635791Y629269D03*
X1646507Y638240D03*
X1642734Y633391D03*
X1638443Y699419D03*
Y696919D03*
Y694419D03*
Y701919D03*
X1640943Y694419D03*
Y696919D03*
Y699419D03*
Y701919D03*
X1643517Y702013D03*
Y699513D03*
Y694513D03*
Y697013D03*
X1643427Y691919D03*
X1640927D03*
X1638427D03*
X1640877Y706972D03*
Y709472D03*
X1638377D03*
Y704472D03*
Y706972D03*
X1640877Y704472D03*
X1643377Y709510D03*
Y704510D03*
Y707010D03*
X1640877Y711972D03*
X1638377D03*
X1643377Y712010D03*
X1635088Y767205D03*
Y771005D03*
X1644188Y766870D03*
X1634428Y1260917D03*
X1645163Y1276184D03*
X1641677Y1341488D03*
Y1344488D03*
X1641087Y1396118D03*
X1641065Y1403393D03*
X1644001Y1408069D03*
X1646483Y1412741D03*
X1641065Y1406393D03*
X1635619Y1430536D03*
X1639834Y1434478D03*
X1636167Y1446746D03*
X1642400Y1439674D03*
X1645979Y1437950D03*
X1650400Y1437820D03*
X1641167Y1446746D03*
X1646879Y1681738D03*
X1645029Y1715609D03*
Y1710609D03*
X1648029Y1708609D03*
Y1723759D03*
X1645029Y1725759D03*
Y1730759D03*
X1652525Y146762D03*
Y151762D03*
Y161762D03*
X1650023Y221842D03*
X1654419Y224597D03*
X1659419D03*
X1650023Y227157D03*
X1654419Y229912D03*
X1661928Y230172D03*
X1650020Y408952D03*
Y411452D03*
X1654110Y434177D03*
X1657545Y434506D03*
X1650035Y434750D03*
X1657194Y599956D03*
X1651194D03*
X1660194Y609450D03*
X1654194D03*
X1660194Y599956D03*
X1657194Y609450D03*
X1654194Y599956D03*
X1651194Y609450D03*
X1654147Y616523D03*
X1662377Y696300D03*
Y693300D03*
X1651072Y1314137D03*
X1660572Y1313837D03*
X1660635Y1329166D03*
X1651072Y1323137D03*
Y1320137D03*
Y1317137D03*
X1660572Y1322837D03*
Y1319837D03*
X1660635Y1326466D03*
X1660572Y1316837D03*
X1658015Y1328966D03*
X1658115Y1326466D03*
X1660635Y1331666D03*
Y1334166D03*
Y1339166D03*
Y1336666D03*
X1650177Y1341488D03*
X1658277Y1341888D03*
X1658015Y1336466D03*
Y1338966D03*
Y1331466D03*
Y1333966D03*
X1650177Y1344488D03*
X1658677D03*
X1653390Y1386316D03*
Y1388857D03*
X1649197Y1396743D03*
X1654883Y1397231D03*
X1660152Y1397383D03*
X1664106Y1397828D03*
X1660152Y1399891D03*
X1657163Y1393706D03*
X1661807Y1416948D03*
X1663777Y1421568D03*
X1662487Y1424178D03*
X1658089Y1437444D03*
X1649380Y1446713D03*
X1659975Y1592929D03*
X1656101Y1671720D03*
X1651101Y1671833D03*
X1653930Y1660640D03*
X1656180Y1659220D03*
X1656849Y1664949D03*
X1651698Y1665045D03*
X1661125Y1690751D03*
X1656101Y1701094D03*
X1656997Y1718759D03*
Y1733909D03*
X1673100Y121762D03*
Y136762D03*
Y131762D03*
X1673403Y199997D03*
X1664335Y210191D03*
X1663310Y215488D03*
X1664789Y767265D03*
Y771065D03*
X1673889Y766870D03*
X1674972Y1313837D03*
X1675134Y1329219D03*
X1675234Y1326519D03*
X1674972Y1316837D03*
X1672623Y1326476D03*
X1663437Y1326526D03*
X1674972Y1319837D03*
Y1322837D03*
X1677754Y1326519D03*
Y1329019D03*
X1663437Y1334726D03*
X1672623Y1334676D03*
X1663437Y1329726D03*
X1672623Y1332176D03*
X1663437Y1332226D03*
X1672623Y1329676D03*
X1675134Y1331719D03*
Y1334219D03*
Y1336719D03*
Y1339219D03*
X1677754Y1339019D03*
Y1336519D03*
Y1331519D03*
Y1334019D03*
X1675931Y1384335D03*
Y1387235D03*
X1667594Y1399428D03*
X1666844Y1396860D03*
X1675470Y1390170D03*
X1673040D03*
X1670610D03*
X1672501Y1416678D03*
X1675641Y1432891D03*
X1672401Y1423365D03*
X1664237Y1426278D03*
X1671079Y1435069D03*
X1663239Y1428592D03*
X1670147Y1444311D03*
X1676685Y1537893D03*
X1671034Y1549734D03*
Y1552234D03*
X1668703Y1550898D03*
X1671034Y1546934D03*
X1668827Y1553551D03*
X1671034Y1557234D03*
Y1554734D03*
X1673706Y1560425D03*
X1671006Y1576744D03*
Y1574244D03*
Y1571744D03*
X1668826Y1575498D03*
Y1572998D03*
X1676176Y1580650D03*
X1674923Y1582973D03*
X1677556Y1656405D03*
X1674356D03*
X1671156D03*
X1666168Y1667688D03*
X1670202Y1663150D03*
X1675290Y1663157D03*
X1674338Y1677832D03*
X1671902Y1676267D03*
X1669377Y1675241D03*
X1670773Y1688827D03*
X1680029Y1710609D03*
Y1715609D03*
X1672500Y1708927D03*
X1675360Y1721252D03*
X1695100Y121762D03*
X1683275Y120762D03*
X1695100Y136762D03*
Y131762D03*
X1684925D03*
Y136762D03*
Y123762D03*
Y126762D03*
Y145762D03*
X1695100Y146762D03*
X1684925Y141762D03*
X1695100Y156762D03*
Y161762D03*
Y166762D03*
X1684925Y157762D03*
Y166762D03*
X1678809Y206451D03*
X1682433Y220857D03*
X1682408Y228337D03*
X1689000Y234000D03*
X1692429Y403985D03*
X1694050Y416643D03*
X1690208Y421855D03*
X1690140Y434160D03*
X1692450Y436772D03*
X1692974Y553115D03*
X1685890Y708610D03*
X1684672Y1313837D03*
X1690697Y1329066D03*
Y1326566D03*
X1684672Y1322837D03*
Y1319837D03*
Y1316837D03*
X1690697Y1336566D03*
Y1334066D03*
Y1331566D03*
X1679028Y1341733D03*
X1687234Y1341533D03*
Y1344033D03*
X1679028Y1344233D03*
X1690697Y1339066D03*
X1686172Y1386416D03*
Y1388957D03*
X1687665Y1397331D03*
X1692934Y1397483D03*
Y1399991D03*
X1689945Y1393806D03*
X1682500Y1390475D03*
X1680300Y1391875D03*
X1682500Y1396275D03*
X1680400Y1394875D03*
X1678234Y1393605D03*
Y1396505D03*
X1682500Y1393375D03*
X1683741Y1443075D03*
X1681538Y1451522D03*
X1689062Y1451496D03*
X1687783Y1472068D03*
X1685745Y1552579D03*
X1686219Y1549994D03*
X1685745Y1555079D03*
Y1557579D03*
X1685995Y1561516D03*
X1680589Y1559626D03*
Y1563526D03*
X1690353Y1591494D03*
X1680695Y1656307D03*
X1686675Y1659287D03*
X1692415Y1663740D03*
X1685500Y1663599D03*
X1680367Y1663367D03*
X1691952Y1698947D03*
X1689184Y1702095D03*
X1683029Y1708609D03*
X1680877Y1723593D03*
X1692218Y1717539D03*
X1685383Y1729559D03*
X1707186Y15708D03*
X1703583Y26505D03*
X1700183D03*
X1703536Y50649D03*
X1700136D03*
X1695100Y126762D03*
Y141762D03*
Y151762D03*
X1705120Y143610D03*
X1693000Y234000D03*
X1698220Y369652D03*
X1699809Y403985D03*
X1695579D03*
X1702959Y404243D03*
X1697161Y406602D03*
X1706500Y415862D03*
Y413362D03*
X1707780Y410738D03*
X1695455Y422287D03*
X1707568Y420370D03*
X1701124Y423802D03*
X1707544Y431745D03*
X1704974Y553115D03*
X1700974D03*
X1696974D03*
X1693490Y620672D03*
X1697530Y636369D03*
X1701661Y644554D03*
X1705561D03*
X1699500Y654738D03*
Y673738D03*
X1694490Y767265D03*
Y771065D03*
X1708049Y766870D03*
X1699072Y1313737D03*
X1696047Y1326576D03*
X1705383D03*
X1693417Y1329266D03*
X1693217Y1326566D03*
X1699072Y1322737D03*
Y1319737D03*
Y1316737D03*
X1693417Y1334266D03*
Y1331766D03*
X1705383Y1334676D03*
X1696047D03*
X1705383Y1329676D03*
X1696047Y1332176D03*
Y1329676D03*
X1705383Y1332176D03*
X1693417Y1336766D03*
Y1339266D03*
X1700376Y1399528D03*
X1696888Y1397928D03*
X1699626Y1396960D03*
X1703392Y1390270D03*
X1705822D03*
X1700272Y1460547D03*
X1702281Y1449801D03*
X1705108Y1451774D03*
X1695020Y1465621D03*
X1698440Y1466590D03*
X1705246Y1465325D03*
X1701348Y1466557D03*
X1709964Y1597490D03*
X1709833Y1612940D03*
Y1606340D03*
X1701984Y1671618D03*
X1695987D03*
X1700156Y1698830D03*
X1702750Y1696185D03*
X1706086Y1691568D03*
X1717148Y19910D03*
X1712977Y19986D03*
X1722148Y19910D03*
X1722085Y25908D03*
X1717055D03*
X1710106Y39768D03*
X1723241Y48822D03*
X1710106Y48978D03*
X1721646Y68115D03*
X1716558Y67866D03*
X1715861Y72593D03*
X1712486Y117908D03*
X1712686Y111908D03*
X1719909Y112713D03*
Y116713D03*
X1713399Y132858D03*
X1721384Y135373D03*
X1717384D03*
X1716609Y141297D03*
X1721628Y147312D03*
X1714293Y156278D03*
X1711293D03*
X1716893D03*
X1719493D03*
X1722093D03*
X1711293Y158878D03*
X1714293D03*
X1711293Y161478D03*
X1714293D03*
X1711293Y163978D03*
X1714293D03*
X1711293Y166478D03*
X1714293D03*
X1722093Y158878D03*
X1719493D03*
X1716893D03*
X1722093Y161478D03*
Y163978D03*
Y166478D03*
X1719493Y161478D03*
X1716893D03*
X1719493Y163978D03*
X1716893D03*
Y166478D03*
X1719493D03*
X1719200Y371162D03*
X1717220Y381152D03*
X1713720D03*
X1717220Y384652D03*
Y388152D03*
X1713720D03*
Y384652D03*
X1717220Y391652D03*
X1713720D03*
X1709000Y415862D03*
Y413362D03*
X1709339Y637251D03*
X1718465Y657982D03*
X1720050Y649142D03*
X1716030Y668182D03*
X1709759Y670221D03*
X1718686Y676154D03*
X1722672Y1313237D03*
X1708672Y1313737D03*
X1707916Y1329319D03*
X1722672Y1316237D03*
X1708672Y1322737D03*
Y1319737D03*
X1710536Y1329119D03*
X1708016Y1326619D03*
X1710536D03*
X1722672Y1319237D03*
Y1322237D03*
X1719916Y1326559D03*
X1717396D03*
X1719916Y1329059D03*
X1717396D03*
X1708672Y1316737D03*
X1707916Y1334319D03*
Y1331819D03*
Y1339319D03*
Y1336819D03*
X1710536Y1336619D03*
Y1339119D03*
X1719916Y1339059D03*
X1717396D03*
X1719916Y1336559D03*
X1717396D03*
X1710536Y1334119D03*
Y1331619D03*
X1719916Y1331559D03*
Y1334059D03*
X1717396D03*
Y1331559D03*
X1710176Y1342089D03*
X1718706Y1341629D03*
Y1344129D03*
X1710176Y1344589D03*
X1708713Y1384435D03*
Y1387335D03*
X1708252Y1390270D03*
X1715282Y1396375D03*
X1713082Y1391975D03*
X1715282Y1390575D03*
X1711016Y1393705D03*
Y1396605D03*
X1713182Y1394975D03*
X1715282Y1393475D03*
X1717447Y1417213D03*
X1714447D03*
X1717447Y1423213D03*
Y1420213D03*
X1714447D03*
Y1423213D03*
X1722334Y1468146D03*
X1718425Y1468245D03*
X1722347Y1471246D03*
X1716070Y1472037D03*
X1712870Y1586615D03*
X1715693Y1597190D03*
X1713593Y1609640D03*
Y1603040D03*
X1720845Y1668498D03*
X1719181Y1706712D03*
X1721172Y1712115D03*
X1710360Y1706502D03*
X1721912Y1705115D03*
X1719218Y1727265D03*
X1719148Y1721530D03*
X1722149Y1720265D03*
X1710230Y1729654D03*
X1729557Y-35912D03*
Y-32512D03*
X1736006Y41838D03*
Y44338D03*
X1729836Y54524D03*
X1727336D03*
X1724685Y51454D03*
X1727225Y51424D03*
X1729895Y51354D03*
X1726741Y48822D03*
X1730241D03*
X1737617Y75640D03*
Y73140D03*
Y79140D03*
Y81640D03*
X1722984Y101713D03*
X1723184Y93313D03*
X1736731Y102293D03*
X1728965Y112941D03*
X1729046Y118178D03*
X1739686Y120938D03*
X1725093Y156278D03*
Y158878D03*
Y161478D03*
Y163978D03*
Y166478D03*
X1735471Y293682D03*
Y290682D03*
Y296682D03*
Y299682D03*
X1730331Y293722D03*
Y296722D03*
X1732831D03*
X1730331Y299722D03*
X1732831D03*
Y293722D03*
X1723492Y293068D03*
X1732751Y305732D03*
X1730251D03*
X1732751Y302732D03*
X1730251D03*
X1735391Y305692D03*
Y302692D03*
X1725344Y359334D03*
X1728300Y377787D03*
X1733043Y657091D03*
X1736848Y650974D03*
X1726409Y653641D03*
X1737002Y671494D03*
X1724191Y767299D03*
Y771099D03*
X1737850Y766794D03*
X1732702Y1313007D03*
Y1316007D03*
Y1322007D03*
Y1319007D03*
X1732766Y1410562D03*
Y1413062D03*
X1735266Y1410562D03*
Y1413062D03*
X1732766Y1426362D03*
Y1428862D03*
X1735266Y1426362D03*
Y1428862D03*
X1730004Y1540968D03*
X1726604Y1540970D03*
X1735379Y1566282D03*
X1735354Y1580480D03*
X1735351Y1569832D03*
X1736479Y1584330D03*
X1730202Y1602093D03*
X1735463Y1651965D03*
X1730381Y1647386D03*
X1726381D03*
X1734500Y1656965D03*
X1734589Y1666203D03*
X1734962Y1662965D03*
X1734963Y1673465D03*
X1724263Y1672465D03*
X1734763Y1680465D03*
X1735463Y1694465D03*
X1725423Y1692656D03*
X1731936Y1690165D03*
X1731117Y1715265D03*
X1732251Y1708265D03*
X1731117Y1730415D03*
X1748708Y26641D03*
X1751031Y39063D03*
X1738093Y53103D03*
Y55603D03*
X1741621Y76613D03*
Y74113D03*
Y82613D03*
Y80113D03*
X1743491Y92827D03*
X1738435Y100244D03*
X1741935D03*
X1745435D03*
X1740231Y102293D03*
X1743731D03*
X1748686Y97408D03*
X1740091Y92827D03*
X1750786Y120018D03*
X1744976Y122998D03*
X1754339Y128242D03*
X1752022Y269794D03*
Y266794D03*
X1742971Y293682D03*
Y290682D03*
X1737971D03*
X1740471Y293682D03*
Y290682D03*
Y299682D03*
X1737971D03*
X1740471Y296682D03*
X1737971D03*
Y293682D03*
X1751352Y293386D03*
X1745671Y290682D03*
Y293682D03*
X1737891Y302692D03*
X1740391D03*
X1737891Y305692D03*
X1740391D03*
X1744510Y377452D03*
X1744380Y382892D03*
X1742398Y484304D03*
X1742306Y661032D03*
X1745484Y668216D03*
X1751490Y713890D03*
X1748990D03*
X1746490D03*
X1743990D03*
X1751490Y706390D03*
X1748990D03*
X1746490D03*
X1743990D03*
X1751490Y708890D03*
X1748990D03*
X1746490D03*
X1743990D03*
X1751490Y711390D03*
X1748990D03*
X1746490D03*
X1743990D03*
X1742766Y1418462D03*
Y1415962D03*
X1737766Y1410562D03*
Y1413062D03*
X1740266Y1410562D03*
Y1413062D03*
X1742766D03*
Y1410562D03*
X1740266Y1415962D03*
Y1418462D03*
X1737766Y1426362D03*
Y1428862D03*
X1742766Y1423462D03*
X1740266Y1426362D03*
Y1423462D03*
Y1420962D03*
X1742766D03*
X1741329Y1506405D03*
Y1503405D03*
Y1509405D03*
Y1512405D03*
X1745543Y1518678D03*
X1742758Y1521239D03*
X1745746D03*
X1751120Y1521223D03*
X1751087Y1518704D03*
X1748346Y1521223D03*
X1748313Y1518704D03*
X1739565Y1528105D03*
X1751132Y1526748D03*
Y1524248D03*
Y1529248D03*
X1742810Y1524534D03*
X1745410D03*
X1748358Y1526748D03*
Y1524248D03*
Y1529248D03*
X1746779Y1583378D03*
X1751558Y1579332D03*
X1746079Y1587705D03*
X1750463Y1654465D03*
X1744963Y1656465D03*
X1744463Y1651229D03*
X1747986Y1686215D03*
X1751340Y1686140D03*
X1744620Y1716018D03*
X1750380Y1707468D03*
X1747120Y1710824D03*
X1749480Y1718158D03*
X1765920Y17031D03*
X1765980Y27031D03*
X1765920Y22031D03*
X1758638Y26477D03*
X1755238D03*
X1767266Y48748D03*
X1763010Y51223D03*
X1765527Y53692D03*
X1758635Y50649D03*
X1755235D03*
X1757923Y72637D03*
X1767956Y76843D03*
X1767136Y83653D03*
X1761417Y90017D03*
X1760444Y106173D03*
X1763644D03*
X1755944Y111073D03*
Y108473D03*
X1760944Y116773D03*
X1757944D03*
X1760124Y128246D03*
X1755504Y202263D03*
X1758030D03*
X1762564Y202326D03*
X1765090D03*
X1761573Y266657D03*
X1764573D03*
X1761573Y269657D03*
X1764573D03*
X1758022Y269794D03*
Y266794D03*
X1755022Y269794D03*
Y266794D03*
X1755772Y278859D03*
X1758772D03*
X1761772D03*
X1755772Y281859D03*
X1758772D03*
X1761772D03*
X1752772Y278859D03*
Y281859D03*
X1756800Y364048D03*
Y368048D03*
X1756933Y372452D03*
X1759379Y507927D03*
X1753566Y512968D03*
X1768041Y556537D03*
X1753990Y711390D03*
Y708890D03*
Y706390D03*
Y713890D03*
X1753891Y767305D03*
Y771105D03*
X1767450Y766870D03*
X1759949Y1297324D03*
X1764267Y1460080D03*
X1756329Y1506405D03*
Y1503405D03*
X1764029Y1506405D03*
Y1503405D03*
X1756329Y1509405D03*
Y1512405D03*
X1764029Y1509405D03*
Y1512405D03*
X1765286Y1518471D03*
X1765176Y1515902D03*
X1765286Y1521095D03*
X1765246Y1524001D03*
Y1526601D03*
X1765334Y1529342D03*
X1764679Y1572105D03*
X1765679Y1575405D03*
X1762679D03*
X1766079Y1578705D03*
X1763079D03*
X1753512Y1583478D03*
X1763706Y1616451D03*
X1760206D03*
X1767206D03*
X1765854Y1646456D03*
X1755463Y1654465D03*
X1767888Y1664465D03*
X1762263Y1671765D03*
X1765163Y1670543D03*
X1765463Y1677465D03*
X1761463Y1683465D03*
X1775920Y17031D03*
X1770920D03*
X1775920Y27068D03*
X1770920Y22031D03*
X1775920D03*
X1768956Y37558D03*
X1777720Y37792D03*
X1773830Y49000D03*
X1779377Y50738D03*
X1774294Y60133D03*
X1774291Y57191D03*
X1769240Y50788D03*
X1769200Y54300D03*
X1780300Y54400D03*
X1775546Y73376D03*
X1774294Y63033D03*
X1779744Y72973D03*
Y70073D03*
X1770334Y72737D03*
X1778205Y90982D03*
X1781451Y88238D03*
X1773577Y88339D03*
X1778544Y97973D03*
X1769244Y113773D03*
Y110973D03*
Y108073D03*
X1781368Y162824D03*
X1780929Y179408D03*
X1776930Y179051D03*
X1773581Y194120D03*
X1771055D03*
X1771931Y200920D03*
X1769405D03*
X1777170Y201002D03*
X1774644D03*
X1778796Y261633D03*
X1767573Y266657D03*
X1775633Y261666D03*
X1767573Y269657D03*
X1778796Y266633D03*
Y269133D03*
Y264133D03*
X1775633Y269166D03*
Y266666D03*
Y264166D03*
X1778796Y271633D03*
X1775633Y271666D03*
X1770280Y372452D03*
X1770220Y382952D03*
Y377452D03*
X1782324Y403932D03*
Y410432D03*
Y418932D03*
Y425432D03*
X1779376Y558324D03*
X1782376D03*
X1773963Y557537D03*
X1776986Y749023D03*
X1776550Y763765D03*
X1769650Y1280200D03*
X1771000Y1278060D03*
X1782369Y1447581D03*
X1782385Y1450095D03*
X1782337Y1453191D03*
X1775682Y1466568D03*
X1779029Y1506405D03*
Y1503405D03*
Y1509405D03*
Y1512405D03*
X1780012Y1518631D03*
Y1516031D03*
Y1521231D03*
X1777152Y1518631D03*
Y1516031D03*
Y1521231D03*
X1774552D03*
Y1516031D03*
Y1518631D03*
X1768176Y1515902D03*
X1768286Y1518471D03*
Y1521095D03*
X1770886D03*
Y1518471D03*
X1770776Y1515902D03*
X1780039Y1523860D03*
Y1526360D03*
X1779997Y1528888D03*
X1777179Y1526360D03*
Y1523860D03*
X1774579D03*
Y1526360D03*
X1768246Y1526601D03*
Y1524001D03*
X1768334Y1529342D03*
X1770846Y1524001D03*
Y1526601D03*
X1771079Y1566782D03*
X1770404Y1575330D03*
X1780579Y1582178D03*
X1771094Y1570332D03*
X1778794Y1585332D03*
X1768105Y1595925D03*
X1775794Y1585332D03*
X1768030Y1599249D03*
X1768180Y1606549D03*
X1768030Y1603149D03*
X1780154Y1615026D03*
X1777454D03*
X1780154Y1617726D03*
X1777454D03*
X1773349Y1631938D03*
Y1634438D03*
Y1636938D03*
X1770649Y1631938D03*
Y1634438D03*
X1781423Y1634394D03*
Y1636894D03*
X1778723Y1634294D03*
X1776023D03*
Y1636894D03*
X1778723D03*
X1773929Y1657465D03*
Y1654956D03*
X1768929Y1651956D03*
X1774338Y1676865D03*
X1771038Y1692956D03*
X1787826Y37548D03*
X1783700Y50011D03*
X1794099Y50461D03*
X1788204Y74958D03*
X1785108Y76078D03*
X1787756Y85178D03*
X1788204Y82338D03*
Y78108D03*
X1784144Y113973D03*
Y111173D03*
Y108273D03*
X1797692Y146285D03*
X1784006Y137395D03*
X1788950Y142750D03*
X1787390Y165834D03*
Y156834D03*
Y151834D03*
X1793444Y178083D03*
X1785320Y193072D03*
X1784915Y186053D03*
X1783896Y266633D03*
Y269133D03*
X1794174Y274499D03*
X1790674D03*
X1783896Y271633D03*
X1789771Y367866D03*
X1797929Y385293D03*
X1786260Y379059D03*
X1792507Y403932D03*
X1792335Y418775D03*
X1792450Y410615D03*
X1792220Y425432D03*
X1785376Y558324D03*
X1788376D03*
X1792895Y683536D03*
X1783592Y767565D03*
Y771365D03*
X1792692Y766870D03*
X1794362Y1275546D03*
X1785336Y1447565D03*
Y1450065D03*
X1785634Y1456326D03*
X1782530Y1456229D03*
X1785408Y1453385D03*
X1788029Y1506405D03*
Y1503405D03*
Y1509405D03*
Y1512405D03*
X1794265Y1518262D03*
Y1520862D03*
Y1523462D03*
Y1526062D03*
X1794268Y1528720D03*
X1784601Y1578967D03*
X1787239Y1579406D03*
X1789294Y1583278D03*
X1797118Y1596588D03*
X1797143Y1607014D03*
X1797076Y1603662D03*
X1797043Y1599811D03*
X1791979Y1616550D03*
X1795479D03*
X1782654Y1615026D03*
Y1617726D03*
X1784048Y1636875D03*
Y1634375D03*
X1786615Y1631800D03*
X1786588Y1634472D03*
X1786624Y1637021D03*
X1802565Y156557D03*
X1800554Y177229D03*
X1808622Y170869D03*
X1806470Y186866D03*
X1802570Y186913D03*
X1811274Y198098D03*
X1807596Y264133D03*
Y266633D03*
Y269133D03*
X1797674Y274499D03*
X1801174D03*
X1807596Y271633D03*
X1800160Y362542D03*
X1808962Y698055D03*
Y700555D03*
Y703055D03*
X1798462Y698055D03*
X1801962D03*
X1805462D03*
Y700555D03*
X1801962D03*
X1798462D03*
X1805462Y703055D03*
X1801962D03*
X1798462D03*
X1808962Y705555D03*
Y708055D03*
X1798462Y705555D03*
X1801962D03*
X1805462D03*
X1798462Y708055D03*
X1801962D03*
X1805462D03*
X1809002Y710945D03*
Y713445D03*
Y715945D03*
X1805502Y710945D03*
Y713445D03*
Y715945D03*
X1802050Y710940D03*
X1811526Y1281671D03*
X1803029Y1506405D03*
Y1503405D03*
X1812029Y1506405D03*
Y1503405D03*
X1803029Y1509405D03*
Y1512405D03*
X1812029Y1509405D03*
Y1512405D03*
X1797362Y1518304D03*
X1799882Y1520912D03*
Y1518312D03*
X1797362Y1520904D03*
X1804049Y1528031D03*
X1799882Y1523512D03*
X1797362Y1523504D03*
X1799882Y1526112D03*
X1797362Y1526104D03*
X1799994Y1528674D03*
X1797450Y1528768D03*
X1809890Y1524532D03*
X1807290D03*
X1798479Y1575605D03*
X1798879Y1578905D03*
X1801479Y1575605D03*
X1800479Y1572305D03*
X1801879Y1578905D03*
X1798979Y1616550D03*
X1815005Y149325D03*
X1817196Y163797D03*
Y159947D03*
X1818828Y175241D03*
X1817275Y180619D03*
X1813224Y194699D03*
X1816190Y208879D03*
X1817157Y373829D03*
X1828669Y379552D03*
X1816994Y398052D03*
X1816224Y410432D03*
X1822724Y424948D03*
X1815724Y423932D03*
X1825874Y424948D03*
X1822394Y436225D03*
X1827073Y565157D03*
X1824073D03*
X1821073D03*
X1812462Y698055D03*
Y700555D03*
Y703055D03*
Y705555D03*
Y708055D03*
X1812502Y710945D03*
Y713445D03*
Y715945D03*
X1827029Y1506405D03*
Y1503405D03*
Y1509405D03*
Y1512405D03*
X1818475Y1524682D03*
X1815875D03*
X1823649Y1525144D03*
X1831166Y149986D03*
X1827580Y151834D03*
X1829732Y371329D03*
X1828483Y431678D03*
X1833288Y1469639D03*
X1850791Y170287D03*
G54D30*
X180780Y1507509D03*
X178580D03*
X177487Y1521612D03*
X177086Y1518121D03*
X178745Y1513218D03*
X177533Y1535698D03*
Y1537898D03*
X178980Y1540317D03*
X183051Y1544625D03*
X225950Y1516970D03*
X230674D03*
X227525Y1519698D03*
X235399Y1516970D03*
X240123D03*
X244848D03*
X236974Y1519698D03*
X241698D03*
X246422D03*
X232249D03*
X249572Y1516970D03*
X254297D03*
X259021D03*
X251147Y1519698D03*
X255871D03*
X260596D03*
X265421Y1507355D03*
X263321D03*
X266828Y1514073D03*
X266772Y1516336D03*
X267123Y1536640D03*
Y1534540D03*
X267124Y1531618D03*
X267035Y1528698D03*
X266538Y1538658D03*
X305549Y1521612D03*
X305148Y1518121D03*
X305595Y1535698D03*
Y1537898D03*
X316107Y895569D03*
X314256Y905135D03*
Y924269D03*
X316107Y914702D03*
Y933836D03*
Y952970D03*
X314256Y943403D03*
Y962537D03*
X316107Y972104D03*
X314256Y981671D03*
Y1000805D03*
X316107Y991238D03*
X317957Y988049D03*
X317288Y1028056D03*
X313587D03*
X320988D03*
X315437Y1037623D03*
X319138Y1031245D03*
X315437Y1056757D03*
X317288Y1047190D03*
X319138Y1056757D03*
X320988Y1047190D03*
X317288Y1066324D03*
Y1085458D03*
X315437Y1075891D03*
X317288Y1104592D03*
X315437Y1095025D03*
Y1114159D03*
Y1133293D03*
X317288Y1123726D03*
Y1142859D03*
X315437Y1158804D03*
Y1152426D03*
X319138Y1158804D03*
X308893Y1507460D03*
X306807Y1513218D03*
X311113Y1544625D03*
X307042Y1540317D03*
X327209Y882813D03*
X323508D03*
X332760Y988049D03*
X323508Y991238D03*
Y1010372D03*
X324689Y1028056D03*
X332091D03*
X333941Y1031245D03*
X326540Y1044001D03*
X333941Y1056757D03*
X332091Y1047190D03*
X324689Y1053568D03*
X332091Y1161993D03*
X333941Y1165182D03*
X326539D03*
X324689Y1161993D03*
X342012Y895569D03*
X340162Y905135D03*
Y924269D03*
X342012Y914702D03*
Y933836D03*
Y952970D03*
X340162Y943403D03*
Y962537D03*
X342012Y972104D03*
X340162Y981671D03*
Y1000805D03*
X342012Y991238D03*
X338311D03*
X349414D03*
X343862Y988049D03*
X338311Y1010372D03*
X349414D03*
X343193Y1028056D03*
X350595D03*
X339492D03*
X346894D03*
X341343Y1037623D03*
X337642Y1044001D03*
X345043Y1031245D03*
X341343Y1056757D03*
X343193Y1047190D03*
X339492Y1053568D03*
X345043Y1056757D03*
X346894Y1047190D03*
X350595Y1053568D03*
X343193Y1066324D03*
Y1085458D03*
X341343Y1075891D03*
Y1095025D03*
X343193Y1104592D03*
X341343Y1114159D03*
X343193Y1123726D03*
X341343Y1133293D03*
X343193Y1142859D03*
X339492Y1161993D03*
X341343Y1165182D03*
X350595Y1161993D03*
X341343Y1152426D03*
X345043Y1158804D03*
X364217Y876435D03*
X358665Y879624D03*
X364217Y991238D03*
X358666Y988049D03*
X364217Y1010372D03*
X365398Y1028056D03*
X357996D03*
X363547Y1044001D03*
X359847Y1031245D03*
X352445Y1044001D03*
X359847Y1056757D03*
X357996Y1047190D03*
X365398Y1053568D03*
X359847Y1165182D03*
X357996Y1161993D03*
X352445Y1165182D03*
X365398Y1161993D03*
X367917Y876435D03*
X371618D03*
X379020D03*
X369768Y873246D03*
X373469D03*
X377169D03*
X371618Y882813D03*
X375319D03*
X379020Y889191D03*
X367917Y895569D03*
X366067Y905135D03*
X379020Y901947D03*
X366067Y924269D03*
X367917Y914702D03*
X379020D03*
X367917Y933836D03*
X379020Y927458D03*
X366067Y943403D03*
X367917Y952970D03*
X379020Y946592D03*
X366067Y962537D03*
X379020Y959348D03*
X366067Y981671D03*
X367917Y972104D03*
X379020D03*
X366067Y1000805D03*
X367917Y991238D03*
X375319D03*
X369768Y988049D03*
X379020Y1010372D03*
X375319D03*
X369099Y1028056D03*
X376500D03*
X372799D03*
X367248Y1037623D03*
X378351Y1044001D03*
X370949Y1031245D03*
X367248Y1056757D03*
X369099Y1047190D03*
X370949Y1056757D03*
X372799Y1047190D03*
X376500Y1053568D03*
X369099Y1066324D03*
X380201D03*
X367248Y1075891D03*
X369099Y1085458D03*
X380201Y1079080D03*
Y1091836D03*
X367248Y1095025D03*
X369099Y1104592D03*
X367248Y1114159D03*
X380201Y1110970D03*
X369099Y1123726D03*
X367248Y1133293D03*
X380201Y1123726D03*
Y1149237D03*
X369099Y1142859D03*
X380201Y1136481D03*
X378351Y1165182D03*
X374650D03*
X367248Y1158804D03*
X370949D03*
X369099Y1161993D03*
X372799D03*
X380201D03*
X367248Y1152426D03*
X393823Y876435D03*
X382721D03*
X390122D03*
X380870Y879624D03*
X384571D03*
X380870Y873246D03*
X391973D03*
X395673D03*
Y879624D03*
X391973D03*
Y886002D03*
X393823Y895569D03*
X380870Y886002D03*
X382721Y895569D03*
X390122Y889191D03*
X386421Y895569D03*
X395673Y886002D03*
X393823Y908325D03*
X386421D03*
X382721D03*
X393823Y921080D03*
X382721D03*
X386421D03*
X393823Y940214D03*
X382721D03*
X386421D03*
X380870Y937025D03*
X395673D03*
X388272D03*
X391973D03*
X384571D03*
X393823Y952970D03*
X382721D03*
X386421D03*
X393823Y965726D03*
X382721D03*
X386421D03*
X380870Y981671D03*
X382721Y984860D03*
X388272Y981671D03*
X390122Y984860D03*
X386421Y978482D03*
X393823D03*
X395673Y981671D03*
X382721Y978482D03*
X395673Y994427D03*
Y988049D03*
Y1000805D03*
X380870Y988049D03*
Y994427D03*
X382721Y997616D03*
Y991238D03*
X380870Y1000805D03*
X388272Y994427D03*
X390122Y997616D03*
X388272Y988049D03*
X390122Y991238D03*
X388272Y1000805D03*
X380870Y1007183D03*
X382721Y1003994D03*
X388272Y1007183D03*
X390122Y1003994D03*
X393823Y1010372D03*
X386421D03*
X391303Y1028056D03*
X383902D03*
X382051Y1031245D03*
Y1037623D03*
Y1044001D03*
X391303Y1034434D03*
X389453Y1037623D03*
X391303Y1040812D03*
X389453Y1044001D03*
Y1031245D03*
X383902Y1040812D03*
Y1034434D03*
X395004Y1059946D03*
X383902D03*
X387603D03*
X389453Y1056757D03*
X382051Y1050379D03*
X391303Y1047190D03*
X383902D03*
X391303Y1053568D03*
X389453Y1050379D03*
X383902Y1053568D03*
X385752Y1056757D03*
X382051D03*
X395004Y1072702D03*
X383902D03*
X387603D03*
X395004Y1085458D03*
X383902D03*
X387603D03*
X395004Y1098214D03*
X383902D03*
X387603D03*
X382051Y1101403D03*
X393154D03*
X389453D03*
X385752D03*
X395004Y1117348D03*
X387603D03*
X383902D03*
X395004Y1130103D03*
X387603D03*
X383902D03*
X395004Y1142859D03*
X387603D03*
X383902D03*
X391303Y1149237D03*
X382051Y1152426D03*
X383902Y1161993D03*
X391303D03*
X395004D03*
X393154Y1152426D03*
X393483Y1507355D03*
X391383D03*
X394890Y1514073D03*
X394834Y1516336D03*
X395185Y1536640D03*
Y1534540D03*
X395186Y1531618D03*
X395097Y1528698D03*
X394600Y1538658D03*
X404925Y876435D03*
X401225D03*
X403075Y879624D03*
X406776D03*
X403075Y873246D03*
X397524Y895569D03*
X403075Y886002D03*
X401225Y889191D03*
X408626Y895569D03*
X404925D03*
X406776Y886002D03*
X410477D03*
X399374D03*
X397524Y908325D03*
X408626D03*
X404925Y908324D03*
X397524Y921080D03*
X408626D03*
X404925D03*
X397524Y940214D03*
X410477Y930647D03*
X406776D03*
X408626Y940214D03*
X404925D03*
X403075Y937025D03*
X404925Y933836D03*
X410477Y937025D03*
X408626Y933836D03*
X399374Y937025D03*
X406776D03*
X397524Y952970D03*
X408626D03*
X404925D03*
X397524Y965726D03*
X408626D03*
X404925D03*
X397524Y978482D03*
Y984860D03*
X404925Y978482D03*
X408626D03*
X410477Y981671D03*
X403075D03*
X404925Y984860D03*
X397524Y991238D03*
X410477Y988049D03*
X403075D03*
X404925Y991238D03*
X397524Y997616D03*
X403075Y994427D03*
Y1000805D03*
X401225Y1010372D03*
X397524Y1003994D03*
X406763Y1007175D03*
X403075Y1007183D03*
X406094Y1028064D03*
X402406Y1028056D03*
X406104Y1040820D03*
X404256Y1044001D03*
X398705Y1040812D03*
X406094Y1034442D03*
X404256Y1037623D03*
Y1031245D03*
X402406Y1034434D03*
X396855Y1044001D03*
Y1031245D03*
Y1037623D03*
X398705Y1047190D03*
X406107D03*
X404256Y1050379D03*
X398705Y1059946D03*
Y1053568D03*
X396855Y1050379D03*
Y1056757D03*
X409807Y1059946D03*
X406107D03*
Y1053568D03*
X404256Y1056757D03*
X407957Y1063135D03*
X398705Y1072702D03*
X406107D03*
X409807D03*
X398705Y1085458D03*
X406107D03*
X409807D03*
X398705Y1098214D03*
X406107D03*
X409807D03*
Y1104592D03*
X407957Y1101403D03*
X404256D03*
X396855D03*
X406107Y1104592D03*
X400555Y1101403D03*
X398705Y1117348D03*
X407957Y1107781D03*
X406107Y1117348D03*
X409807D03*
X398705Y1130103D03*
X406107D03*
X409807D03*
X398705Y1142859D03*
X406107D03*
X409807D03*
X402406Y1149237D03*
X404256Y1152426D03*
X406107Y1161993D03*
X402406D03*
X416028Y876435D03*
X412327D03*
X423429D03*
X414177Y873246D03*
X412327Y889191D03*
X425280Y886002D03*
X423429Y889191D03*
X419729Y895569D03*
X416028D03*
X414177Y886002D03*
X419729Y908325D03*
X416028D03*
Y921080D03*
X419729D03*
X417878Y930647D03*
X421579D03*
X416028Y940214D03*
X419729D03*
X416028Y952970D03*
X419729D03*
Y965726D03*
X416028D03*
X412327Y984860D03*
X416028Y978482D03*
X419729D03*
X425280Y981671D03*
X417878D03*
X419729Y984860D03*
X417878Y988049D03*
X425280D03*
X412315Y997608D03*
X412327Y991238D03*
X419716Y997608D03*
X419729Y991238D03*
X413496Y1040820D03*
X420897D03*
X413508Y1047190D03*
X420910D03*
X419059Y1050379D03*
X411658D03*
X413508Y1053568D03*
X411658Y1056757D03*
X420910Y1053568D03*
X419059Y1056757D03*
X417209Y1059946D03*
X420910D03*
X419059Y1063135D03*
Y1069513D03*
X422760Y1063135D03*
X411658D03*
X422760Y1069513D03*
X417209Y1072702D03*
X420910D03*
X419059Y1075891D03*
X422760D03*
X417209Y1085458D03*
X420910D03*
Y1098214D03*
X417209D03*
X411658Y1101403D03*
Y1107781D03*
X422760D03*
X419059D03*
X420910Y1117348D03*
X417209D03*
X420910Y1130103D03*
X417209D03*
Y1142859D03*
X420910D03*
X413508Y1149237D03*
X424610D03*
Y1161993D03*
X415358Y1152426D03*
X413508Y1161993D03*
X417209D03*
X427130Y876435D03*
X428981Y892380D03*
X432681D03*
X428981Y911513D03*
X432681D03*
X428981Y898758D03*
X432681D03*
X428981Y924269D03*
X432681D03*
X427130Y933836D03*
X430831D03*
X428981Y943403D03*
Y956159D03*
X432681Y943403D03*
Y956159D03*
X428981Y968915D03*
X432681D03*
X427130Y984860D03*
X432681Y981671D03*
X434532Y984860D03*
X432681Y988049D03*
X434532Y991238D03*
X427118Y997608D03*
X427130Y991238D03*
X434519Y997608D03*
X428299Y1040820D03*
X428311Y1059946D03*
X432012D03*
X428311Y1047190D03*
X435713D03*
X433862Y1050379D03*
X426461D03*
Y1056757D03*
X428311Y1053568D03*
X433862Y1056757D03*
X435713Y1053568D03*
X428311Y1072702D03*
Y1066324D03*
X432012Y1072702D03*
Y1066324D03*
X430162Y1069513D03*
X433862D03*
X428311Y1079080D03*
X432012D03*
X430162Y1082269D03*
X433862D03*
X430162Y1095025D03*
X428311Y1104592D03*
X433862Y1095025D03*
X432012Y1104592D03*
X430162Y1114159D03*
X433862D03*
X430162Y1126915D03*
X433862D03*
X430162Y1139670D03*
Y1146048D03*
X433862Y1139670D03*
Y1146048D03*
Y1158804D03*
X432012Y1161993D03*
X428311D03*
X426461Y1152426D03*
X430162D03*
X433862D03*
X432012Y1155615D03*
X426461Y1158804D03*
X428311Y1155615D03*
X454861Y873246D03*
X453011Y876435D03*
X449310D03*
X451160Y879624D03*
X454861D03*
X451160Y873246D03*
Y886002D03*
X454861D03*
X451160Y892380D03*
X447460D03*
Y886002D03*
X449310Y882813D03*
X451160Y911513D03*
X447460D03*
X451160Y898758D03*
X447460D03*
X451160Y924269D03*
X447460D03*
X449310Y933836D03*
X453011D03*
X451160Y943403D03*
Y956159D03*
X447460Y943403D03*
Y956159D03*
X453011Y959348D03*
Y965726D03*
X449310Y959348D03*
Y965726D03*
X451160Y968915D03*
X447460D03*
X453011Y978482D03*
Y972104D03*
X449310Y978482D03*
Y972104D03*
X451160Y981671D03*
X449310Y984860D03*
X449323Y997608D03*
X451160Y988049D03*
X449310Y991238D03*
X450491Y1047190D03*
X452341Y1056757D03*
X450491Y1053568D03*
X452341Y1050379D03*
X448641Y1069513D03*
X452341D03*
X448641Y1082269D03*
X452341D03*
X448641Y1095025D03*
X452341D03*
X450491Y1104592D03*
X454192D03*
X448641Y1114159D03*
X452341D03*
X448641Y1126915D03*
X452341D03*
X448641Y1139670D03*
X452341D03*
X448641Y1146048D03*
X452341D03*
X450491Y1161993D03*
X452341Y1165182D03*
X454192Y1161993D03*
X452341Y1152426D03*
X448640Y1165182D03*
X448641Y1158804D03*
X452341D03*
X450491Y1155615D03*
X444953Y1507509D03*
X442753D03*
X442918Y1513218D03*
X441660Y1521612D03*
X441259Y1518121D03*
X441706Y1535698D03*
Y1537898D03*
X443153Y1540317D03*
X447224Y1544625D03*
X462263Y879624D03*
X458562D03*
Y873246D03*
X462263D03*
X456712Y876435D03*
X467814D03*
X464113D03*
X465964Y879624D03*
Y873246D03*
X460412Y882813D03*
X464113D03*
X469664Y886002D03*
X456712Y889191D03*
X460412Y895569D03*
X465964Y886002D03*
X467814Y889191D03*
X464113Y895569D03*
X462263Y886002D03*
X458562D03*
X456712Y882813D03*
X460412Y908325D03*
X464113D03*
X460412Y921080D03*
X464113D03*
X462263Y930647D03*
X458562D03*
X460412Y940214D03*
X469664Y930647D03*
X464113Y940214D03*
X465964Y930647D03*
X469664Y937025D03*
X460412Y952970D03*
X464113D03*
X462263Y962537D03*
Y968915D03*
X458562Y962537D03*
Y968915D03*
X469664Y962537D03*
Y968915D03*
X460412Y965726D03*
X464113D03*
X462263Y975293D03*
X458562D03*
X469664D03*
X460412Y978482D03*
X458562Y981671D03*
X456712Y984860D03*
X464113Y978482D03*
X465964Y981671D03*
X464113Y984860D03*
X458562Y988049D03*
X456724Y997608D03*
X456712Y991238D03*
X464126Y997608D03*
X465964Y988049D03*
X464113Y991238D03*
X457905Y1040820D03*
X465307D03*
X457893Y1047190D03*
X465294D03*
X459743Y1050379D03*
X465294Y1053568D03*
X467145Y1056757D03*
Y1050379D03*
X457893Y1053568D03*
X461593Y1059946D03*
X459743Y1056757D03*
X465294Y1059946D03*
X461593Y1072702D03*
X465294D03*
X461593Y1085458D03*
X465294D03*
X461593Y1098214D03*
X465294D03*
X459743Y1107781D03*
X461593Y1117348D03*
X463444Y1107781D03*
X465294Y1117348D03*
X461593Y1130103D03*
X465294D03*
X461593Y1142859D03*
X457893Y1149237D03*
X465294Y1142859D03*
X468995Y1149237D03*
X467145Y1165182D03*
X468995Y1161993D03*
X465294D03*
X467145Y1152426D03*
X457893Y1161993D03*
X456042Y1152426D03*
X459743Y1165182D03*
X456042Y1158804D03*
X457893Y1155615D03*
X456042Y1165182D03*
X461593Y1161993D03*
Y1155615D03*
X463444Y1152426D03*
Y1158804D03*
X467145D03*
X468995Y1155615D03*
X463444Y1165182D03*
X484467Y873246D03*
X473365D03*
X477066D03*
X484467Y879624D03*
X477066D03*
X473365D03*
X475215Y876435D03*
X478916D03*
X484467Y886002D03*
X480767D03*
X473365D03*
X477066D03*
X475215Y895569D03*
X471515D03*
X478916Y889191D03*
X482617Y895569D03*
X475215Y908325D03*
X471515D03*
X482617D03*
X475215Y921080D03*
X471515D03*
X482617D03*
X473365Y930647D03*
X471515Y940214D03*
X475215D03*
X482617D03*
X477066Y937025D03*
X480767D03*
X475215Y933836D03*
X471515D03*
X484467Y937025D03*
X473365D03*
X475215Y952970D03*
X471515D03*
X482617D03*
X484467Y962537D03*
Y968915D03*
X473365Y962537D03*
Y968915D03*
X480767Y962537D03*
Y968915D03*
X475215Y965726D03*
X471515D03*
X482617D03*
X484467Y975293D03*
X473365D03*
X480767D03*
X475215Y978482D03*
X471515D03*
X473365Y981671D03*
X471515Y984860D03*
X478916D03*
X482617Y978482D03*
X480767Y981671D03*
X473365Y988049D03*
X471527Y997608D03*
X471515Y991238D03*
X478916Y997616D03*
Y991238D03*
X480767Y994427D03*
Y988049D03*
Y1000805D03*
X478916Y1003994D03*
Y1010372D03*
X480767Y1007183D03*
X483798Y1028056D03*
X472708Y1040820D03*
X481948Y1044001D03*
Y1037623D03*
X480097Y1040812D03*
X483798Y1034434D03*
X478247Y1031245D03*
X472696Y1047190D03*
X480097D03*
X474546Y1050379D03*
Y1056757D03*
X472696Y1053568D03*
Y1059946D03*
X476397D03*
X483798D03*
X481948Y1056757D03*
X480097Y1053568D03*
X481948Y1050379D03*
X476397Y1072702D03*
X472696D03*
X483798D03*
X472696Y1085458D03*
X476397D03*
X483798D03*
X472696Y1098214D03*
X476397D03*
X483798D03*
X478247Y1101403D03*
X472696Y1104592D03*
X481948Y1101403D03*
X476397Y1104592D03*
X470845Y1101403D03*
X474546D03*
X470845Y1107781D03*
X474546D03*
X476397Y1117348D03*
X472696D03*
X483798D03*
X472696Y1130103D03*
X483798D03*
X476396D03*
X472696Y1142859D03*
X476397D03*
X483798D03*
X480097Y1149237D03*
X483798Y1155615D03*
X480097Y1161993D03*
X476397D03*
X478247Y1152426D03*
X470846Y1165182D03*
X481948D03*
X483798Y1161993D03*
X472696Y1155615D03*
X481948Y1152426D03*
X478247Y1158804D03*
X474546D03*
X478247Y1165182D03*
X480097Y1155615D03*
X474546Y1165182D03*
X470845Y1152426D03*
X472696Y1161993D03*
X499271Y879624D03*
X488168Y873246D03*
Y879624D03*
X486318Y876435D03*
X490019D03*
X497420D03*
X495570Y879624D03*
Y886002D03*
X491869D03*
X488168D03*
X490019Y889191D03*
X493719Y895569D03*
X486318D03*
X499271Y886002D03*
X497420Y895569D03*
Y882813D03*
X493719Y908325D03*
X486318D03*
X497420D03*
X493719Y921080D03*
X486318D03*
X497420D03*
X493719Y940214D03*
X486318D03*
X497420D03*
X499271Y937025D03*
X488168D03*
X491869D03*
X495570D03*
X486318Y952970D03*
X493719D03*
X497420D03*
X495570Y962537D03*
Y968915D03*
X491869Y962537D03*
Y968915D03*
X493719Y965726D03*
X486318D03*
X497420D03*
X495570Y975293D03*
X491869D03*
X493719Y978482D03*
X486318D03*
X488168Y981671D03*
X493719Y984860D03*
X486318D03*
X495570Y981671D03*
X497420Y978482D03*
X488168Y988049D03*
Y994427D03*
X486318Y997616D03*
X493719D03*
X486318Y991238D03*
X493719D03*
X488168Y1000805D03*
X495570Y994427D03*
Y988049D03*
Y1000805D03*
X488168Y1007183D03*
X486318Y1003994D03*
Y1010372D03*
X493719Y1003994D03*
Y1010372D03*
X495570Y1007183D03*
X491200Y1028056D03*
X498601D03*
X494901Y1040812D03*
X489349Y1044001D03*
X487499Y1040812D03*
X489349Y1037623D03*
X496751Y1044001D03*
Y1037623D03*
X485649Y1031245D03*
X493050D03*
X491200Y1034434D03*
X498601D03*
X496751Y1050379D03*
X494901Y1047190D03*
X487499D03*
X489349Y1050379D03*
X494901Y1059946D03*
Y1053568D03*
X487499Y1059946D03*
X489349Y1056757D03*
X487499Y1053568D03*
X496751Y1056757D03*
X498601Y1059946D03*
X494901Y1072702D03*
X487499D03*
X498601D03*
X494901Y1085458D03*
X487499D03*
X498601D03*
X494901Y1098214D03*
X487499D03*
X498601D03*
X493050Y1101403D03*
X485649D03*
X489349D03*
X494901Y1117348D03*
X487499D03*
X498601D03*
X487499Y1130103D03*
X494901D03*
X498601D03*
X494901Y1142859D03*
X487499D03*
X491200Y1149237D03*
X498601Y1142859D03*
Y1161993D03*
X487499D03*
X491200D03*
X489349Y1152426D03*
X493050Y1165182D03*
X485649Y1158804D03*
Y1165182D03*
X496751D03*
Y1158804D03*
X489349D03*
X491200Y1155615D03*
X493050Y1152426D03*
X494901Y1161993D03*
Y1155615D03*
X489349Y1165182D03*
X510373Y879624D03*
X514074D03*
X508523Y876435D03*
X506672Y879624D03*
X512223Y876435D03*
X501121D03*
Y889191D03*
X512223Y895569D03*
X501121Y882813D03*
X514074Y905135D03*
X501121Y901947D03*
X512223Y914702D03*
X514074Y924269D03*
X501121Y914702D03*
X512223Y933836D03*
X501121Y927458D03*
X514074Y943403D03*
X512223Y952970D03*
X501121Y946592D03*
X514074Y962537D03*
X501121Y959348D03*
X514074Y981671D03*
X512223Y972104D03*
X501121D03*
Y984860D03*
Y997616D03*
Y991238D03*
X512223D03*
X514074Y1000805D03*
X502971Y994427D03*
X508523Y991238D03*
X501121Y1010372D03*
X512223D03*
X501121Y1003994D03*
X504822Y1010372D03*
X506003Y1028056D03*
X509704D03*
X502302Y1040812D03*
X500452Y1031245D03*
X511554Y1044001D03*
Y1031245D03*
X502302Y1047190D03*
Y1053568D03*
X513405Y1047190D03*
X511554Y1056757D03*
X509704Y1047190D03*
X506003Y1053568D03*
X513405Y1066324D03*
X502302D03*
X513405Y1085458D03*
X502302Y1079080D03*
X513405Y1104592D03*
X502302Y1091836D03*
X500452Y1101403D03*
X502302Y1110970D03*
X513405Y1123726D03*
X502302D03*
X513405Y1142859D03*
X502302Y1136481D03*
Y1149237D03*
X513405Y1161993D03*
X511554Y1158804D03*
X509704Y1161993D03*
X502302D03*
X500452Y1152426D03*
X506003Y1161993D03*
X500452Y1158804D03*
Y1165182D03*
X507853D03*
X504153D03*
X521475Y879624D03*
X519625Y876435D03*
X517775Y879624D03*
X521475Y873246D03*
X517775D03*
X527027Y876435D03*
X528877Y879624D03*
X515924Y882813D03*
X527027D03*
X517775Y994427D03*
X523326Y991238D03*
X528877Y994427D03*
X515924Y1010372D03*
X517105Y1028056D03*
X524507D03*
X515255Y1037623D03*
X522656Y1044001D03*
Y1031245D03*
X515255Y1056757D03*
X522656D03*
X524507Y1047190D03*
X517105Y1053568D03*
X515255Y1075891D03*
Y1095025D03*
Y1114159D03*
Y1133293D03*
X528208Y1161993D03*
X515255Y1152426D03*
X524507Y1161993D03*
X520806D03*
X518956Y1158804D03*
X529594Y1507355D03*
X527494D03*
X530727Y876435D03*
X532578Y873246D03*
X538129Y895569D03*
X539979Y886002D03*
X530727Y882813D03*
X541830D03*
X539979Y905135D03*
Y924269D03*
X538129Y914702D03*
Y933836D03*
Y952970D03*
X539979Y943403D03*
Y962537D03*
X538129Y972104D03*
X539979Y981671D03*
Y1000805D03*
X538129Y991238D03*
X543680Y994427D03*
X534428Y991238D03*
X538129Y1010372D03*
X530727D03*
X541830D03*
X531908Y1028056D03*
X543011D03*
X535609D03*
X541160Y1037623D03*
X537460Y1044001D03*
Y1031245D03*
X541160Y1056757D03*
X539310Y1047190D03*
X543011Y1053568D03*
X537460Y1056757D03*
X535609Y1047190D03*
X531908Y1053568D03*
X539310Y1066324D03*
Y1085458D03*
X541160Y1075891D03*
Y1095025D03*
X539310Y1104592D03*
X541160Y1114159D03*
X539310Y1123726D03*
X541160Y1133293D03*
X539310Y1142859D03*
X541160Y1152426D03*
X531908Y1161993D03*
X535609D03*
X539310D03*
X537460Y1158804D03*
X541160D03*
X531001Y1514073D03*
X530945Y1516336D03*
X532310Y1536640D03*
X531926Y1534540D03*
X531537Y1531618D03*
X531208Y1528698D03*
X530711Y1538658D03*
X554783Y879624D03*
X556633Y882813D03*
X552932D03*
X554782Y994427D03*
X549231Y991238D03*
X556633Y1010372D03*
X557814Y1028056D03*
X550412D03*
X548562Y1044001D03*
Y1031245D03*
X557814Y1053568D03*
X548562Y1056757D03*
X550412Y1047190D03*
X546712Y1161993D03*
X557814D03*
X544861Y1158804D03*
X562184Y873246D03*
X565885Y879624D03*
X564034Y876435D03*
X573286Y879624D03*
X571436Y876435D03*
X569586Y879624D03*
X564034Y895569D03*
X565885Y886002D03*
X567735Y882813D03*
X565885Y905135D03*
Y924269D03*
X564034Y914702D03*
Y933836D03*
Y952970D03*
X565885Y943403D03*
Y962537D03*
Y981671D03*
X564034Y972104D03*
X565885Y1000805D03*
X564034Y991238D03*
X560334D03*
X564034Y1010372D03*
X567735D03*
X568916Y1028056D03*
X561515D03*
X567066Y1037623D03*
X563365Y1044001D03*
Y1031245D03*
X567066Y1056757D03*
X565215Y1047190D03*
X563365Y1056757D03*
X561515Y1047190D03*
X565215Y1066324D03*
Y1085458D03*
X567066Y1075891D03*
X565215Y1104592D03*
X567066Y1095025D03*
Y1114159D03*
Y1133293D03*
X565215Y1123726D03*
Y1142859D03*
X567066Y1158804D03*
X563365D03*
X567066Y1152426D03*
X572617Y1161993D03*
X570767Y1165182D03*
X567066D03*
X568916Y1161993D03*
X570815Y1507509D03*
X573066Y1507460D03*
X570980Y1513218D03*
X569722Y1521612D03*
X569321Y1518121D03*
X569768Y1535698D03*
Y1537898D03*
X571215Y1540317D03*
X575286Y1544625D03*
X657656Y1507355D03*
X655556D03*
X659063Y1514073D03*
X659007Y1516336D03*
X659358Y1536640D03*
Y1534540D03*
X659359Y1531618D03*
X659270Y1528698D03*
X662353Y1534413D03*
X660877Y1530158D03*
X658773Y1538658D03*
X1184959Y1551121D03*
X1185360Y1554612D03*
X1185406Y1568698D03*
Y1570898D03*
X1188653Y1540509D03*
X1186453D03*
X1186618Y1546218D03*
X1186853Y1573317D03*
X1190924Y1577625D03*
X1243272Y1549970D03*
X1233823D03*
X1238547D03*
X1244847Y1552698D03*
X1235398D03*
X1240122D03*
X1247996Y1549970D03*
X1252721D03*
X1257445D03*
X1249571Y1552698D03*
X1254295D03*
X1259020D03*
X1262170Y1549970D03*
X1266894D03*
X1263744Y1552698D03*
X1268469D03*
X1273294Y1540355D03*
X1271194D03*
X1274701Y1547073D03*
X1274645Y1549336D03*
X1274996Y1567540D03*
X1274997Y1564618D03*
X1274908Y1561698D03*
X1274411Y1571658D03*
X1274996Y1569640D03*
X1288549Y876434D03*
X1288548Y1010371D03*
X1289729Y1028055D03*
X1297800Y879623D03*
X1299650Y876434D03*
X1290399Y879623D03*
X1303351Y882812D03*
X1292249Y895568D03*
X1299650Y882812D03*
X1290398Y905134D03*
X1292249Y914701D03*
X1290398Y924268D03*
X1292249Y933835D03*
Y952969D03*
X1290398Y943402D03*
Y962536D03*
X1292249Y972103D03*
X1290398Y981670D03*
X1292249Y991237D03*
X1290398Y1000804D03*
X1299650Y991237D03*
X1294099Y988048D03*
X1299650Y1010371D03*
X1293430Y1028055D03*
X1300831D03*
X1297130D03*
X1291579Y1037622D03*
X1302682Y1044000D03*
X1295280Y1031244D03*
X1291579Y1056756D03*
X1293430Y1047189D03*
X1295280Y1056756D03*
X1297130Y1047189D03*
X1300831Y1053567D03*
X1293430Y1066323D03*
Y1085457D03*
X1291579Y1075890D03*
X1293430Y1104591D03*
X1291579Y1095024D03*
Y1114158D03*
Y1133292D03*
X1293430Y1123725D03*
Y1142858D03*
X1291579Y1158803D03*
X1295280D03*
X1291579Y1152425D03*
X1300831Y1161992D03*
X1302682Y1165181D03*
X1318154Y876434D03*
X1305201Y879623D03*
X1312603D03*
X1316304D03*
X1307052Y876434D03*
X1318154Y895568D03*
X1316304Y905134D03*
Y924268D03*
X1318154Y914701D03*
Y933835D03*
Y952969D03*
X1316304Y943402D03*
Y962536D03*
Y981670D03*
X1318154Y972103D03*
X1316304Y1000804D03*
X1318154Y991237D03*
X1314453D03*
X1308902Y988048D03*
X1314453Y1010371D03*
X1319335Y1028055D03*
X1315634D03*
X1308233D03*
X1317485Y1037622D03*
X1313784Y1044000D03*
X1310083Y1031244D03*
X1317485Y1056756D03*
X1319335Y1047189D03*
X1310083Y1056756D03*
X1308233Y1047189D03*
X1315634Y1053567D03*
X1319335Y1066323D03*
Y1085457D03*
X1317485Y1075890D03*
X1319335Y1104591D03*
X1317485Y1095024D03*
Y1114158D03*
Y1133292D03*
X1319335Y1123725D03*
Y1142858D03*
X1317485Y1152425D03*
X1308233Y1161992D03*
X1310083Y1165181D03*
X1317485D03*
X1315634Y1161992D03*
X1316766Y1540460D03*
X1314515Y1540509D03*
X1314680Y1546218D03*
X1313021Y1551121D03*
X1313422Y1554612D03*
X1313468Y1568698D03*
Y1570898D03*
X1318986Y1577625D03*
X1314915Y1573317D03*
X1323705Y879623D03*
X1327406D03*
X1321855Y876434D03*
X1332957D03*
X1329256D03*
X1334807Y879623D03*
X1334808Y988048D03*
X1325556Y991237D03*
X1320004Y988048D03*
X1325556Y1010371D03*
X1326737Y1028055D03*
X1334138D03*
X1323036D03*
X1328587Y1044000D03*
X1321185Y1031244D03*
X1334138Y1047189D03*
X1321185Y1056756D03*
X1323036Y1047189D03*
X1326737Y1053567D03*
X1321185Y1158803D03*
X1334138Y1161992D03*
X1344059Y876434D03*
X1347760D03*
X1340359D03*
X1347760Y882812D03*
X1344059Y895568D03*
X1342209Y905134D03*
X1344059Y914701D03*
X1342209Y924268D03*
X1344059Y933835D03*
X1342209Y943402D03*
X1344059Y952969D03*
X1342209Y962536D03*
Y981670D03*
X1344059Y972103D03*
Y991237D03*
X1342209Y1000804D03*
X1340359Y991237D03*
X1345910Y988048D03*
X1340359Y1010371D03*
X1345241Y1028055D03*
X1341540D03*
X1348941D03*
X1343390Y1037622D03*
X1339689Y1044000D03*
X1335989Y1031244D03*
X1347091D03*
X1345241Y1047189D03*
X1343390Y1056756D03*
X1335989D03*
X1341540Y1053567D03*
X1347091Y1056756D03*
X1348941Y1047189D03*
X1345241Y1066323D03*
X1343390Y1075890D03*
X1345241Y1085457D03*
X1343390Y1095024D03*
X1345241Y1104591D03*
X1343390Y1114158D03*
Y1133292D03*
X1345241Y1123725D03*
Y1142858D03*
X1347091Y1158803D03*
X1348941Y1161992D03*
X1345241D03*
X1343390Y1152425D03*
X1335989Y1165181D03*
X1343390Y1158803D03*
X1341540Y1161992D03*
X1358863Y876434D03*
X1355162D03*
X1351461Y882812D03*
X1357012Y886001D03*
X1362563Y895568D03*
X1358863D03*
X1355162Y889190D03*
X1362563Y908324D03*
X1358863D03*
X1355162Y901946D03*
X1358863Y921079D03*
X1362563D03*
X1355162Y914701D03*
X1362563Y940213D03*
X1358863D03*
X1357012Y937024D03*
X1355162Y927457D03*
X1364414Y937024D03*
X1360713D03*
X1362563Y952969D03*
X1358863D03*
X1355162Y946591D03*
X1360713Y962536D03*
Y968914D03*
X1364414Y962536D03*
Y968914D03*
X1362563Y965725D03*
X1358863D03*
X1355162Y959347D03*
X1360713Y975292D03*
X1364414D03*
X1357012Y981670D03*
X1364414D03*
X1358863Y984859D03*
X1362563Y978481D03*
X1358863D03*
X1355162Y972103D03*
X1357012Y988048D03*
X1358863Y997615D03*
X1357012Y994426D03*
X1358863Y991237D03*
X1364414Y988048D03*
Y994426D03*
X1357012Y1000804D03*
X1364414D03*
X1351461Y991237D03*
X1357012Y1007182D03*
X1358863Y1003993D03*
X1364414Y1007182D03*
X1355162Y1010371D03*
X1362563D03*
X1351461D03*
X1360044Y1028055D03*
X1352642D03*
X1358193Y1031244D03*
X1360044Y1040811D03*
Y1034433D03*
X1358193Y1037622D03*
Y1044000D03*
X1354493D03*
X1363745Y1059945D03*
X1360044D03*
Y1047189D03*
X1358193Y1050378D03*
X1360044Y1053567D03*
X1361894Y1056756D03*
X1358193D03*
X1352642Y1053567D03*
X1363745Y1072701D03*
X1360044D03*
X1356343Y1066323D03*
X1363745Y1085457D03*
X1360044D03*
X1356343Y1079079D03*
X1363745Y1098213D03*
X1360044D03*
X1356343Y1091835D03*
X1358193Y1101402D03*
X1361894D03*
X1363745Y1117347D03*
X1360044D03*
X1356343Y1110969D03*
X1363745Y1130102D03*
X1360044D03*
X1356343Y1123725D03*
X1360044Y1142858D03*
X1363745D03*
X1356343Y1149236D03*
Y1136480D03*
X1358193Y1152425D03*
X1356343Y1161992D03*
X1360044D03*
X1369965Y876434D03*
X1366264D03*
X1377367D03*
X1368115Y879623D03*
X1371815D03*
X1368115Y886001D03*
X1369965Y895568D03*
X1373666D03*
X1366264Y889190D03*
X1377366D03*
X1379216Y886001D03*
X1371815D03*
X1375516D03*
X1369965Y908324D03*
X1373666D03*
X1369965Y921079D03*
X1373666D03*
X1369965Y940213D03*
X1373666D03*
X1371815Y937024D03*
X1379217D03*
X1368115D03*
X1375516D03*
X1369965Y952969D03*
X1373666D03*
X1371815Y962536D03*
Y968914D03*
X1375516Y962536D03*
Y968914D03*
X1369965Y965725D03*
X1373666D03*
X1371815Y975292D03*
X1375516D03*
X1366264Y984859D03*
X1369965Y978481D03*
X1373666D03*
X1371815Y981670D03*
X1379217D03*
X1373666Y984859D03*
Y991237D03*
X1371815Y988048D03*
Y994426D03*
Y1000804D03*
X1366264Y997615D03*
Y991237D03*
X1379217Y988048D03*
Y994426D03*
X1373666Y997615D03*
X1379217Y1000804D03*
X1366264Y1003993D03*
X1379217Y1007182D03*
X1377367Y1010371D03*
X1373666Y1003993D03*
X1369965Y1010371D03*
X1378548Y1028055D03*
X1367445D03*
X1374847Y1040811D03*
X1378548Y1034433D03*
X1372997Y1037622D03*
Y1044000D03*
X1367445Y1040811D03*
Y1034433D03*
X1365595Y1031244D03*
Y1037622D03*
Y1044000D03*
X1372997Y1031244D03*
X1374847Y1047189D03*
Y1053567D03*
X1371146Y1059945D03*
X1372997Y1056756D03*
Y1050378D03*
X1374847Y1059945D03*
X1365595Y1056756D03*
X1367445Y1047189D03*
Y1053567D03*
X1365595Y1050378D03*
X1371146Y1072701D03*
X1374847D03*
Y1085457D03*
X1371146D03*
X1374847Y1098213D03*
X1371146D03*
X1372997Y1101402D03*
X1376697D03*
X1369296D03*
X1365595D03*
X1374847Y1117347D03*
X1371146D03*
Y1130102D03*
X1374847D03*
Y1142858D03*
X1371146D03*
X1378548Y1149236D03*
X1367445D03*
X1369296Y1152425D03*
X1371146Y1161992D03*
X1378548D03*
X1367445D03*
X1388469Y876434D03*
X1392170D03*
X1381067D03*
X1390320Y879623D03*
X1394021D03*
X1381067Y895568D03*
X1384768D03*
X1390319Y886001D03*
X1392170Y895568D03*
X1388469Y889190D03*
X1394021Y886001D03*
X1384768Y908324D03*
X1392170D03*
X1381067Y908323D03*
X1384768Y921079D03*
X1381067D03*
X1392170D03*
X1382918Y930646D03*
X1386619D03*
X1384768Y940213D03*
X1381067D03*
X1394020Y930646D03*
X1392170Y940213D03*
X1381067Y933835D03*
X1386619Y937024D03*
X1384768Y933835D03*
X1382918Y937024D03*
X1384768Y952969D03*
X1381067D03*
X1392170D03*
X1394020Y962536D03*
Y968914D03*
X1382918Y962536D03*
Y968914D03*
X1386619Y962536D03*
Y968914D03*
X1384768Y965725D03*
X1381067D03*
X1392170D03*
X1394020Y975292D03*
X1382918D03*
X1386619D03*
X1381067Y978481D03*
X1384768D03*
X1386619Y981670D03*
X1381067Y984859D03*
X1392170Y978481D03*
X1394020Y981670D03*
X1388469Y984859D03*
X1386619Y988048D03*
X1394020D03*
X1381067Y991237D03*
X1388457Y997607D03*
X1388469Y991237D03*
X1382905Y1007174D03*
X1382236Y1028063D03*
X1380398Y1044000D03*
X1382246Y1040819D03*
X1389638D03*
X1382236Y1034441D03*
X1380398Y1037622D03*
Y1031244D03*
X1382249Y1047189D03*
X1389650D03*
X1380398Y1050378D03*
X1382249Y1059945D03*
Y1053567D03*
X1385949Y1059945D03*
X1380398Y1056756D03*
X1387800D03*
X1393351Y1059945D03*
X1387800Y1050378D03*
X1389650Y1053567D03*
X1384099Y1063134D03*
X1387800D03*
X1382249Y1072701D03*
X1385949D03*
X1393351D03*
X1382249Y1085457D03*
X1385949D03*
X1393351D03*
X1382249Y1098213D03*
X1385949D03*
X1393351D03*
X1385949Y1104591D03*
X1384099Y1101402D03*
X1380398D03*
X1382249Y1104591D03*
X1387800Y1101402D03*
X1384099Y1107780D03*
X1382249Y1117347D03*
X1385949D03*
X1387800Y1107780D03*
X1393351Y1117347D03*
X1385949Y1130102D03*
X1382249D03*
X1393351D03*
X1382249Y1142858D03*
X1385949D03*
X1393351D03*
X1389650Y1149236D03*
X1380398Y1152425D03*
X1382249Y1161992D03*
X1391500Y1152425D03*
X1393351Y1161992D03*
X1389650D03*
X1399571Y876434D03*
X1403272D03*
X1405123Y879623D03*
X1401423D03*
X1401422Y886001D03*
X1395871Y895568D03*
X1399571Y889190D03*
X1408823Y892379D03*
X1405123D03*
X1397722Y886001D03*
X1408824D03*
X1405123D03*
X1395871Y908324D03*
X1408823Y911512D03*
X1405123D03*
X1408823Y898757D03*
X1405123D03*
X1395871Y921079D03*
X1408823Y924268D03*
X1405123D03*
X1397721Y930646D03*
X1395871Y940213D03*
X1406973Y933835D03*
X1403272D03*
X1395871Y952969D03*
X1405123Y943402D03*
X1408823D03*
X1405123Y956158D03*
X1408823D03*
X1403272Y959347D03*
Y965725D03*
X1406973Y959347D03*
Y965725D03*
X1397721Y962536D03*
Y968914D03*
X1405123D03*
X1395871Y965725D03*
X1408823Y968914D03*
X1403272Y978481D03*
Y972103D03*
X1406973Y978481D03*
Y972103D03*
X1397721Y975292D03*
X1395871Y978481D03*
X1401422Y981670D03*
X1395871Y984859D03*
X1408823Y981670D03*
X1403272Y984859D03*
X1401422Y988048D03*
X1395858Y997607D03*
X1395871Y991237D03*
X1403260Y997607D03*
X1408823Y988048D03*
X1403272Y991237D03*
X1397039Y1040819D03*
X1404441D03*
X1404453Y1059945D03*
X1408154D03*
X1397052Y1047189D03*
X1404453D03*
X1395201Y1050378D03*
X1402603Y1056756D03*
Y1050378D03*
X1395201Y1056756D03*
X1397052Y1059945D03*
Y1053567D03*
X1404453D03*
X1395201Y1063134D03*
X1404453Y1072701D03*
Y1066323D03*
X1395201Y1069512D03*
X1398902Y1063134D03*
X1408154Y1072701D03*
Y1066323D03*
X1398902Y1069512D03*
X1406304D03*
X1397052Y1072701D03*
X1395201Y1075890D03*
X1404453Y1079079D03*
X1398902Y1075890D03*
X1408154Y1079079D03*
X1397052Y1085457D03*
X1406304Y1082268D03*
X1397052Y1098213D03*
X1406304Y1095024D03*
X1408154Y1104591D03*
X1404453D03*
X1398902Y1107780D03*
X1395201D03*
X1397052Y1117347D03*
X1406304Y1114158D03*
X1397052Y1130102D03*
X1406304Y1126914D03*
X1397052Y1142858D03*
X1400752Y1149236D03*
X1406304Y1139669D03*
Y1146047D03*
X1402603Y1152425D03*
X1400752Y1161992D03*
X1406304Y1152425D03*
X1404453Y1161992D03*
X1408154Y1155614D03*
X1399256Y1540355D03*
X1401356D03*
X1402763Y1547073D03*
X1402707Y1549336D03*
X1403058Y1567540D03*
X1403059Y1564618D03*
X1402970Y1561698D03*
X1402473Y1571658D03*
X1423602Y892379D03*
Y911512D03*
Y898757D03*
Y924268D03*
Y943402D03*
Y956158D03*
Y968914D03*
X1410674Y984859D03*
X1410661Y997607D03*
X1410674Y991237D03*
X1411855Y1047189D03*
X1410004Y1050378D03*
X1411855Y1053567D03*
X1410004Y1056756D03*
Y1069512D03*
Y1082268D03*
Y1095024D03*
Y1114158D03*
Y1126914D03*
Y1139669D03*
Y1146047D03*
Y1152425D03*
Y1158803D03*
X1438405Y879623D03*
X1431003Y873245D03*
X1434704Y879623D03*
Y873245D03*
X1438405D03*
X1429153Y876434D03*
X1432854D03*
X1436554Y882812D03*
X1431003Y886001D03*
X1427302D03*
Y892379D03*
X1432854Y889190D03*
X1436554Y895568D03*
X1438405Y886001D03*
X1427302Y911512D03*
X1436554Y908324D03*
X1427302Y898757D03*
Y924268D03*
X1436554Y921079D03*
X1429153Y933835D03*
X1425452D03*
X1434704Y930646D03*
X1438405D03*
X1436554Y940213D03*
X1427302Y943402D03*
Y956158D03*
X1436554Y952969D03*
X1427302Y968914D03*
X1436554Y965725D03*
X1427302Y981670D03*
X1434704D03*
X1425452Y984859D03*
X1432854D03*
X1436554Y978481D03*
X1434704Y988048D03*
X1425465Y997607D03*
X1432866D03*
X1427302Y988048D03*
X1425452Y991237D03*
X1432854D03*
X1434047Y1040819D03*
X1434035Y1047189D03*
X1426633D03*
X1435885Y1050378D03*
X1428483D03*
X1437735Y1059945D03*
X1435885Y1056756D03*
X1428483D03*
X1426633Y1053567D03*
X1434035D03*
X1428483Y1069512D03*
X1424783D03*
X1437735Y1072701D03*
X1428483Y1082268D03*
X1424783D03*
X1437735Y1085457D03*
X1428483Y1095024D03*
X1424783D03*
X1430334Y1104591D03*
X1426633D03*
X1437735Y1098213D03*
X1428483Y1114158D03*
X1424783D03*
X1435885Y1107780D03*
X1437735Y1117347D03*
X1424783Y1126914D03*
X1428483D03*
X1437735Y1130102D03*
X1428483Y1139669D03*
X1424783D03*
X1434035Y1149236D03*
X1428483Y1146047D03*
X1424783D03*
X1437735Y1142858D03*
X1426633Y1161992D03*
X1424783Y1152425D03*
X1426633Y1155614D03*
X1428483Y1152425D03*
X1432184D03*
X1434035Y1161992D03*
X1430334D03*
X1424783Y1158803D03*
X1432184D03*
X1434035Y1155614D03*
X1428484Y1158803D03*
X1437735Y1155614D03*
X1443956Y876434D03*
X1440255D03*
X1451358D03*
X1449507Y873245D03*
X1453208D03*
X1440255Y882812D03*
X1442106Y886001D03*
X1443956Y889190D03*
X1447657Y895568D03*
X1440255D03*
X1453208Y886001D03*
X1451358Y895568D03*
X1447657Y908324D03*
X1440255D03*
X1451357D03*
X1447657Y921079D03*
X1440255D03*
X1451357D03*
X1445806Y930646D03*
X1449507D03*
X1447657Y940213D03*
X1440255D03*
X1451357D03*
X1442106Y930646D03*
X1453208Y937024D03*
X1445806D03*
X1451357Y933835D03*
X1447657D03*
X1449507Y937024D03*
X1447657Y952969D03*
X1440255D03*
X1451357D03*
X1440255Y965725D03*
X1447657D03*
X1451357D03*
X1440255Y978481D03*
X1447657D03*
X1442106Y981670D03*
X1449507D03*
X1447657Y984859D03*
X1440255D03*
X1451357Y978481D03*
X1449507Y988048D03*
X1440268Y997607D03*
X1447669D03*
X1442106Y988048D03*
X1440255Y991237D03*
X1447657D03*
X1441449Y1040819D03*
X1448850D03*
X1441436Y1047189D03*
X1448838D03*
X1450688Y1050378D03*
Y1056756D03*
X1441436Y1059945D03*
Y1053567D03*
X1443287Y1056756D03*
X1448838Y1053567D03*
X1443287Y1050378D03*
X1448838Y1059945D03*
X1452539D03*
X1441436Y1072701D03*
X1448838D03*
X1452539D03*
X1448838Y1085457D03*
X1441436D03*
X1452539D03*
X1448838Y1098213D03*
X1441436D03*
X1452539D03*
X1448838Y1104591D03*
X1452539D03*
X1446987Y1101402D03*
X1450688D03*
Y1107780D03*
X1446987D03*
X1439586D03*
X1448838Y1117347D03*
X1441436D03*
X1452539D03*
X1448838Y1130102D03*
X1441436D03*
X1452539Y1130103D03*
X1448838Y1142858D03*
X1441436D03*
X1445137Y1149236D03*
X1452539Y1142858D03*
X1446987Y1152425D03*
X1443287Y1165181D03*
X1439586Y1158803D03*
X1443287Y1152425D03*
X1452539Y1161992D03*
X1441436D03*
X1445137D03*
X1448838Y1155614D03*
X1439586Y1152425D03*
X1445137Y1155614D03*
X1443287Y1158803D03*
X1450627Y1540509D03*
X1452827D03*
X1450792Y1546218D03*
X1449133Y1551121D03*
X1449534Y1554612D03*
X1449580Y1568698D03*
Y1570898D03*
X1451027Y1573317D03*
X1462460Y876434D03*
X1455058D03*
X1466161D03*
X1464310Y873245D03*
X1460609D03*
Y879623D03*
X1464310D03*
Y886001D03*
X1458759Y895568D03*
X1462460D03*
X1466161Y889190D03*
X1455058D03*
X1460609Y886001D03*
X1456909D03*
X1468011D03*
X1458759Y908324D03*
X1462460D03*
X1458759Y921079D03*
X1462460D03*
Y940213D03*
X1458759D03*
X1456909Y937024D03*
X1464310D03*
X1460609D03*
X1468011D03*
X1458759Y952969D03*
X1462460D03*
Y965725D03*
X1458759D03*
X1462460Y978481D03*
X1458759D03*
X1464310Y981670D03*
X1456909D03*
X1462460Y984859D03*
X1455058D03*
X1464310Y988048D03*
Y994426D03*
X1456909Y988048D03*
Y994426D03*
X1462460Y997615D03*
Y991237D03*
X1455058Y997615D03*
Y991237D03*
X1456909Y1000804D03*
X1464310D03*
Y1007182D03*
X1456909D03*
X1462460Y1010371D03*
Y1003993D03*
X1455058Y1010371D03*
Y1003993D03*
X1459940Y1028055D03*
X1467342D03*
X1458090Y1037622D03*
Y1044000D03*
X1465491Y1037622D03*
Y1044000D03*
X1463641Y1040811D03*
X1456239D03*
X1459940Y1034433D03*
X1461791Y1031244D03*
X1454389D03*
X1467342Y1034433D03*
X1463641Y1047189D03*
X1456239D03*
X1465491Y1050378D03*
X1456239Y1053567D03*
X1463641D03*
X1458090Y1056756D03*
X1463641Y1059945D03*
X1465491Y1056756D03*
X1458090Y1050378D03*
X1459940Y1059945D03*
X1463641Y1072701D03*
X1459940D03*
X1463641Y1085457D03*
X1459940D03*
X1463641Y1098213D03*
X1459940D03*
X1454389Y1101402D03*
X1461791D03*
X1458090D03*
X1465491D03*
X1459940Y1117347D03*
X1463641D03*
X1459940Y1130102D03*
X1463641D03*
Y1142858D03*
X1459940D03*
X1456239Y1149236D03*
X1467342D03*
X1454389Y1158803D03*
X1467342Y1155614D03*
X1465491Y1158803D03*
X1459940Y1155614D03*
X1465491Y1152425D03*
X1454389D03*
X1467342Y1161992D03*
X1463641D03*
X1456239D03*
X1461791Y1165181D03*
X1458090Y1152425D03*
X1461791Y1158803D03*
X1456239Y1155614D03*
X1455098Y1577625D03*
X1475413Y879623D03*
X1482814D03*
X1473562Y876434D03*
X1477263D03*
X1471712Y873245D03*
X1475413D03*
X1480964Y876434D03*
X1475413Y886001D03*
X1477263Y889190D03*
X1473562Y895568D03*
X1469861D03*
X1471712Y886001D03*
X1469861Y908324D03*
X1473562D03*
X1477263Y901946D03*
X1473562Y921079D03*
X1469861D03*
X1477263Y914701D03*
X1469861Y940213D03*
X1473562D03*
X1477263Y927457D03*
X1475413Y937024D03*
X1471712D03*
X1473562Y952969D03*
X1469861D03*
X1477263Y946591D03*
X1473562Y965725D03*
X1469861D03*
X1477263Y959347D03*
X1471712Y981670D03*
X1473562Y978481D03*
X1469861D03*
Y984859D03*
X1477263Y972103D03*
Y984859D03*
Y991237D03*
X1469861Y997615D03*
Y991237D03*
X1471712Y988048D03*
Y994426D03*
X1477263Y997615D03*
X1471712Y1000804D03*
X1479113Y994426D03*
X1471712Y1007182D03*
X1477263Y1010371D03*
Y1003993D03*
X1469861Y1010371D03*
Y1003993D03*
X1480964Y1010371D03*
X1474743Y1028055D03*
X1482145D03*
X1478444Y1040811D03*
X1471043D03*
X1472893Y1037622D03*
Y1044000D03*
X1474743Y1034433D03*
X1476594Y1031244D03*
X1469192D03*
X1472893Y1050378D03*
X1478444Y1047189D03*
X1471043D03*
X1478444Y1053567D03*
X1472893Y1056756D03*
X1471043Y1053567D03*
X1474743Y1059945D03*
X1471043D03*
X1482145Y1053567D03*
X1478444Y1066323D03*
X1471043Y1072701D03*
X1474743D03*
X1478444Y1079079D03*
X1474743Y1085457D03*
X1471043D03*
X1478444Y1091835D03*
X1476594Y1101402D03*
X1474743Y1098213D03*
X1471043D03*
X1469192Y1101402D03*
X1478444Y1110969D03*
X1474743Y1117347D03*
X1471043D03*
X1478444Y1123725D03*
X1474743Y1130102D03*
X1471043D03*
X1478444Y1136480D03*
X1474743Y1142858D03*
X1471043D03*
X1478444Y1149236D03*
X1472893Y1158803D03*
X1471043Y1155614D03*
Y1161992D03*
X1469192Y1152425D03*
X1476594D03*
X1478444Y1161992D03*
X1474743D03*
X1476594Y1158803D03*
X1476778Y1165778D03*
X1486515Y879623D03*
X1490216D03*
X1484665Y876434D03*
X1488365D03*
Y895568D03*
X1492066Y882812D03*
X1490216Y905134D03*
X1488365Y914701D03*
X1490216Y924268D03*
X1488365Y933835D03*
X1490216Y943402D03*
X1488365Y952969D03*
X1490216Y962536D03*
Y981670D03*
X1488365Y972103D03*
Y991237D03*
X1490216Y1000804D03*
X1493917Y994426D03*
X1484665Y991237D03*
X1488365Y1010371D03*
X1492066D03*
X1493247Y1028055D03*
X1485846D03*
X1491397Y1037622D03*
X1498798Y1044000D03*
Y1031244D03*
X1487696Y1044000D03*
Y1031244D03*
X1489547Y1047189D03*
X1491397Y1056756D03*
X1498798D03*
X1493247Y1053567D03*
X1487696Y1056756D03*
X1485846Y1047189D03*
X1489547Y1066323D03*
X1491397Y1075890D03*
X1489547Y1085457D03*
X1491397Y1095024D03*
X1489547Y1104591D03*
X1491397Y1114158D03*
Y1133292D03*
X1489547Y1123725D03*
Y1142858D03*
X1491397Y1152425D03*
X1489547Y1161992D03*
X1485846D03*
X1487696Y1158803D03*
X1506869Y876434D03*
X1512421Y879623D03*
X1505019D03*
X1506869Y882812D03*
X1499468Y991237D03*
X1505019Y994426D03*
X1510570Y991237D03*
X1506869Y1010371D03*
X1508050Y1028055D03*
X1500649D03*
X1511751D03*
X1513602Y1044000D03*
Y1031244D03*
X1500649Y1047189D03*
X1513602Y1056756D03*
X1511751Y1047189D03*
X1508050Y1053567D03*
X1513602Y1158803D03*
X1500649Y1161992D03*
X1504350D03*
X1527224Y873245D03*
X1516121D03*
X1519822D03*
X1514271Y876434D03*
X1523523Y879623D03*
X1525373Y876434D03*
X1516121Y886001D03*
X1514271Y895568D03*
X1516121Y905134D03*
Y924268D03*
X1514271Y914701D03*
Y933835D03*
X1516121Y943402D03*
X1514271Y952969D03*
X1516121Y962536D03*
Y981670D03*
X1514271Y972103D03*
X1516121Y1000804D03*
X1514271Y991237D03*
X1519822Y994426D03*
X1525373Y991237D03*
X1514271Y1010371D03*
X1517972D03*
X1519153Y1028055D03*
X1526554D03*
X1517302Y1037622D03*
X1524704Y1044000D03*
Y1031244D03*
X1517302Y1056756D03*
X1515452Y1047189D03*
X1524704Y1056756D03*
X1526554Y1047189D03*
X1519153Y1053567D03*
X1515452Y1066323D03*
Y1085457D03*
X1517302Y1075890D03*
X1515452Y1104591D03*
X1517302Y1095024D03*
Y1114158D03*
Y1133292D03*
X1515452Y1123725D03*
Y1142858D03*
X1517302Y1152425D03*
X1521003Y1158803D03*
X1515452Y1161992D03*
X1542027Y879623D03*
X1540176Y876434D03*
X1530924Y873245D03*
X1534625Y879623D03*
X1536476Y876434D03*
X1540176Y895568D03*
X1542027Y886001D03*
X1532775Y882812D03*
X1542027Y905134D03*
Y924268D03*
X1540176Y914701D03*
Y933835D03*
Y952969D03*
X1542027Y943402D03*
Y962536D03*
Y981670D03*
X1540176Y972103D03*
X1542027Y1000804D03*
X1540176Y991237D03*
X1530924Y994426D03*
X1536476Y991237D03*
X1540176Y1010371D03*
X1532775D03*
X1533956Y1028055D03*
X1537657D03*
X1543208Y1037622D03*
X1539507Y1044000D03*
Y1031244D03*
X1543208Y1056756D03*
X1541357Y1047189D03*
X1539507Y1056756D03*
X1537657Y1047189D03*
X1533956Y1053567D03*
X1541357Y1066323D03*
Y1085457D03*
X1543208Y1075890D03*
X1541357Y1104591D03*
X1543208Y1095024D03*
Y1114158D03*
Y1133292D03*
X1541357Y1123725D03*
Y1142858D03*
X1533956Y1161992D03*
X1543208Y1158803D03*
X1539507D03*
X1543208Y1152425D03*
X1537657Y1161992D03*
X1530255D03*
X1535368Y1540355D03*
X1537468D03*
X1538875Y1547073D03*
X1538819Y1549336D03*
X1539170Y1567540D03*
X1539171Y1564618D03*
X1539082Y1561698D03*
X1538585Y1571658D03*
X1539170Y1569640D03*
X1549428Y879623D03*
X1545728D03*
X1543877Y1010371D03*
X1545058Y1028055D03*
X1548759Y1161992D03*
X1546909Y1165181D03*
X1580940Y1540460D03*
X1578689Y1540509D03*
X1578854Y1546218D03*
X1577195Y1551121D03*
X1577596Y1554612D03*
X1577642Y1568698D03*
Y1570898D03*
X1583160Y1577625D03*
X1579089Y1573317D03*
X1663430Y1540355D03*
X1665530D03*
X1666937Y1547073D03*
X1666881Y1549336D03*
X1667231Y1567540D03*
X1667232Y1564618D03*
X1667143Y1561698D03*
X1670227Y1567413D03*
X1668750Y1563158D03*
X1666647Y1571658D03*
X1667231Y1569640D03*
G54D41*
X326731Y653394D03*
X363731D03*
X433624Y594259D03*
X754645Y1426892D03*
X766889Y1486756D03*
Y1530256D03*
X1166535Y1412479D03*
X1291146Y1375715D03*
X1320516D03*
X1415690Y601230D03*
X1487677Y640145D03*
X1524437Y640365D03*
X1701285Y198612D03*
X1700840Y1424519D03*
X1731660Y198612D03*
X1770442Y284934D03*
X1800002D03*
G54D25*
X79729Y289822D03*
Y310256D03*
X89729Y289822D03*
X99729D03*
X89729Y310256D03*
X99729D03*
X757184Y1712772D03*
Y1722772D03*
X1072863Y1419176D03*
Y1429176D03*
X1080970Y1650958D03*
Y1660958D03*
X1299439Y92812D03*
Y102812D03*
X1530377Y581353D03*
X1540377D03*
G54D68*
X1233404Y60384D03*
X1241278D03*
X1249152D03*
X1439049Y87432D03*
X1431175D03*
X1446923D03*
G54D23*
X64823Y756832D03*
Y760178D03*
X73933Y768706D03*
X73960Y766090D03*
X69323Y1068052D03*
Y1064706D03*
X94524Y760178D03*
Y756832D03*
X89965D03*
X90015Y766871D03*
X89965Y763525D03*
X94474D03*
X90015Y770218D03*
X85465Y960966D03*
X90965D03*
X103574Y763766D03*
X99024Y1068052D03*
Y1064706D03*
X124224Y760178D03*
Y756832D03*
X119666D03*
X119616Y767166D03*
X119666Y763525D03*
X124174D03*
X119716Y770218D03*
X115166Y960966D03*
X120666D03*
X133124Y763766D03*
X128724Y1068052D03*
Y1064706D03*
X153925Y760178D03*
Y756832D03*
X149366D03*
X149416Y766871D03*
X149366Y763525D03*
X153875D03*
X149416Y770218D03*
X144866Y960966D03*
X150366D03*
X162975Y763766D03*
X158425Y1068052D03*
Y1064706D03*
X183626Y760178D03*
Y756832D03*
X179067D03*
X179117Y766871D03*
X179067Y763525D03*
X183576D03*
X179117Y770218D03*
X174567Y960966D03*
X180067D03*
X186530Y1523953D03*
X192676Y763766D03*
X188126Y1068052D03*
Y1064706D03*
X195979Y1523953D03*
X196530Y1526353D03*
X191805D03*
X187081D03*
X200703Y1523953D03*
X201254Y1526353D03*
X191254Y1523953D03*
X188254Y1544997D03*
X192978D03*
X197703D03*
X188254Y1548397D03*
X192978D03*
X197703D03*
X194196Y1602380D03*
X197596D03*
X194196Y1614292D03*
X197596D03*
X213327Y760178D03*
Y756832D03*
X208768D03*
Y763525D03*
X212772Y766871D03*
X213277Y763525D03*
X208818Y770218D03*
X204268Y960966D03*
X209768D03*
X205427Y1523953D03*
X205978Y1526353D03*
X210703D03*
X210152Y1523953D03*
X214876D03*
X215427Y1526353D03*
X202427Y1544997D03*
X207152D03*
X211876D03*
X216601D03*
X202427Y1548397D03*
X207152D03*
X211876D03*
X216601D03*
X206256Y1602380D03*
X209656D03*
X206256Y1614292D03*
X209656D03*
X222377Y763766D03*
X227540Y960966D03*
X220152Y1526353D03*
X224876D03*
X224325Y1523953D03*
X219601D03*
X229049D03*
X229600Y1526353D03*
X221325Y1544997D03*
X226050D03*
X230774D03*
X221325Y1548397D03*
X226050D03*
X230774D03*
X218316Y1602380D03*
X230376D03*
X221716D03*
X218316Y1614292D03*
X230376D03*
X221716D03*
X238469Y756832D03*
Y763525D03*
X238519Y770218D03*
X233969Y960966D03*
X243223Y1523953D03*
X243774Y1526353D03*
X238498Y1523953D03*
X239049Y1526353D03*
X233774Y1523953D03*
X234325Y1526353D03*
X235499Y1544997D03*
X240223D03*
X244947D03*
X235499Y1548397D03*
X240223D03*
X244947D03*
X242436Y1602380D03*
X233776D03*
X245836D03*
X242436Y1614292D03*
X233776D03*
X245836D03*
X257396Y1523953D03*
X253223Y1526353D03*
X252672Y1523953D03*
X257947Y1526353D03*
X248498D03*
X247947Y1523953D03*
X249671Y1544997D03*
X254396D03*
X259120D03*
X249671Y1548397D03*
X254396D03*
X259120D03*
X254496Y1602380D03*
X257896D03*
X254496Y1614292D03*
X257896D03*
X272525Y108556D03*
X268981D03*
Y111056D03*
X265438Y108556D03*
X261895D03*
Y111056D03*
X265438D03*
X272525D03*
X266556Y1602380D03*
X269956D03*
X266556Y1614292D03*
X269956D03*
X278616Y1602380D03*
X290676D03*
X282016D03*
X278616Y1614292D03*
X290676D03*
X282016D03*
X302736Y1602380D03*
X294076D03*
X306136D03*
X302736Y1614292D03*
X294076D03*
X306136D03*
X306694Y1507279D03*
X319867Y1526353D03*
X315143D03*
X319316Y1523953D03*
X314592D03*
X314796Y1602380D03*
X318196D03*
X314796Y1614292D03*
X318196D03*
X324041Y1523953D03*
X324592Y1526353D03*
X328765Y1523953D03*
X329316Y1526353D03*
X334040D03*
X333489Y1523953D03*
X326856Y1602380D03*
X330256D03*
X326856Y1614292D03*
X330256D03*
X338765Y1526353D03*
X338214Y1523953D03*
X347663D03*
X348214Y1526353D03*
X343489D03*
X342938Y1523953D03*
X338916Y1602380D03*
X350976D03*
X342316D03*
X338916Y1614292D03*
X350976D03*
X342316D03*
X362387Y1526353D03*
X361836Y1523953D03*
X352387D03*
X352938Y1526353D03*
X357662D03*
X357111Y1523953D03*
X363036Y1602380D03*
X354376D03*
X363036Y1614292D03*
X354376D03*
X380734Y1523953D03*
X376560Y1526353D03*
X376009Y1523953D03*
X371285D03*
X371836Y1526353D03*
X367111D03*
X366560Y1523953D03*
X375096Y1602380D03*
X366436D03*
X378496D03*
X375096Y1614292D03*
X366436D03*
X378496D03*
X385458Y1523953D03*
X381285Y1526353D03*
X386009D03*
X450703Y1523953D03*
X451254Y1526353D03*
X464876Y1523953D03*
X460703Y1526353D03*
X455978D03*
X465427D03*
X455427Y1523953D03*
X460152D03*
X469600D03*
X470151Y1526353D03*
X458369Y1602380D03*
X461769D03*
X458369Y1614292D03*
X461769D03*
X474325Y1523953D03*
X474876Y1526353D03*
X483774Y1523953D03*
X484325Y1526353D03*
X479049Y1523953D03*
X479600Y1526353D03*
X470429Y1602380D03*
X482489D03*
X473829D03*
X470429Y1614292D03*
X482489D03*
X473829D03*
X497947Y1523953D03*
X498498Y1526353D03*
X488498Y1523953D03*
X489049Y1526353D03*
X493222Y1523953D03*
X493773Y1526353D03*
X494549Y1602380D03*
X485889D03*
X497949D03*
X494549Y1614292D03*
X485889D03*
X497949D03*
X507947Y1526353D03*
X507396Y1523953D03*
X512120D03*
X512671Y1526353D03*
X503222D03*
X502671Y1523953D03*
X506609Y1602380D03*
X510009D03*
X506609Y1614292D03*
X510009D03*
X521569Y1523953D03*
X522120Y1526353D03*
X517396D03*
X516845Y1523953D03*
X518669Y1602380D03*
X522069D03*
X518669Y1614292D03*
X522069D03*
X530729Y1602380D03*
X542789D03*
X534129D03*
X530729Y1614292D03*
X542789D03*
X534129D03*
X554849Y1602380D03*
X546189D03*
X558249D03*
X554849Y1614292D03*
X546189D03*
X558249D03*
X566909Y1602380D03*
X570309D03*
X566909Y1614292D03*
X570309D03*
X588765Y1526353D03*
X588214Y1523953D03*
X578765D03*
X583489D03*
X579316Y1526353D03*
X584040D03*
X580489Y1544997D03*
X585213D03*
X580489Y1548397D03*
X585213D03*
X578969Y1602380D03*
X582369D03*
X578969Y1614292D03*
X582369D03*
X602387Y1523953D03*
X602938Y1526353D03*
X592938Y1523953D03*
X593489Y1526353D03*
X598213D03*
X597662Y1523953D03*
X589938Y1544997D03*
X594662D03*
X599387D03*
X604111D03*
X589938Y1548397D03*
X594662D03*
X599387D03*
X604111D03*
X591029Y1602380D03*
X603089D03*
X594429D03*
X591029Y1614292D03*
X603089D03*
X594429D03*
X616560Y1523953D03*
X617111Y1526353D03*
X607111Y1523953D03*
X607662Y1526353D03*
X612387D03*
X611836Y1523953D03*
X608836Y1544997D03*
X613560D03*
X618285D03*
X608836Y1548397D03*
X613560D03*
X618285D03*
X615149Y1602380D03*
X606489D03*
X618549D03*
X615149Y1614292D03*
X606489D03*
X618549D03*
X626009Y1523953D03*
X626560Y1526353D03*
X631284D03*
X630733Y1523953D03*
X621835Y1526353D03*
X621284Y1523953D03*
X627734Y1544997D03*
X632458D03*
X623009D03*
X627734Y1548397D03*
X632458D03*
X623009D03*
X627209Y1602380D03*
X630609D03*
X627209Y1614292D03*
X630609D03*
X642854Y760178D03*
Y756832D03*
X642804Y763525D03*
X644907Y1523953D03*
X640733Y1526353D03*
X640182Y1523953D03*
X635458D03*
X636009Y1526353D03*
X645458D03*
X637182Y1544997D03*
X641906D03*
X646631D03*
X637182Y1548397D03*
X641906D03*
X646631D03*
X639269Y1602380D03*
X642669D03*
X639269Y1614292D03*
X642669D03*
X651905Y763766D03*
X663496Y960966D03*
X657996D03*
X650182Y1526353D03*
X649631Y1523953D03*
X651355Y1544997D03*
Y1548397D03*
X664634Y449952D03*
X667996Y756832D03*
X672555D03*
Y760178D03*
X668046Y766871D03*
X667996Y763525D03*
X672505D03*
X668046Y770218D03*
X677055Y1068052D03*
Y1064706D03*
X695796Y430957D03*
Y437256D03*
Y468672D03*
X681606Y763766D03*
X693197Y960966D03*
X687697D03*
X698599Y115178D03*
X705686D03*
X702142D03*
X698599Y112678D03*
X705686D03*
X702142D03*
X695056D03*
Y115178D03*
X708395Y427807D03*
Y424657D03*
X705245D03*
Y427807D03*
X702095D03*
X708395Y434106D03*
X705245Y430957D03*
X702095Y434106D03*
X698946Y427807D03*
X705245Y437256D03*
X698946Y430957D03*
X705245Y434106D03*
X702095Y430957D03*
X705245Y446705D03*
X708395Y440405D03*
Y443555D03*
X702095Y446705D03*
X705245Y443555D03*
X702095Y437256D03*
Y440405D03*
Y443555D03*
X705245Y440405D03*
X708395Y437256D03*
X698946Y446705D03*
X708395D03*
X698946Y449854D03*
X708395Y462373D03*
Y449854D03*
X705245Y459223D03*
X702095Y456074D03*
Y459223D03*
X708395Y456074D03*
X705245Y462373D03*
X702095D03*
X705245Y456074D03*
X695796Y449854D03*
X708395Y459223D03*
Y465523D03*
X705245Y468672D03*
X702095D03*
X698946Y471822D03*
X702095Y465523D03*
X695796Y471822D03*
X708395Y478121D03*
X705245Y471822D03*
X695796Y465523D03*
X702095Y478121D03*
X705245Y474971D03*
X708395Y471822D03*
Y468672D03*
X705245Y465523D03*
X702095Y471822D03*
X698946Y465523D03*
X705245Y478121D03*
X702095Y474971D03*
X698946Y487570D03*
Y481271D03*
Y484420D03*
X705245Y481271D03*
X702095D03*
X695796Y484420D03*
X708395D03*
Y481271D03*
X697697Y756832D03*
X702256D03*
Y760178D03*
X697747Y766871D03*
X697697Y763525D03*
X702206D03*
X697747Y770218D03*
X706756Y1068052D03*
Y1064706D03*
X720993Y418358D03*
X717843D03*
Y421508D03*
X720993Y430957D03*
X711544D03*
X714694D03*
X717843Y434106D03*
X720993D03*
X717843Y430957D03*
X720993Y421508D03*
X711544Y434106D03*
X714694D03*
X720993Y424657D03*
X717843D03*
Y427807D03*
X714694Y424657D03*
Y427807D03*
X711544Y424657D03*
Y427807D03*
X720993D03*
X717843Y437256D03*
X720993D03*
X714694D03*
X711544D03*
Y443555D03*
X717843D03*
X714694Y446705D03*
Y440405D03*
X720993D03*
X711544D03*
X714694Y443555D03*
X711544Y446705D03*
Y459223D03*
X714694D03*
X717843Y462373D03*
Y456074D03*
Y449854D03*
X714694Y462373D03*
X711544D03*
X714694Y449854D03*
X711544D03*
X714694Y456074D03*
X711544D03*
X720993Y471822D03*
Y468672D03*
X711544Y478121D03*
X717843Y474971D03*
X724143Y471822D03*
X720993Y478121D03*
X717843D03*
X720993Y474971D03*
X714694Y465523D03*
X717843Y471822D03*
Y468672D03*
X714694Y471822D03*
X711544D03*
X714694Y468672D03*
X711544D03*
X720993Y465523D03*
X711544Y474971D03*
X714694Y478121D03*
Y474971D03*
X724143Y481271D03*
X711544Y465523D03*
X717843Y481271D03*
X714694D03*
X720993D03*
X711544D03*
X720993Y484420D03*
X711307Y763766D03*
X722898Y960966D03*
X717398D03*
X731208Y398737D03*
X733512Y418358D03*
X727292D03*
X724143D03*
X736661Y424657D03*
Y430957D03*
Y434106D03*
X733512D03*
Y421508D03*
Y424657D03*
Y430957D03*
X727292D03*
Y434106D03*
X724143Y430957D03*
X727292Y427807D03*
X736661D03*
X727292Y424657D03*
X724143Y434106D03*
Y421508D03*
X739811Y430957D03*
X724143Y427807D03*
Y424657D03*
X733512Y437256D03*
X727292Y440405D03*
X724143Y446705D03*
X736661D03*
X733512Y440405D03*
X736661D03*
X727292Y437256D03*
X724143Y440405D03*
Y437256D03*
X736661D03*
Y459223D03*
Y456074D03*
X733512D03*
Y449854D03*
X736661D03*
X727292Y456074D03*
X724143Y459223D03*
Y456074D03*
X727292Y449854D03*
X724143D03*
X727292Y471822D03*
X724143Y468672D03*
X727292D03*
X736661D03*
X724143Y474971D03*
X733512Y478121D03*
X724143Y465523D03*
X727292D03*
X733512D03*
X736661D03*
X733512Y474971D03*
Y468672D03*
X736661Y478121D03*
Y471822D03*
X724143Y478121D03*
X727292D03*
X733512Y471822D03*
X736661Y474971D03*
Y487570D03*
Y481271D03*
X733512D03*
X727292D03*
X724143Y487570D03*
X727292Y484420D03*
Y487570D03*
X727398Y756832D03*
X731957D03*
Y760178D03*
X727398Y763525D03*
X731462Y766871D03*
X731907Y763525D03*
X727448Y770218D03*
X736457Y1068052D03*
Y1064706D03*
X755559Y421508D03*
X739811Y424657D03*
Y427807D03*
X742961Y424657D03*
Y427807D03*
X746110Y424657D03*
Y427807D03*
X752409Y430957D03*
Y434106D03*
X749260D03*
X752409Y424657D03*
X749260D03*
X746110Y430957D03*
X749260D03*
X742961D03*
X752409Y427807D03*
X749260D03*
X739811Y434106D03*
X742961D03*
X746110D03*
X752409Y443555D03*
X739811Y437256D03*
X746110D03*
X742961D03*
X746110Y440405D03*
X749260Y437256D03*
X739811Y440405D03*
X742961Y443555D03*
Y446705D03*
X752409Y440405D03*
X749260D03*
Y446705D03*
X752409Y437256D03*
Y446705D03*
X746110D03*
Y443555D03*
X749260D03*
X742961Y459223D03*
Y462373D03*
Y456074D03*
Y449854D03*
X752409Y456074D03*
X749260Y449854D03*
X746110Y459223D03*
X752409Y462373D03*
Y459223D03*
X749260D03*
X746110Y456074D03*
Y449854D03*
Y462373D03*
X749260D03*
X752409Y449854D03*
X749260Y456074D03*
X742961Y474971D03*
Y468672D03*
X739811Y478121D03*
Y474971D03*
Y471822D03*
X749260D03*
X739811Y468672D03*
X749260D03*
Y474971D03*
X742961Y471822D03*
X749260Y478121D03*
X746110Y474971D03*
X752409Y468672D03*
X742961Y478121D03*
X746110Y468672D03*
X739811Y465523D03*
X752409Y478121D03*
Y471822D03*
Y465523D03*
X746110D03*
X749260D03*
X752409Y474971D03*
X746110Y478121D03*
Y471822D03*
X749260Y481271D03*
X742961Y484420D03*
X739811Y481271D03*
X746110Y484420D03*
X749260D03*
X752409Y487570D03*
X742961D03*
Y490070D03*
X746110Y481271D03*
X752409D03*
X742961D03*
X741007Y763766D03*
X752599Y960966D03*
X747099D03*
X755559Y418358D03*
X758709D03*
X761858D03*
X755559Y427807D03*
Y430957D03*
X758709Y427807D03*
Y430957D03*
X765008Y424657D03*
X755559D03*
X758709D03*
Y421508D03*
X761858Y424657D03*
X765008Y430957D03*
X755559Y434106D03*
X761858Y430957D03*
Y427807D03*
X758709Y434106D03*
X765008Y427807D03*
Y446705D03*
X758709D03*
X755559Y443555D03*
Y446705D03*
Y437256D03*
X758709Y440405D03*
X755559D03*
X758709Y443555D03*
X761858Y446705D03*
X755559Y449854D03*
Y459223D03*
X765008Y456074D03*
X758709Y465523D03*
X755559Y462373D03*
X758709Y459223D03*
Y462373D03*
Y456074D03*
Y449854D03*
X755559Y478121D03*
Y468672D03*
Y471822D03*
X758709D03*
X761858Y478121D03*
Y474971D03*
Y471822D03*
X758709Y474971D03*
X765008Y471822D03*
Y474971D03*
Y465523D03*
X758709Y478121D03*
X761858Y468672D03*
Y465523D03*
X765008Y468672D03*
X755559Y465523D03*
Y474971D03*
Y481271D03*
Y484420D03*
X765008Y481271D03*
X761858D03*
X758709D03*
X757099Y756832D03*
X761658D03*
Y760178D03*
X757149Y766871D03*
X757099Y763525D03*
X761608D03*
X757149Y770218D03*
X766158Y1068052D03*
Y1064706D03*
X770708Y763766D03*
X782300Y960966D03*
X776800D03*
X786800Y756832D03*
X791358Y760178D03*
Y756832D03*
X786850Y766871D03*
X786800Y763525D03*
X791308D03*
X786850Y770218D03*
X795858Y1068052D03*
Y1064706D03*
X800409Y763765D03*
X812000Y960966D03*
X806500D03*
X816500Y756832D03*
X816550Y770218D03*
X816500Y763525D03*
X998206Y196191D03*
X1000706D03*
X998206Y199735D03*
X1000706D03*
X998206Y206821D03*
X1000706D03*
X998206Y203278D03*
X1000706D03*
X1040965Y756831D03*
Y760177D03*
X1050015Y763765D03*
X1040915Y763524D03*
X1045465Y1068051D03*
Y1064705D03*
X1066107Y756831D03*
X1066157Y766870D03*
X1066107Y763524D03*
X1066157Y770217D03*
X1061607Y960965D03*
X1070666Y756831D03*
Y760177D03*
X1079716Y763765D03*
X1070616Y763524D03*
X1067107Y960965D03*
X1075166Y1068051D03*
Y1064705D03*
X1095808Y756831D03*
X1095858Y766870D03*
X1095808Y763524D03*
X1095858Y770217D03*
X1091308Y960965D03*
X1100366Y756831D03*
Y760177D03*
X1109416Y763765D03*
X1100316Y763524D03*
X1096808Y960965D03*
X1104866Y1068051D03*
Y1064705D03*
X1125508Y756831D03*
X1125558Y766870D03*
X1125508Y763524D03*
X1125558Y770217D03*
X1121008Y960965D03*
X1130067Y756831D03*
Y760177D03*
X1139117Y763765D03*
X1130017Y763524D03*
X1126508Y960965D03*
X1134567Y1068051D03*
Y1064705D03*
X1155209Y756831D03*
Y763524D03*
X1155259Y770217D03*
X1150709Y960965D03*
X1159768Y756831D03*
Y760177D03*
X1168818Y763765D03*
X1159718Y763524D03*
X1156209Y960965D03*
X1164268Y1068051D03*
Y1064705D03*
X1184910Y756831D03*
Y763524D03*
X1184960Y770217D03*
X1180410Y960965D03*
X1189469Y760177D03*
Y756831D03*
X1198519Y763765D03*
X1188805Y766870D03*
X1189419Y763524D03*
X1185910Y960965D03*
X1194403Y1556953D03*
X1199678Y1559353D03*
X1194954D03*
X1199127Y1556953D03*
X1196127Y1577997D03*
Y1581397D03*
X1214600Y759562D03*
X1205448Y769914D03*
X1214661Y766870D03*
X1214611Y763524D03*
X1214841Y772277D03*
X1210111Y960965D03*
X1203682D03*
X1208576Y1556953D03*
X1204403Y1559353D03*
X1209127D03*
X1203852Y1556953D03*
X1213300D03*
X1213851Y1559353D03*
X1200851Y1577997D03*
X1205576D03*
X1210300D03*
X1215025D03*
X1200851Y1581397D03*
X1205576D03*
X1210300D03*
X1215025D03*
X1202069Y1635380D03*
X1214129D03*
X1205469D03*
X1202069Y1647292D03*
X1214129D03*
X1205469D03*
X1218025Y1556953D03*
X1218576Y1559353D03*
X1227474Y1556953D03*
X1228025Y1559353D03*
X1222749Y1556953D03*
X1223300Y1559353D03*
X1219749Y1577997D03*
X1224474D03*
X1229198D03*
X1219749Y1581397D03*
X1224474D03*
X1229198D03*
X1226189Y1635380D03*
X1217529D03*
X1229589D03*
X1226189Y1647292D03*
X1217529D03*
X1229589D03*
X1241647Y1556953D03*
X1242198Y1559353D03*
X1232198Y1556953D03*
X1232749Y1559353D03*
X1236922Y1556953D03*
X1237473Y1559353D03*
X1243372Y1577997D03*
X1233923D03*
X1238647D03*
X1243372Y1581397D03*
X1233923D03*
X1238647D03*
X1238249Y1635380D03*
X1241649D03*
X1238249Y1647292D03*
X1241649D03*
X1251647Y1559353D03*
X1251096Y1556953D03*
X1255820D03*
X1256371Y1559353D03*
X1246371Y1556953D03*
X1246922Y1559353D03*
X1248096Y1577997D03*
X1252820D03*
X1257544D03*
X1248096Y1581397D03*
X1252820D03*
X1257544D03*
X1250309Y1635380D03*
X1253709D03*
X1250309Y1647292D03*
X1253709D03*
X1265269Y1556953D03*
X1265820Y1559353D03*
X1261096D03*
X1260545Y1556953D03*
X1262269Y1577997D03*
X1266993D03*
X1262269Y1581397D03*
X1266993D03*
X1262369Y1635380D03*
X1274429D03*
X1265769D03*
X1262369Y1647292D03*
X1274429D03*
X1265769D03*
X1286489Y1635380D03*
X1277829D03*
X1289889D03*
X1286489Y1647292D03*
X1277829D03*
X1289889D03*
X1298549Y1635380D03*
X1301949D03*
X1298549Y1647292D03*
X1301949D03*
X1310609Y1635380D03*
X1314009D03*
X1310609Y1647292D03*
X1314009D03*
X1332465Y1559353D03*
X1331914Y1556953D03*
X1322465D03*
X1327189D03*
X1323016Y1559353D03*
X1327740D03*
X1322669Y1635380D03*
X1334729D03*
X1326069D03*
X1322669Y1647292D03*
X1334729D03*
X1326069D03*
X1346087Y1556953D03*
X1346638Y1559353D03*
X1336638Y1556953D03*
X1337189Y1559353D03*
X1341913D03*
X1341362Y1556953D03*
X1346789Y1635380D03*
X1338129D03*
X1346789Y1647292D03*
X1338129D03*
X1360260Y1556953D03*
X1360811Y1559353D03*
X1350811Y1556953D03*
X1351362Y1559353D03*
X1356087D03*
X1355536Y1556953D03*
X1358849Y1635380D03*
X1350189D03*
X1362249D03*
X1358849Y1647292D03*
X1350189D03*
X1362249D03*
X1369709Y1556953D03*
X1370260Y1559353D03*
X1379158Y1556953D03*
X1374984Y1559353D03*
X1374433Y1556953D03*
X1365535Y1559353D03*
X1364984Y1556953D03*
X1370909Y1635380D03*
X1374309D03*
X1370909Y1647292D03*
X1374309D03*
X1388607Y1556953D03*
X1384433Y1559353D03*
X1383882Y1556953D03*
X1379709Y1559353D03*
X1393882D03*
X1389158D03*
X1393331Y1556953D03*
X1382969Y1635380D03*
X1386369D03*
X1382969Y1647292D03*
X1386369D03*
X1458577Y1556953D03*
X1468577Y1559353D03*
X1463852D03*
X1459128D03*
X1463301Y1556953D03*
X1468026D03*
X1466243Y1635380D03*
Y1647292D03*
X1482199Y1556953D03*
X1482750Y1559353D03*
X1472750Y1556953D03*
X1473301Y1559353D03*
X1477474Y1556953D03*
X1478025Y1559353D03*
X1478303Y1635380D03*
X1469643D03*
X1481703D03*
X1478303Y1647292D03*
X1469643D03*
X1481703D03*
X1496372Y1556953D03*
X1491648D03*
X1496923Y1559353D03*
X1492199D03*
X1486923Y1556953D03*
X1487474Y1559353D03*
X1490363Y1635380D03*
X1493763D03*
X1490363Y1647292D03*
X1493763D03*
X1505821Y1556953D03*
X1506372Y1559353D03*
X1511096D03*
X1510545Y1556953D03*
X1501096D03*
X1501647Y1559353D03*
X1502423Y1635380D03*
X1505823D03*
X1502423Y1647292D03*
X1505823D03*
X1515821Y1559353D03*
X1515270Y1556953D03*
X1519994D03*
X1520545Y1559353D03*
X1525270D03*
X1524719Y1556953D03*
X1514483Y1635380D03*
X1526543D03*
X1517883D03*
X1514483Y1647292D03*
X1526543D03*
X1517883D03*
X1529443Y1556953D03*
X1529994Y1559353D03*
X1538603Y1635380D03*
X1529943D03*
X1542003D03*
X1538603Y1647292D03*
X1529943D03*
X1542003D03*
X1550663Y1635380D03*
X1554063D03*
X1550663Y1647292D03*
X1554063D03*
X1562723Y1635380D03*
X1566123D03*
X1562723Y1647292D03*
X1566123D03*
X1586639Y1556953D03*
X1587190Y1559353D03*
X1588363Y1577997D03*
Y1581397D03*
X1586843Y1635380D03*
X1574783D03*
X1578183D03*
X1586843Y1647292D03*
X1574783D03*
X1578183D03*
X1600812Y1556953D03*
X1596639Y1559353D03*
X1596088Y1556953D03*
X1601363Y1559353D03*
X1591363Y1556953D03*
X1591914Y1559353D03*
X1593087Y1577997D03*
X1597812D03*
X1602536D03*
X1593087Y1581397D03*
X1597812D03*
X1602536D03*
X1598903Y1635380D03*
X1590243D03*
X1602303D03*
X1598903Y1647292D03*
X1590243D03*
X1602303D03*
X1610261Y1556953D03*
X1610812Y1559353D03*
X1606087D03*
X1605536Y1556953D03*
X1614985D03*
X1615536Y1559353D03*
X1607261Y1577997D03*
X1611985D03*
X1616710D03*
X1607261Y1581397D03*
X1611985D03*
X1616710D03*
X1610963Y1635380D03*
X1614363D03*
X1610963Y1647292D03*
X1614363D03*
X1618996Y760177D03*
Y756831D03*
X1618946Y763524D03*
X1624434Y1556953D03*
X1624985Y1559353D03*
X1620261D03*
X1619710Y1556953D03*
X1629709Y1559353D03*
X1629158Y1556953D03*
X1621434Y1577997D03*
X1626159D03*
X1630883D03*
X1621434Y1581397D03*
X1626159D03*
X1630883D03*
X1623023Y1635380D03*
X1626423D03*
X1623023Y1647292D03*
X1626423D03*
X1644138Y756831D03*
Y763524D03*
X1644188Y770217D03*
X1639638Y960965D03*
X1634138D03*
X1633883Y1556953D03*
X1634434Y1559353D03*
X1643332Y1556953D03*
X1643883Y1559353D03*
X1639158D03*
X1638607Y1556953D03*
X1635608Y1577997D03*
X1640332D03*
X1645056D03*
X1635608Y1581397D03*
X1640332D03*
X1645056D03*
X1635083Y1635380D03*
X1647143D03*
X1638483D03*
X1635083Y1647292D03*
X1647143D03*
X1638483D03*
X1648697Y760177D03*
Y756831D03*
X1657747Y763765D03*
X1648647Y766870D03*
Y763524D03*
X1653197Y1068051D03*
Y1064705D03*
X1652781Y1556953D03*
X1648607Y1559353D03*
X1648056Y1556953D03*
X1658056Y1559353D03*
X1653332D03*
X1657505Y1556953D03*
X1649780Y1577997D03*
X1654505D03*
X1659229D03*
X1649780Y1581397D03*
X1654505D03*
X1659229D03*
X1650543Y1635380D03*
Y1647292D03*
X1673839Y756831D03*
Y763524D03*
X1673889Y770217D03*
X1669339Y960965D03*
X1663839D03*
X1678398Y760177D03*
Y756831D03*
X1687448Y763765D03*
X1678348Y766870D03*
Y763524D03*
X1682898Y1068051D03*
Y1064705D03*
X1703540Y756831D03*
X1703590Y766870D03*
X1703540Y763524D03*
X1703590Y770217D03*
X1699040Y960965D03*
X1693540D03*
X1708099Y760177D03*
Y756831D03*
X1717149Y763765D03*
X1708049Y763524D03*
X1712599Y1068051D03*
Y1064705D03*
X1736986Y109723D03*
Y112223D03*
X1733241Y756831D03*
X1733727Y766870D03*
X1733241Y763524D03*
X1733291Y770217D03*
X1728741Y960965D03*
X1723241D03*
X1740529Y112223D03*
Y109723D03*
X1744072Y112223D03*
Y109723D03*
X1747616Y112223D03*
Y109723D03*
X1737800Y756831D03*
Y760177D03*
X1746850Y763765D03*
X1737750Y763524D03*
X1742300Y1068051D03*
Y1064705D03*
X1762942Y756831D03*
X1762992Y766870D03*
X1762942Y763524D03*
X1762992Y770217D03*
X1758442Y960965D03*
X1752942D03*
X1767500Y760177D03*
Y756831D03*
X1767450Y763524D03*
X1772000Y1068051D03*
Y1064705D03*
X1792642Y756831D03*
Y763524D03*
X1792692Y770217D03*
X1788142Y960965D03*
X1782642D03*
G54D43*
X373673Y-28871D03*
Y-18871D03*
D03*
Y-8871D03*
X398673Y-28871D03*
Y-18871D03*
D03*
Y-8871D03*
X718093Y-28871D03*
Y-18871D03*
D03*
Y-8871D03*
X743093Y-28871D03*
Y-18871D03*
D03*
Y-8871D03*
X825152Y-35011D03*
Y-25011D03*
Y-15011D03*
Y-25011D03*
Y-15011D03*
Y-5011D03*
D03*
Y4989D03*
Y14989D03*
D03*
Y4989D03*
Y24989D03*
X850152Y-35011D03*
Y-25011D03*
Y-15011D03*
Y-25011D03*
Y-15011D03*
Y-5011D03*
D03*
Y4989D03*
Y14989D03*
D03*
Y4989D03*
Y24989D03*
X1169572Y-35011D03*
Y-15011D03*
Y-25011D03*
D03*
Y-15011D03*
Y-5011D03*
D03*
Y4989D03*
Y14989D03*
Y4989D03*
Y14989D03*
Y24989D03*
X1194572Y-35011D03*
Y-15011D03*
Y-25011D03*
D03*
Y-15011D03*
Y-5011D03*
D03*
Y4989D03*
Y14989D03*
Y4989D03*
Y14989D03*
Y24989D03*
X1228672Y-35011D03*
Y-25011D03*
Y-15011D03*
Y-25011D03*
Y-15011D03*
Y-5011D03*
D03*
Y4989D03*
Y14989D03*
D03*
Y4989D03*
Y24989D03*
X1253672Y-35011D03*
Y-25011D03*
Y-15011D03*
Y-25011D03*
Y-15011D03*
Y-5011D03*
D03*
Y4989D03*
Y14989D03*
D03*
Y4989D03*
Y24989D03*
X1428431Y-35011D03*
Y-15011D03*
Y-25011D03*
D03*
Y-15011D03*
Y-5011D03*
D03*
Y4989D03*
Y14989D03*
Y4989D03*
Y14989D03*
Y24989D03*
X1453431Y-35011D03*
Y-15011D03*
Y-25011D03*
D03*
Y-15011D03*
Y-5011D03*
D03*
Y4989D03*
Y14989D03*
Y4989D03*
Y14989D03*
Y24989D03*
X1521966Y-29212D03*
D03*
Y-39212D03*
Y-19212D03*
X1546966Y-29212D03*
D03*
Y-39212D03*
Y-19212D03*
X1721725Y-29212D03*
Y-39212D03*
Y-29212D03*
Y-19212D03*
X1746725Y-29212D03*
Y-39212D03*
Y-29212D03*
Y-19212D03*
G54D54*
X793879Y194881D03*
X789942Y204724D03*
X793879Y214567D03*
X805690Y188976D03*
Y220472D03*
X817501Y194881D03*
X821438Y204724D03*
X817501Y214567D03*
X828390Y1420331D03*
X841240Y1407481D03*
X832154Y1411245D03*
Y1429417D03*
X841240Y1433181D03*
X850326Y1411245D03*
Y1429417D03*
X854090Y1420331D03*
X1007154Y1411245D03*
X1003390Y1420331D03*
X1007154Y1429417D03*
X1016240Y1407481D03*
Y1433181D03*
X1025326Y1411245D03*
Y1429417D03*
X1029090Y1420331D03*
X1045848Y194881D03*
X1041911Y204724D03*
X1045848Y214567D03*
X1057659Y188976D03*
Y220472D03*
X1069470Y194881D03*
X1073407Y204724D03*
X1069470Y214567D03*
G54D10*
X3001Y61178D03*
Y127178D03*
Y149178D03*
Y171178D03*
Y193178D03*
Y215178D03*
Y237178D03*
Y259178D03*
Y281178D03*
Y303178D03*
X10875Y323721D03*
Y345721D03*
Y367721D03*
Y389721D03*
Y411721D03*
Y433721D03*
Y455721D03*
Y477721D03*
Y499721D03*
Y521721D03*
X20587Y523970D03*
X16342Y516951D03*
X16512Y533155D03*
X10875Y543721D03*
Y565721D03*
Y587721D03*
Y609721D03*
Y653721D03*
Y675721D03*
Y697721D03*
Y719721D03*
Y741721D03*
Y763721D03*
Y785721D03*
Y807721D03*
Y829721D03*
Y851721D03*
Y873721D03*
Y895721D03*
Y917721D03*
Y939721D03*
Y961721D03*
Y983721D03*
Y1005721D03*
Y1027721D03*
Y1049721D03*
Y1071721D03*
Y1093721D03*
Y1115721D03*
Y1137721D03*
Y1159721D03*
Y1181721D03*
Y1203721D03*
Y1225721D03*
Y1247721D03*
Y1269721D03*
Y1291721D03*
Y1445721D03*
Y1467721D03*
Y1489721D03*
Y1511721D03*
Y1533721D03*
Y1555721D03*
Y1577721D03*
X33184Y523285D03*
X36402Y528675D03*
X33257Y540370D03*
X26887Y541805D03*
X35133Y1603396D03*
X35167Y1610521D03*
X28592Y1617961D03*
X35233Y1623196D03*
X28592Y1639961D03*
Y1661961D03*
Y1683961D03*
X44600Y280357D03*
X50500Y311100D03*
X47602Y1622414D03*
X51333Y1640996D03*
X54584Y8335D03*
Y30335D03*
X58633Y1641388D03*
X85133Y1616396D03*
Y1620896D03*
Y1625396D03*
X85167Y1629905D03*
X101939Y1657742D03*
Y1662728D03*
X120891Y521216D03*
X144610Y429560D03*
X163113Y1486190D03*
X160513Y1479500D03*
Y1484280D03*
X165713Y1479500D03*
Y1484280D03*
X160513Y1501300D03*
Y1506080D03*
X165713D03*
X163113Y1507982D03*
X165713Y1501300D03*
X173488Y1510800D03*
Y1514420D03*
Y1518040D03*
X224055Y127146D03*
X262886Y147391D03*
X274201Y579478D03*
X280621Y1486682D03*
X291175Y1486190D03*
X288575Y1484280D03*
Y1479500D03*
X280621Y1500082D03*
X288575Y1506080D03*
Y1501300D03*
X291175Y1507990D03*
X301747Y121469D03*
Y127469D03*
Y124469D03*
X293775Y1484280D03*
Y1479500D03*
Y1506080D03*
Y1501300D03*
X304606Y1546333D03*
X297323Y1659772D03*
X311754Y121472D03*
Y124472D03*
Y127472D03*
X311476Y1552567D03*
X307255Y1649750D03*
X326475Y182855D03*
X349676Y276708D03*
X349695Y286712D03*
X380181Y236674D03*
X390461Y270694D03*
Y267694D03*
Y275194D03*
X387184Y494382D03*
X390082Y1549178D03*
X404743Y494451D03*
X408683Y1486682D03*
Y1500082D03*
X425555Y92014D03*
Y82014D03*
X412715Y254165D03*
X423730Y249570D03*
X412715Y262165D03*
Y270165D03*
X418543Y494374D03*
X418918Y1006025D03*
Y1013505D03*
Y1009765D03*
Y1024726D03*
Y1020986D03*
Y1028466D03*
Y1017245D03*
X415318Y1032206D03*
X424686Y1484280D03*
Y1479500D03*
Y1506080D03*
Y1501300D03*
X431299Y204145D03*
X432343Y494297D03*
X427286Y1486190D03*
X429886Y1484280D03*
Y1479500D03*
Y1506080D03*
Y1501300D03*
X427286Y1507990D03*
X438732Y1546977D03*
X444090Y116007D03*
X443400Y247880D03*
X448852Y283318D03*
X441159Y1055141D03*
X447587Y1552567D03*
X468228Y70016D03*
X457931Y212703D03*
X465699Y282833D03*
X469323Y306273D03*
X462093Y310123D03*
X467943Y311563D03*
X465153Y310123D03*
X467893Y308643D03*
X458873Y310173D03*
X455813D03*
X462365Y1006025D03*
Y1009765D03*
Y1013505D03*
Y1020986D03*
Y1028466D03*
Y1024726D03*
Y1017245D03*
Y1032206D03*
X462500Y1733500D03*
X480323Y291023D03*
X474691Y306073D03*
X471743Y304923D03*
X473643Y308683D03*
X471003Y311563D03*
X470953Y308643D03*
X484063Y313956D03*
X498776Y209285D03*
Y213285D03*
X500269Y225071D03*
X488908Y242754D03*
X503161Y149895D03*
X514418Y141171D03*
X515151Y220166D03*
X501718Y240558D03*
X508723Y280721D03*
X510223Y289035D03*
X507698D03*
Y297090D03*
X510223D03*
X507698Y305145D03*
X510223D03*
X510606Y314124D03*
X508081D03*
X523831Y95445D03*
Y102931D03*
X519579Y207435D03*
X530418Y141171D03*
X538567Y294777D03*
X542813Y319173D03*
X544794Y1486682D03*
Y1500082D03*
X549800Y147000D03*
X553300Y164500D03*
X556811Y152742D03*
X552699Y291833D03*
X556323Y315273D03*
X558743Y313923D03*
X545873Y319173D03*
X549093Y319123D03*
X558003Y320563D03*
X554943D03*
X552153Y319123D03*
X554893Y317643D03*
X557953D03*
X555348Y1486190D03*
X552748Y1484280D03*
Y1479500D03*
X557948Y1484280D03*
Y1479500D03*
X552748Y1506080D03*
Y1501300D03*
X557948Y1506080D03*
Y1501300D03*
X555348Y1507990D03*
X568472Y149226D03*
X563951Y160644D03*
X567323Y300023D03*
X561691Y315073D03*
X560643Y317683D03*
X568573Y321993D03*
X568779Y1546333D03*
X585685Y178125D03*
X578172Y231393D03*
X587140Y257630D03*
X575524Y261171D03*
X575649Y1552567D03*
X599678Y175534D03*
X595723Y289721D03*
X594698Y298035D03*
X597223D03*
X594698Y314145D03*
X597223D03*
X594698Y306090D03*
X597223D03*
Y322200D03*
X594698D03*
X600520Y401728D03*
X616654Y1382864D03*
X633805Y302289D03*
X642816Y574185D03*
X634529Y674890D03*
X640129D03*
X643649Y674781D03*
X649936Y574185D03*
X660062Y672761D03*
X654676Y674806D03*
X654005Y1548999D03*
X670000Y465844D03*
X672856Y1486682D03*
Y1500082D03*
X719195Y172873D03*
Y177865D03*
X714203Y172873D03*
Y177865D03*
X719195Y196373D03*
X714203D03*
X719195Y184873D03*
Y189865D03*
X714203Y184873D03*
Y189865D03*
Y208207D03*
X719195D03*
Y201365D03*
X714203D03*
Y213199D03*
X719195D03*
X744911Y166887D03*
X749261Y1628208D03*
X754286Y266319D03*
X754291Y269322D03*
X756692Y278942D03*
X765285Y276374D03*
X761510Y1638434D03*
X762030Y1668583D03*
X755408Y1672381D03*
X757557Y1684444D03*
X773457Y249792D03*
X774485Y286879D03*
X791341Y264848D03*
X784261Y1482049D03*
Y1534963D03*
X784277Y1528191D03*
X808469Y1356745D03*
Y1359245D03*
X811272Y1382752D03*
X811767Y1388154D03*
X836163Y279355D03*
X856397Y344669D03*
X865132Y333317D03*
X860152D03*
X861377Y344669D03*
X869406Y753541D03*
X874617Y1084657D03*
X877817D03*
Y1088057D03*
X874617D03*
X881217Y1084657D03*
Y1088057D03*
X874617Y1100957D03*
X877817D03*
Y1097557D03*
X874617D03*
X881217Y1100957D03*
Y1097557D03*
X889057Y1053133D03*
X897754Y1156119D03*
X916268Y277859D03*
X928224Y264072D03*
X942763Y272340D03*
X944820Y1156119D03*
X957421Y157699D03*
X960421D03*
X962243Y179917D03*
X947748Y1146553D03*
X964743Y179917D03*
X963985Y177154D03*
X965520Y1567570D03*
X962520D03*
X968520D03*
X965520Y1582570D03*
X962520D03*
Y1579570D03*
X965520D03*
Y1576570D03*
X962520D03*
X965520Y1573570D03*
X962520D03*
Y1570570D03*
X965520D03*
X968520Y1582570D03*
Y1579570D03*
Y1576570D03*
Y1573570D03*
Y1570570D03*
X965520Y1588570D03*
X962520D03*
Y1585570D03*
X965520D03*
X968520Y1588570D03*
Y1585570D03*
X991553Y216809D03*
X988460Y354725D03*
X992233Y373679D03*
X986356Y1087508D03*
X983156D03*
Y1084108D03*
X986356D03*
X989556Y1087508D03*
Y1084108D03*
X986356Y1097008D03*
X983156D03*
Y1100408D03*
X986356D03*
X989556Y1097008D03*
Y1100408D03*
X1002736Y157943D03*
X999736D03*
X993306Y174953D03*
X993206Y178053D03*
X1006436Y176843D03*
X999916Y184548D03*
X996416D03*
X992506Y184553D03*
X993460Y354725D03*
X998460D03*
X997488Y370287D03*
X994160Y1567710D03*
X997160D03*
X1000160D03*
X994160Y1582710D03*
X997160D03*
Y1579710D03*
X994160D03*
X997160Y1570710D03*
X994160D03*
Y1573710D03*
X997160D03*
X994160Y1576710D03*
X997160D03*
X1000160Y1582710D03*
Y1579710D03*
Y1570710D03*
Y1573710D03*
Y1576710D03*
X994160Y1588710D03*
X997160D03*
Y1585710D03*
X994160D03*
X1000160Y1588710D03*
Y1585710D03*
X1021899Y61590D03*
Y127590D03*
X1011358Y195324D03*
X1008068Y198387D03*
X1019936Y207333D03*
Y210463D03*
X1013306Y528942D03*
X1032354Y538201D03*
X1022686D03*
X1027520Y552724D03*
X1025750Y1567710D03*
X1031750D03*
X1028750D03*
X1025750Y1576710D03*
Y1573710D03*
Y1570710D03*
Y1579710D03*
Y1582710D03*
X1028750Y1576710D03*
Y1573710D03*
Y1570710D03*
Y1579710D03*
Y1582710D03*
X1031750Y1576710D03*
Y1573710D03*
Y1570710D03*
Y1579710D03*
Y1582710D03*
X1025750Y1585710D03*
Y1588710D03*
X1028750Y1585710D03*
Y1588710D03*
X1031750Y1585710D03*
Y1588710D03*
X1059055Y492537D03*
X1057219Y1567883D03*
X1060219D03*
X1063219D03*
X1066219D03*
X1057219Y1576883D03*
Y1573883D03*
Y1570883D03*
Y1579883D03*
Y1582883D03*
X1060219Y1576883D03*
Y1573883D03*
Y1570883D03*
Y1579883D03*
Y1582883D03*
X1063219Y1576883D03*
Y1573883D03*
Y1570883D03*
X1066219Y1576883D03*
Y1573883D03*
Y1570883D03*
Y1579883D03*
X1063219D03*
Y1582883D03*
X1066219D03*
X1057219Y1585883D03*
Y1588883D03*
X1060219Y1585883D03*
Y1588883D03*
X1066219Y1585883D03*
X1063219D03*
Y1588883D03*
X1066219D03*
X1094399Y1568043D03*
X1091399D03*
X1085399D03*
X1088399D03*
X1091399Y1580043D03*
X1094399D03*
Y1571043D03*
Y1574043D03*
Y1577043D03*
X1091399Y1571043D03*
Y1574043D03*
Y1577043D03*
X1088399Y1580043D03*
X1085399D03*
X1088399Y1571043D03*
X1085399D03*
Y1574043D03*
X1088399D03*
X1085399Y1577043D03*
X1088399D03*
X1094399Y1583043D03*
X1091399D03*
X1085399D03*
X1088399D03*
X1094399Y1589043D03*
X1091399D03*
Y1586043D03*
X1094399D03*
X1085399Y1589043D03*
X1088399D03*
Y1586043D03*
X1085399D03*
X1092030Y1715841D03*
Y1725991D03*
X1097399Y1568043D03*
Y1580043D03*
Y1571043D03*
Y1574043D03*
Y1577043D03*
Y1583043D03*
Y1589043D03*
Y1586043D03*
X1170986Y1519190D03*
X1168386Y1517280D03*
Y1512500D03*
Y1534300D03*
Y1539080D03*
X1170986Y1540990D03*
X1173586Y1517280D03*
Y1512500D03*
Y1534300D03*
Y1539080D03*
X1181361Y1543800D03*
Y1547420D03*
Y1551040D03*
X1172603Y1554561D03*
X1188472Y80165D03*
X1197980Y1688270D03*
X1213072Y1682899D03*
X1207770Y1717011D03*
Y1731011D03*
X1226094Y297066D03*
X1288494Y1519682D03*
Y1533082D03*
X1304705Y79807D03*
X1303266Y533713D03*
Y530413D03*
X1300200Y590600D03*
X1299048Y1519190D03*
X1296448Y1517280D03*
Y1512500D03*
X1301648Y1517280D03*
Y1512500D03*
X1296448Y1534300D03*
X1301648D03*
X1296448Y1539080D03*
X1301648D03*
X1299048Y1540990D03*
X1309185Y74748D03*
X1316266Y564514D03*
X1317266Y589522D03*
X1318300Y640000D03*
Y643000D03*
Y649000D03*
Y646000D03*
X1318363Y1411404D03*
X1312700Y1579596D03*
X1319349Y1585567D03*
X1330820Y525165D03*
X1330758Y521749D03*
X1330820Y518265D03*
X1330658Y538749D03*
X1330758Y528649D03*
X1330773Y531776D03*
X1330758Y535449D03*
X1329673Y552509D03*
X1332673D03*
X1326673Y544909D03*
X1329673Y545909D03*
Y549309D03*
X1330658Y542949D03*
X1332673Y545909D03*
Y549309D03*
X1329673Y558709D03*
Y555709D03*
X1332673D03*
X1325366Y589522D03*
X1321300Y643000D03*
Y640000D03*
Y649000D03*
Y646000D03*
X1326433Y1214334D03*
X1335260Y236594D03*
Y246594D03*
Y241594D03*
Y251594D03*
X1348611Y1212963D03*
Y1218463D03*
X1364239Y1207949D03*
X1391460Y1032205D03*
X1388918Y1687878D03*
X1382045Y1712038D03*
Y1708038D03*
X1384604Y1728318D03*
X1393179Y1733118D03*
X1404917Y109037D03*
X1395060Y1009764D03*
Y1006024D03*
Y1013504D03*
Y1020985D03*
Y1024725D03*
Y1028465D03*
Y1017244D03*
X1397955Y1582178D03*
X1405058Y1639607D03*
X1417301Y1055140D03*
X1416556Y1519682D03*
Y1533082D03*
X1418740Y1622902D03*
X1427973Y60409D03*
X1438507Y1006024D03*
Y1009764D03*
Y1013504D03*
Y1024725D03*
Y1020985D03*
Y1017244D03*
Y1028465D03*
Y1032205D03*
X1435160Y1519190D03*
X1432560Y1517280D03*
Y1512500D03*
X1437760Y1517280D03*
Y1512500D03*
X1432560Y1534300D03*
X1437760D03*
X1432560Y1539080D03*
X1437760D03*
X1435160Y1540990D03*
X1433979Y1655655D03*
X1441141Y53699D03*
X1448505Y1579725D03*
X1455461Y1585567D03*
X1528993Y4115D03*
Y26115D03*
X1534067Y1582178D03*
X1552668Y1519682D03*
Y1533082D03*
X1568176Y568423D03*
X1570676D03*
X1565676D03*
X1561376Y572258D03*
X1566010Y673210D03*
X1562730Y675180D03*
X1563222Y1519190D03*
X1560622Y1517280D03*
Y1512500D03*
X1565822Y1517280D03*
Y1512500D03*
X1560622Y1534300D03*
X1565822D03*
X1560622Y1539080D03*
X1565822D03*
X1563222Y1540990D03*
X1586291Y306746D03*
X1584160Y558973D03*
X1576653Y1579333D03*
X1583523Y1585567D03*
X1606535Y553297D03*
X1607369Y561330D03*
X1631889Y521480D03*
X1618884Y533388D03*
X1632798Y544564D03*
X1622391Y564169D03*
X1627242Y1436148D03*
X1627181Y1448016D03*
X1636929Y524690D03*
Y528190D03*
Y531690D03*
Y535190D03*
Y538690D03*
X1639868Y542444D03*
X1636783Y542604D03*
X1635798Y545564D03*
X1638798D03*
Y548964D03*
Y552164D03*
X1635798D03*
Y548964D03*
Y555364D03*
X1638798D03*
X1635798Y558364D03*
X1648029Y1718759D03*
Y1733909D03*
X1652525Y141762D03*
X1662129Y1582178D03*
X1673100Y126762D03*
X1676971Y1668582D03*
X1686154Y434160D03*
X1685298Y1451231D03*
X1680730Y1519682D03*
Y1533082D03*
X1688243Y1663802D03*
X1682724Y1717701D03*
X1704444Y407045D03*
X1707444D03*
X1697914Y427155D03*
X1698014Y424055D03*
X1701124Y433650D03*
X1697214Y433655D03*
X1704624Y433650D03*
X1704822Y1694243D03*
X1702985Y1700328D03*
X1711144Y425945D03*
X1722149Y1715265D03*
X1719149Y1703190D03*
X1722149Y1730415D03*
X1724263Y1681465D03*
X1752250Y303850D03*
X1749329Y1662956D03*
X1743329Y1668956D03*
X1743153Y1662956D03*
X1749329Y1674956D03*
X1743329D03*
X1754850Y303930D03*
X1755329Y1668956D03*
Y1662956D03*
Y1674956D03*
X1763463Y1691465D03*
X1758963Y1691565D03*
X1787390Y161834D03*
X1800040Y164393D03*
X1797719Y186610D03*
X1811668Y218900D03*
X1811606Y222513D03*
X1808429Y218837D03*
X1811606Y226438D03*
X1808367Y222450D03*
X1810479Y211850D03*
X1810509Y214660D03*
X1808260Y213232D03*
X1808367Y226375D03*
X1825111Y164393D03*
X1813079Y211850D03*
X1813109Y214660D03*
G54D17*
X18960Y1598181D03*
X440029Y240381D03*
X434420Y239930D03*
X934302Y578318D03*
X1769420Y19506D03*
X1777420D03*
Y24506D03*
G54D19*
X35852Y673010D03*
Y675510D03*
Y697322D03*
Y694822D03*
Y705728D03*
X50138Y425810D03*
X45182D03*
X45022Y449106D03*
X50002D03*
X48626Y552365D03*
X50880Y1412563D03*
X51358Y1647717D03*
Y1650217D03*
X52052Y1684027D03*
X67257Y69340D03*
X62930Y282866D03*
Y312866D03*
X62833Y409597D03*
X62808Y418675D03*
X65380Y427810D03*
X60393D03*
X58349Y1403331D03*
X54449Y1641722D03*
X61415Y1661695D03*
X61374Y1669931D03*
X70127Y1687362D03*
X73015Y28406D03*
X80101D03*
X73015Y40020D03*
X80101D03*
X78253Y75343D03*
X74773Y790297D03*
Y800336D03*
Y827108D03*
Y837147D03*
Y863919D03*
Y873958D03*
Y900730D03*
Y910769D03*
Y937541D03*
Y947580D03*
Y1084785D03*
Y1094824D03*
Y1121596D03*
Y1131635D03*
Y1158407D03*
Y1168446D03*
Y1195218D03*
Y1205257D03*
Y1232029D03*
Y1242068D03*
X71511Y1444379D03*
X69486Y1661828D03*
X69589Y1669878D03*
X78127Y1687362D03*
X74127D03*
X94274Y28406D03*
X87188D03*
Y40020D03*
X94274D03*
X89257Y69340D03*
X90150Y1314560D03*
X86127Y1687362D03*
X92192Y1713741D03*
X92596Y1737117D03*
X108448Y28406D03*
X101361D03*
Y40020D03*
X108448D03*
X100257Y75340D03*
X111257Y69340D03*
X104474Y790297D03*
Y800336D03*
Y827108D03*
Y837147D03*
Y863919D03*
Y873958D03*
Y900730D03*
Y910769D03*
Y937541D03*
Y947580D03*
Y1084785D03*
Y1094824D03*
Y1121596D03*
Y1131635D03*
Y1158407D03*
Y1168446D03*
Y1195218D03*
Y1205257D03*
Y1232029D03*
Y1242068D03*
X112355Y1426064D03*
Y1433564D03*
Y1441064D03*
X110144Y1597831D03*
X110996Y1592018D03*
X122621Y28406D03*
X115534D03*
Y40020D03*
X122621D03*
X122257Y75340D03*
X119855Y1426064D03*
X127355Y1433564D03*
Y1426064D03*
X119855Y1441064D03*
X127355D03*
X127374Y1572749D03*
X127392Y1575524D03*
X125768Y1568744D03*
X127246Y1585801D03*
X127264Y1588576D03*
X113496Y1592018D03*
X116353Y1646612D03*
X120353D03*
X124353D03*
X123278Y1658587D03*
X119353Y1695941D03*
X115353D03*
X125107Y1702666D03*
X124461Y1726116D03*
X114596Y1737117D03*
X129708Y28406D03*
Y40020D03*
X133257Y69343D03*
X141642Y491434D03*
X134174Y790297D03*
Y800336D03*
Y837147D03*
Y827108D03*
Y863919D03*
Y873958D03*
Y900730D03*
Y910769D03*
Y937541D03*
Y947580D03*
Y1084785D03*
Y1094824D03*
Y1121596D03*
Y1131635D03*
Y1158407D03*
Y1168446D03*
Y1195218D03*
Y1205257D03*
Y1232029D03*
Y1242068D03*
X128617Y1561022D03*
X129892Y1575524D03*
X129874Y1572749D03*
X128268Y1568744D03*
X129764Y1588576D03*
X129746Y1585801D03*
X128353Y1646612D03*
X140353D03*
X136048Y1666851D03*
X133548Y1677351D03*
X131353Y1696062D03*
X135353D03*
X139353D03*
X136596Y1737117D03*
X151400Y28406D03*
Y40020D03*
X144257Y75340D03*
X155253Y69343D03*
X148353Y1646612D03*
X144353D03*
X155328Y1670087D03*
X146928Y1685087D03*
X143353Y1696062D03*
X158487Y28406D03*
X165574D03*
X158487Y40020D03*
X165574D03*
X167461Y75340D03*
X163875Y790297D03*
Y800336D03*
Y837147D03*
Y827108D03*
Y863919D03*
Y873958D03*
Y900730D03*
Y910769D03*
Y937541D03*
Y947580D03*
Y1084785D03*
Y1094824D03*
Y1121596D03*
Y1131635D03*
Y1158407D03*
Y1168446D03*
Y1195218D03*
Y1205257D03*
Y1232029D03*
Y1242068D03*
X163421Y1425171D03*
Y1427671D03*
Y1430171D03*
Y1432671D03*
X158596Y1737117D03*
X172660Y28406D03*
X179747D03*
X172660Y40020D03*
X179747D03*
X178461Y69340D03*
X173960Y400560D03*
X172721Y1425171D03*
Y1430171D03*
Y1427671D03*
Y1432671D03*
X175351Y1462595D03*
X182051Y1452895D03*
X181760Y1731351D03*
X180596Y1737117D03*
X195534Y28406D03*
Y40020D03*
X189457Y75343D03*
X200461Y69340D03*
X193576Y790297D03*
Y800336D03*
Y827108D03*
Y837147D03*
Y863919D03*
Y873958D03*
Y900730D03*
Y910769D03*
Y937541D03*
Y947580D03*
Y1084785D03*
Y1094824D03*
Y1121596D03*
Y1131635D03*
Y1158407D03*
Y1168446D03*
Y1205257D03*
Y1195218D03*
Y1232029D03*
Y1242068D03*
X202151Y1462595D03*
X195451Y1472295D03*
X202621Y28406D03*
X216794D03*
X209708D03*
X202621Y40020D03*
X209708D03*
X216794D03*
X211595Y75340D03*
X208851Y1452895D03*
X202596Y1737117D03*
X223881Y28406D03*
X230967D03*
X223881Y40020D03*
X230967D03*
X222591Y69343D03*
X223277Y790297D03*
Y800336D03*
Y837147D03*
Y827108D03*
Y863919D03*
Y873958D03*
Y900730D03*
Y910769D03*
Y937541D03*
Y947580D03*
Y1084785D03*
Y1094824D03*
Y1121596D03*
Y1131635D03*
Y1158407D03*
Y1168446D03*
Y1205257D03*
Y1195218D03*
Y1232029D03*
Y1242068D03*
X228951Y1462595D03*
X222251Y1472295D03*
X224596Y1737117D03*
X233595Y75340D03*
X242215Y151788D03*
X234727Y584030D03*
Y571211D03*
X245815Y672746D03*
X244565Y677846D03*
Y680446D03*
Y675246D03*
X242543Y691115D03*
X239443Y691015D03*
X239843Y709715D03*
X235651Y1452895D03*
X252996Y28365D03*
X256496D03*
X249496D03*
X259996D03*
X252195Y144320D03*
X259475Y657245D03*
X259426Y644830D03*
X259475Y662845D03*
X250312Y670080D03*
Y667180D03*
X250835Y672692D03*
X253279Y672708D03*
X258379Y666644D03*
Y669601D03*
Y672708D03*
X255779D03*
X260979Y666644D03*
Y669601D03*
Y672708D03*
X247165Y677846D03*
Y680446D03*
Y675246D03*
X254448Y692050D03*
X255751Y1462595D03*
X249051Y1472295D03*
X266601Y586578D03*
X271571Y644796D03*
X264335Y657245D03*
X261905D03*
Y662845D03*
X264335D03*
X263579Y669601D03*
X266179D03*
Y672708D03*
X263579D03*
X270857Y668515D03*
X263839Y692049D03*
X275851Y1452895D03*
X262451D03*
X266596Y1737117D03*
X278979Y28406D03*
X286066D03*
X279273Y99186D03*
X289553Y121806D03*
X291109Y700885D03*
X283062Y700979D03*
X279895Y709487D03*
X283565Y706933D03*
X286009Y706949D03*
X278545Y706987D03*
X279895Y712087D03*
Y714687D03*
X291109Y703842D03*
Y706949D03*
X288509D03*
X277295Y709487D03*
Y712087D03*
Y714687D03*
X283062Y703936D03*
X277055Y722649D03*
X279171Y724988D03*
X281992Y1342705D03*
X292705Y580275D03*
X292156Y679071D03*
X304301Y679037D03*
X292205Y691486D03*
X297065D03*
X294635D03*
X293709Y700885D03*
X297065Y697086D03*
X303657Y702815D03*
X292205Y697086D03*
X294635D03*
X293709Y703842D03*
Y706949D03*
X298909Y703842D03*
Y706949D03*
X296309Y703842D03*
Y706949D03*
X303413Y1462595D03*
X315912Y721039D03*
Y723996D03*
X321279Y727099D03*
X312665Y729637D03*
Y732237D03*
X310065Y729637D03*
Y732237D03*
X316335Y727083D03*
X311315Y727137D03*
X318779Y727099D03*
X313255Y746279D03*
X312665Y734837D03*
X310065D03*
X310113Y1452895D03*
X312596Y1737117D03*
X328966Y548030D03*
X324926Y699221D03*
X329835Y711636D03*
X324975D03*
X329835Y717236D03*
X327405Y711636D03*
X324975Y717236D03*
X327405D03*
X326479Y721035D03*
X323879D03*
Y727099D03*
X326479D03*
X329079D03*
X331679D03*
X323879Y723992D03*
X326479D03*
X329079D03*
X331679D03*
X330213Y1462595D03*
X323513Y1472295D03*
X334596Y1737117D03*
X350817Y558248D03*
X343182Y586415D03*
Y591335D03*
X348449Y720827D03*
Y723784D03*
X345725Y729369D03*
X343125D03*
X345725Y731969D03*
X343125D03*
X344375Y726869D03*
X349395Y726815D03*
X336457Y722815D03*
X339825Y746269D03*
X342425D03*
X349625D03*
X345725Y734569D03*
X343125D03*
X336913Y1452895D03*
X350313Y1472295D03*
X352418Y225329D03*
Y222329D03*
X355733Y275059D03*
X357986Y698953D03*
X362895Y716968D03*
X360465Y711368D03*
X362895D03*
X358035D03*
Y716968D03*
X360465D03*
X359539Y720767D03*
X356939D03*
X351839Y726831D03*
X354339D03*
X356939D03*
X362139D03*
X359539D03*
X364739D03*
X356939Y723724D03*
X362139D03*
X359539D03*
X364739D03*
X352225Y746269D03*
X360025D03*
X362625D03*
X352943Y1214510D03*
X363713Y1452895D03*
X357013Y1462595D03*
X356596Y1737117D03*
X379023Y225149D03*
X371318Y218629D03*
X379023Y228649D03*
X379028Y232559D03*
X369428Y231759D03*
X372528Y231859D03*
X369171Y562380D03*
X376671D03*
X369100Y577400D03*
X369171Y569880D03*
X376600Y577400D03*
X376165Y729437D03*
X378765D03*
X376165Y732037D03*
X378765D03*
X377415Y726937D03*
X369557Y722615D03*
X373425Y746169D03*
X370825D03*
X376165Y734637D03*
X378765D03*
X367836Y1209506D03*
X377190Y1387697D03*
X377113Y1472295D03*
X393287Y-9234D03*
X391635Y161091D03*
X384259Y562426D03*
X384301Y577446D03*
X385443Y597279D03*
X391026Y699021D03*
X395935Y717036D03*
Y711436D03*
X393505D03*
X391075D03*
Y717036D03*
X393505D03*
X392579Y720835D03*
X389979D03*
X381802Y720789D03*
Y723746D03*
X387379Y726899D03*
X384879D03*
X389979D03*
Y723792D03*
X382435Y726883D03*
X392579Y726899D03*
X395179D03*
X392579Y723792D03*
X395179D03*
X389981Y1015474D03*
Y1022560D03*
Y1019017D03*
X383813Y1462595D03*
X390513Y1452895D03*
X406243Y100076D03*
X402184Y507101D03*
X403133Y565415D03*
X403157Y569415D03*
X410415Y709137D03*
X409165Y711637D03*
Y714237D03*
Y716837D03*
X397779Y726899D03*
Y723792D03*
X402457Y722615D03*
X397461Y1015474D03*
X404941D03*
X397461Y1022560D03*
X404941Y1019017D03*
Y1022560D03*
X397461Y1019017D03*
X403913Y1452895D03*
X417617Y79073D03*
X423376Y96664D03*
X411952Y132751D03*
Y123051D03*
X422936Y228147D03*
Y232793D03*
X420288Y244184D03*
X415984Y507024D03*
X424026Y681221D03*
X424075Y693636D03*
X425579Y703035D03*
X422979D03*
X424075Y699236D03*
X414682Y703139D03*
X411765Y711637D03*
Y714237D03*
Y716837D03*
X415435Y709083D03*
X417879Y709099D03*
X425579D03*
X422979D03*
X420379D03*
X425579Y705992D03*
X422979D03*
X414682Y706096D03*
X423811Y1009400D03*
Y1028831D03*
X417098Y1533764D03*
Y1531264D03*
X422596Y1737117D03*
X429685Y88657D03*
X436090Y116007D03*
Y124007D03*
Y132007D03*
X440591Y684518D03*
X436130Y683281D03*
X426505Y693636D03*
X428935D03*
Y699236D03*
X426505D03*
X430779Y709099D03*
Y705992D03*
X428179Y709099D03*
Y705992D03*
X435457Y704915D03*
X439411Y733527D03*
X436811D03*
X439411Y736147D03*
X436811D03*
X436411Y738717D03*
X439011D03*
X436411Y743917D03*
X439011D03*
X436411Y741317D03*
X439011D03*
X431291Y1009400D03*
X438316Y1014745D03*
X427551Y1009400D03*
X435031D03*
X438771D03*
X428473Y1014745D03*
X438771Y1028831D03*
X438316Y1023013D03*
X427551Y1028831D03*
X435031D03*
X438316Y1018879D03*
X428473D03*
Y1023013D03*
X431291Y1028831D03*
X427251Y1291747D03*
X439524Y1462595D03*
X448090Y116007D03*
X444090Y132007D03*
X452480Y273420D03*
X441320Y298170D03*
X452565Y652837D03*
X455379Y678435D03*
X450279Y684499D03*
X455379D03*
X452779D03*
X455379Y681392D03*
X444165Y687037D03*
X441565D03*
X443235Y684637D03*
X447835Y684483D03*
X447162Y678409D03*
Y681366D03*
X444325Y702449D03*
X441725D03*
X444165Y689637D03*
Y692237D03*
X441565D03*
Y689637D03*
X446591Y716837D03*
X443991D03*
X446591Y719437D03*
X443991D03*
X441959Y993766D03*
Y997766D03*
X442034Y989766D03*
X442511Y1009400D03*
X449992D03*
X446252D03*
X453732D03*
X441959Y1001766D03*
X447174Y1014745D03*
X446252Y1028831D03*
X453732D03*
X449992D03*
X447174Y1023013D03*
X442511Y1028831D03*
X447174Y1018879D03*
X446224Y1452895D03*
X444596Y1737117D03*
X463402Y229970D03*
X457731Y237588D03*
X463653Y237390D03*
X462703Y242342D03*
X467644Y353417D03*
X469046Y657062D03*
X456426Y656621D03*
X458905Y669036D03*
X456475D03*
X461335D03*
X457979Y678435D03*
X460579Y684499D03*
X457979D03*
X460579Y681392D03*
X457979D03*
X467957Y680315D03*
X463179Y684499D03*
Y681392D03*
X461335Y674636D03*
X456475D03*
X458905D03*
X457472Y1009400D03*
X457410Y1014745D03*
Y1018879D03*
Y1023013D03*
X457472Y1028831D03*
X466324Y1462595D03*
X459624Y1472295D03*
X466596Y1737117D03*
X486682Y197516D03*
X483800Y270440D03*
X475415Y658037D03*
X482879Y657999D03*
X480435Y657983D03*
X485379Y657999D03*
X479822Y651989D03*
Y654946D03*
X476765Y660537D03*
X474165D03*
X476765Y663137D03*
X474165D03*
X476765Y665737D03*
X474165D03*
X473024Y1452895D03*
X495232Y189516D03*
X486600Y200800D03*
X495232Y197516D03*
X491635Y212577D03*
X487541Y226527D03*
X488076Y350420D03*
X501171Y630087D03*
X493935Y642536D03*
X489075D03*
X491505D03*
X489026Y630121D03*
X493935Y648136D03*
X487979Y651935D03*
X490579D03*
X493179Y654892D03*
Y657999D03*
X487979Y654892D03*
X490579D03*
Y657999D03*
X487979D03*
X495779Y654892D03*
Y657999D03*
X489075Y648136D03*
X491505D03*
X499824Y1452895D03*
X493124Y1462595D03*
X486424Y1472295D03*
X488596Y1737117D03*
X510810Y49193D03*
X510065Y626437D03*
X508715Y623937D03*
X507465Y626437D03*
X513735Y623883D03*
X513012Y620706D03*
Y617749D03*
X510065Y629037D03*
X507465D03*
X510065Y631637D03*
X507465D03*
X514771Y643138D03*
X500457Y653715D03*
X513224Y1472295D03*
X517915Y42257D03*
X525001D03*
X517896Y49193D03*
X524763Y49189D03*
X522418Y137171D03*
X526418D03*
X517973Y211998D03*
X522326Y596021D03*
X524805Y608436D03*
X522375D03*
X527235D03*
X526479Y620792D03*
Y623899D03*
X523879Y620792D03*
X521279D03*
X523879Y623899D03*
X521279D03*
X518679D03*
X516179D03*
X529079Y620792D03*
Y623899D03*
X523879Y617835D03*
X521279D03*
X527235Y614036D03*
X522375D03*
X524805D03*
X521771Y643138D03*
X528771D03*
X519924Y1462595D03*
X526624Y1452895D03*
X532070Y49193D03*
X539156D03*
X530418Y137171D03*
X541013Y222441D03*
X534471Y595987D03*
X533857Y619615D03*
X534271Y643138D03*
X540024Y1452895D03*
X532596Y1737117D03*
X557091Y114382D03*
X550505D03*
X553100Y227700D03*
X551200Y377650D03*
X551171Y1167678D03*
X554596Y1737117D03*
X564431Y45132D03*
X562475Y242721D03*
X571271Y1259488D03*
X567586Y1462595D03*
X574286Y1452895D03*
X578621Y45112D03*
X585296Y222954D03*
X586000Y808862D03*
X578830Y1218588D03*
X585501Y1229536D03*
X587686Y1472295D03*
X576596Y1737117D03*
X595682Y44842D03*
X603064Y44523D03*
X599284Y32866D03*
X593920Y49193D03*
X600793Y193185D03*
X596661Y188775D03*
X590300Y190660D03*
X595563Y239128D03*
X603283Y419744D03*
X597071Y799268D03*
X592761Y1220688D03*
X594386Y1462595D03*
X601086Y1452895D03*
X598596Y1737117D03*
X618427Y43432D03*
X615180Y49193D03*
X618600Y160750D03*
X613207Y182229D03*
X615464Y347522D03*
X607871Y359262D03*
X613761Y790418D03*
X605771Y1267098D03*
X614486Y1472295D03*
X624937Y44019D03*
X620390Y36794D03*
X630900Y118920D03*
X632695Y1366157D03*
Y1372257D03*
Y1378257D03*
X627886Y1452895D03*
X621186Y1462595D03*
X620596Y1737117D03*
X648487Y44106D03*
X638695Y1366157D03*
X644795D03*
X643395Y1372857D03*
X638695Y1378257D03*
X644795D03*
X647986Y1462595D03*
X641286Y1472295D03*
X642596Y1737117D03*
X654590Y49193D03*
X661676D03*
X652804Y790297D03*
Y800336D03*
Y837147D03*
Y827108D03*
Y863919D03*
Y873958D03*
Y900730D03*
Y910769D03*
Y937541D03*
Y947580D03*
Y1084785D03*
Y1094824D03*
Y1121596D03*
Y1131635D03*
Y1158407D03*
Y1168446D03*
Y1205257D03*
Y1195218D03*
Y1232029D03*
Y1242068D03*
X661685Y1367283D03*
X654686Y1452895D03*
X662153Y1727718D03*
X675849Y49193D03*
X668763D03*
X668086Y1452895D03*
X664596Y1737117D03*
X682505Y790297D03*
Y800336D03*
Y837147D03*
Y827108D03*
Y863919D03*
Y873958D03*
Y900730D03*
Y910769D03*
Y937541D03*
Y947580D03*
Y1084785D03*
Y1094824D03*
Y1121596D03*
Y1131635D03*
Y1158407D03*
Y1168446D03*
Y1205257D03*
Y1195218D03*
Y1232029D03*
Y1242068D03*
X688540Y1455140D03*
X697400Y345761D03*
X697300Y1454140D03*
X722581Y49182D03*
X713420Y102060D03*
X712206Y790297D03*
Y800336D03*
Y827108D03*
Y837147D03*
Y863919D03*
Y873958D03*
Y900730D03*
Y910769D03*
Y937541D03*
Y947580D03*
Y1084785D03*
Y1094824D03*
Y1121596D03*
Y1131635D03*
Y1158407D03*
Y1168446D03*
Y1195218D03*
Y1205257D03*
Y1232029D03*
Y1242068D03*
X731743Y-30584D03*
X734996Y-30570D03*
X731758Y-28069D03*
X735011Y-28055D03*
X728718Y-29264D03*
X735041Y-23025D03*
X735026Y-25540D03*
X731555Y83685D03*
X737009Y83169D03*
X724134Y141288D03*
X728500Y533862D03*
X736500D03*
X732500D03*
X738260Y553625D03*
X747637Y534874D03*
X740638Y549900D03*
X741907Y790297D03*
Y800336D03*
Y827108D03*
Y837147D03*
Y863919D03*
Y873958D03*
Y900730D03*
Y910769D03*
Y937541D03*
Y947580D03*
Y1084785D03*
Y1094824D03*
Y1121596D03*
Y1131635D03*
Y1158407D03*
Y1168446D03*
Y1195218D03*
Y1205257D03*
Y1232029D03*
Y1242068D03*
X751521Y1659158D03*
X752596Y1737117D03*
X762199Y126684D03*
Y129684D03*
X758111Y172636D03*
X762300Y188910D03*
X764500Y534424D03*
X760500Y534352D03*
X781242Y489574D03*
X771608Y790297D03*
Y800336D03*
Y837147D03*
Y827108D03*
Y863919D03*
Y873958D03*
Y900730D03*
Y910769D03*
Y937541D03*
Y947580D03*
Y1084785D03*
Y1094824D03*
Y1121596D03*
Y1131635D03*
Y1158407D03*
Y1168446D03*
Y1195218D03*
Y1205257D03*
Y1232029D03*
Y1242068D03*
X778030Y1310259D03*
X780530D03*
X773974Y1731920D03*
X796333Y439344D03*
X786030Y1310259D03*
X794030D03*
X796530D03*
X788530D03*
X791823Y1527404D03*
X795926Y1731918D03*
X807451Y763765D03*
X801308Y790297D03*
Y800336D03*
Y837147D03*
Y827108D03*
Y863919D03*
Y873958D03*
Y900730D03*
Y910769D03*
Y937541D03*
Y947580D03*
Y1084785D03*
Y1094824D03*
Y1121596D03*
Y1131635D03*
Y1158407D03*
Y1168446D03*
Y1195218D03*
Y1205257D03*
Y1232029D03*
Y1242068D03*
X802030Y1310259D03*
X804530D03*
X807601Y1307191D03*
X810246Y1351988D03*
X817974Y1731920D03*
X839974D03*
X844766Y-15374D03*
Y-5374D03*
Y24626D03*
X849711Y212062D03*
X845221Y216532D03*
X854707Y229878D03*
X852207D03*
X874295Y163862D03*
X863488Y176332D03*
X861974Y1731920D03*
X883974D03*
X898000Y1112336D03*
Y1109736D03*
Y1116544D03*
Y1119144D03*
Y1130160D03*
Y1132760D03*
Y1123352D03*
Y1125952D03*
X916880Y1138969D03*
X906473Y1158574D03*
X903980Y1268420D03*
X904024Y1272692D03*
X903947Y1276968D03*
X903899Y1281203D03*
X903945Y1285420D03*
X903923Y1289630D03*
X903651Y1293853D03*
X903690Y1298027D03*
X905974Y1731920D03*
X921477Y1134647D03*
X925525Y1135172D03*
X919880Y1146569D03*
Y1139969D03*
Y1143369D03*
Y1149769D03*
X922880Y1146569D03*
Y1139969D03*
Y1143369D03*
Y1149769D03*
X919077Y1136521D03*
X923125Y1137046D03*
X919880Y1152769D03*
X928751Y1266347D03*
X928901Y1270408D03*
X928852Y1274591D03*
X928979Y1278713D03*
X928827Y1283048D03*
X928928Y1287193D03*
X928906Y1291676D03*
X928983Y1295957D03*
X927974Y1731920D03*
X935497Y195925D03*
Y210098D03*
Y203012D03*
Y224272D03*
Y217185D03*
Y231358D03*
X935783Y634051D03*
X941000Y1110557D03*
Y1107957D03*
Y1117557D03*
Y1114957D03*
Y1124557D03*
Y1121957D03*
Y1131557D03*
Y1128957D03*
X953498Y1158574D03*
X949974Y1731920D03*
X967315Y1135550D03*
X972109Y1135149D03*
X966905Y1146569D03*
X969905D03*
X966905Y1139969D03*
Y1143369D03*
X969905Y1139969D03*
Y1143369D03*
X966905Y1149769D03*
X969905D03*
X963012Y1139511D03*
X964915Y1137424D03*
X969709Y1137023D03*
X966905Y1152769D03*
X968594Y1288193D03*
X971974Y1731920D03*
X991031Y528574D03*
X998056Y518214D03*
Y523874D03*
X999031Y528574D03*
X999894Y1267126D03*
X993974Y1731920D03*
X1021220Y243638D03*
X1012220D03*
X1007669Y268884D03*
Y258222D03*
X1007587Y767480D03*
Y769980D03*
Y780880D03*
Y778380D03*
Y789484D03*
Y791984D03*
X1010894Y1271743D03*
X1010865Y1275768D03*
X1010944Y1279751D03*
X1010650Y1310500D03*
X1015974Y1731920D03*
X1025493Y758819D03*
X1044012Y268659D03*
X1051495Y265133D03*
X1040097Y529508D03*
X1050915Y790296D03*
Y800335D03*
Y827107D03*
Y837146D03*
Y863918D03*
Y873957D03*
Y910768D03*
Y900729D03*
Y937540D03*
Y947579D03*
Y1084784D03*
Y1094823D03*
Y1131634D03*
Y1121595D03*
Y1158406D03*
Y1168445D03*
Y1205256D03*
Y1195217D03*
Y1232028D03*
Y1242067D03*
X1037974Y1731920D03*
X1054355Y258698D03*
X1065552Y271441D03*
X1056517Y512787D03*
X1061837Y519703D03*
X1060721Y1313954D03*
X1061974Y1731920D03*
X1080616Y790296D03*
Y800335D03*
Y827107D03*
Y837146D03*
Y863918D03*
Y873957D03*
Y910768D03*
Y900729D03*
Y937540D03*
Y947579D03*
Y1084784D03*
Y1094823D03*
Y1131634D03*
Y1121595D03*
Y1158406D03*
Y1168445D03*
Y1205256D03*
Y1195217D03*
Y1232028D03*
Y1242067D03*
X1081857Y269856D03*
X1089030Y1691229D03*
X1092980Y1696029D03*
X1095489Y1708519D03*
X1081974Y1731920D03*
X1110316Y790296D03*
Y800335D03*
Y827107D03*
Y837146D03*
Y863918D03*
Y873957D03*
Y910768D03*
Y900729D03*
Y937540D03*
Y947579D03*
Y1084784D03*
Y1094823D03*
Y1131634D03*
Y1121595D03*
Y1158406D03*
Y1168445D03*
Y1205256D03*
Y1195217D03*
Y1232028D03*
Y1242067D03*
X1103351Y1737117D03*
X1112001Y1718991D03*
X1125351Y1737117D03*
X1140017Y790296D03*
Y800335D03*
Y827107D03*
Y837146D03*
Y863918D03*
Y873957D03*
Y910768D03*
Y900729D03*
Y937540D03*
Y947579D03*
Y1084784D03*
Y1094823D03*
Y1131634D03*
Y1121595D03*
Y1158406D03*
Y1168445D03*
Y1205256D03*
Y1195217D03*
Y1232028D03*
Y1242067D03*
X1169718Y790296D03*
Y800335D03*
Y837146D03*
Y827107D03*
Y863918D03*
Y873957D03*
Y900729D03*
Y910768D03*
Y937540D03*
Y947579D03*
Y1084784D03*
Y1094823D03*
Y1121595D03*
Y1131634D03*
Y1158406D03*
Y1168445D03*
Y1205256D03*
Y1195217D03*
Y1232028D03*
Y1242067D03*
X1183050Y-20074D03*
Y-10074D03*
Y-74D03*
Y9926D03*
X1183224Y1495595D03*
X1186312Y-20074D03*
Y-10074D03*
Y-74D03*
Y9926D03*
X1200037Y164987D03*
Y160987D03*
X1189727Y177187D03*
X1200012Y185187D03*
X1199419Y790296D03*
Y800335D03*
Y837146D03*
Y827107D03*
Y863918D03*
Y873957D03*
Y900729D03*
Y910768D03*
Y937540D03*
Y947579D03*
Y1084784D03*
Y1094823D03*
Y1121595D03*
Y1131634D03*
Y1158406D03*
Y1168445D03*
Y1195217D03*
Y1205256D03*
Y1232028D03*
Y1242067D03*
X1189924Y1485895D03*
X1199612Y1700334D03*
X1199294Y1721143D03*
X1191351Y1737117D03*
X1215581Y91346D03*
X1202711Y87651D03*
X1215581Y94846D03*
X1213355Y1412564D03*
Y1427564D03*
Y1420064D03*
X1203324Y1505295D03*
X1210024Y1495595D03*
X1214954Y1700343D03*
X1204447Y1707143D03*
X1213351Y1737117D03*
X1223455Y91346D03*
X1230312Y88635D03*
X1215931Y141530D03*
X1218431D03*
X1231118Y142125D03*
X1228355Y1412564D03*
X1220855D03*
X1228355Y1427564D03*
Y1420064D03*
X1220855Y1427564D03*
X1216724Y1485895D03*
X1230124Y1505295D03*
X1235546Y75293D03*
X1232812Y88635D03*
X1239218Y128239D03*
Y137239D03*
Y132739D03*
Y123739D03*
X1238094Y280573D03*
X1233345Y300157D03*
X1242429Y443255D03*
Y447255D03*
X1243524Y1485895D03*
X1236824Y1495595D03*
X1235351Y1737117D03*
X1248286Y-15374D03*
Y-25374D03*
Y14626D03*
X1252561Y72675D03*
X1255185Y140053D03*
Y142553D03*
X1255175Y137553D03*
X1246094Y280573D03*
X1246748Y785752D03*
X1258121Y1342686D03*
X1256924Y1505295D03*
X1257351Y1737117D03*
X1270324Y1485895D03*
X1263624Y1495595D03*
X1278677Y808988D03*
X1283724Y1485895D03*
X1279351Y1737117D03*
X1295532Y539513D03*
X1301666Y555413D03*
X1301351Y1737117D03*
X1319667Y87587D03*
Y105227D03*
X1307857Y111353D03*
X1317986Y1485895D03*
X1311286Y1495595D03*
X1333878Y637721D03*
X1331386Y1505295D03*
X1323351Y1737117D03*
X1344958Y85358D03*
X1336558Y637721D03*
X1339238D03*
X1344438D03*
X1341838D03*
X1344786Y1485895D03*
X1338086Y1495595D03*
X1345351Y1737117D03*
X1356868Y85324D03*
X1360629Y120380D03*
X1363831Y642042D03*
X1361387Y642026D03*
X1356367Y642080D03*
X1352527Y638278D03*
X1360944Y638999D03*
Y636042D03*
X1357717Y647180D03*
Y649780D03*
X1355117D03*
Y647180D03*
X1357717Y644580D03*
X1355117D03*
X1364317Y661368D03*
X1357057Y661328D03*
X1364886Y1495595D03*
X1358186Y1505295D03*
X1369808Y87587D03*
X1382123Y614130D03*
X1374887Y626579D03*
X1372457D03*
X1370027D03*
X1369978Y614164D03*
X1366331Y642042D03*
X1376731Y638935D03*
Y642042D03*
X1371531Y638935D03*
Y642042D03*
Y635978D03*
X1374887Y632179D03*
X1374131Y638935D03*
Y642042D03*
X1368931Y638935D03*
Y642042D03*
Y635978D03*
X1370027Y632179D03*
X1372457D03*
X1371847Y661328D03*
X1366123Y1015473D03*
X1373603D03*
Y1019016D03*
Y1022559D03*
X1366123D03*
Y1019016D03*
X1371586Y1485895D03*
X1367351Y1737117D03*
X1381457Y637865D03*
X1380306Y664816D03*
X1380256Y667466D03*
X1393664Y671949D03*
Y668992D03*
X1390417Y677480D03*
X1389067Y674980D03*
X1387817Y677480D03*
X1394087Y674926D03*
X1390417Y680080D03*
X1387817D03*
X1390417Y682680D03*
X1387817D03*
X1388757Y693397D03*
Y690897D03*
X1381083Y1015473D03*
Y1022559D03*
Y1019016D03*
X1384986Y1505295D03*
X1391686Y1495595D03*
X1389351Y1737117D03*
X1403207Y118938D03*
X1402678Y647064D03*
X1404231Y671835D03*
X1406831D03*
X1409431D03*
X1404231Y668878D03*
X1407587Y665079D03*
X1405157Y659479D03*
X1407587D03*
X1401631Y671835D03*
Y668878D03*
X1402727Y659479D03*
Y665079D03*
X1405157D03*
X1404231Y674942D03*
X1409431D03*
X1406831D03*
X1396531D03*
X1399031D03*
X1401631D03*
X1403693Y1009399D03*
X1407433D03*
X1399953D03*
X1404615Y1014744D03*
X1399953Y1028830D03*
X1407433D03*
X1404615Y1023012D03*
Y1018878D03*
X1403693Y1028830D03*
X1406608Y1282606D03*
X1398386Y1485895D03*
X1414823Y647030D03*
X1414157Y670665D03*
X1416241Y700281D03*
X1416291Y697631D03*
X1420417Y712660D03*
Y715260D03*
Y710060D03*
X1423017Y712660D03*
Y715260D03*
Y710060D03*
X1421667Y707560D03*
X1422757Y726097D03*
Y723597D03*
X1418101Y997765D03*
Y993765D03*
X1418176Y989765D03*
X1418653Y1009399D03*
X1418101Y1001765D03*
X1422394Y1009399D03*
X1414913D03*
X1411173D03*
X1423316Y1014744D03*
X1414458D03*
Y1023012D03*
X1418653Y1028830D03*
X1411173D03*
X1414913D03*
X1423316Y1023012D03*
Y1018878D03*
X1422394Y1028830D03*
X1414458Y1018878D03*
X1411786Y1485895D03*
X1413199Y1643920D03*
X1411351Y1737117D03*
X1438883Y-15050D03*
Y-25050D03*
Y-5050D03*
Y14950D03*
Y4950D03*
X1438312Y152166D03*
X1435278Y679644D03*
X1436257Y676265D03*
X1436831Y701458D03*
X1435327Y692059D03*
X1437757D03*
X1434231Y701458D03*
X1435327Y697659D03*
X1437757D03*
X1426264Y701572D03*
X1436831Y704415D03*
Y707522D03*
X1439431Y704415D03*
Y707522D03*
X1431631D03*
X1429131D03*
X1426687Y707506D03*
X1434231Y704415D03*
Y707522D03*
X1426264Y704529D03*
X1433614Y1009399D03*
X1426134D03*
X1429874D03*
X1433552Y1014744D03*
X1429874Y1028830D03*
X1433552Y1018878D03*
Y1023012D03*
X1426134Y1028830D03*
X1433614D03*
X1433351Y1737117D03*
X1441908Y-26370D03*
X1445161Y-26356D03*
X1441908Y-16370D03*
X1441923Y-13855D03*
X1445161Y-16356D03*
X1445176Y-13841D03*
X1441923Y-23855D03*
X1445176Y-23841D03*
X1441908Y-6370D03*
X1441923Y-3855D03*
X1445161Y-6356D03*
X1445176Y-3841D03*
X1441908Y3630D03*
X1445161Y3644D03*
X1441908Y13630D03*
X1441923Y16145D03*
X1445161Y13644D03*
X1445176Y16159D03*
X1441923Y6145D03*
X1445176Y6159D03*
X1440871Y130118D03*
X1453667Y152166D03*
X1447423Y679610D03*
X1440187Y697659D03*
X1446757Y703265D03*
X1440187Y692059D03*
X1442031Y704415D03*
Y707522D03*
X1453335Y729637D03*
Y732237D03*
Y734837D03*
X1453757Y743597D03*
Y746097D03*
X1454098Y1485895D03*
X1447398Y1495595D03*
X1459177Y163796D03*
X1456282Y568977D03*
Y572977D03*
Y576977D03*
Y580977D03*
X1468196Y699221D03*
X1468245Y711636D03*
Y717236D03*
X1467149Y721035D03*
X1458599Y721045D03*
Y724002D03*
X1455935Y729637D03*
Y732237D03*
X1454585Y727137D03*
X1459605Y727083D03*
X1462049Y727099D03*
X1464549D03*
X1467149Y723992D03*
Y727099D03*
X1455935Y734837D03*
X1467498Y1505295D03*
X1455579Y1636114D03*
X1473105Y717236D03*
X1470675Y711636D03*
X1473105D03*
X1470675Y717236D03*
X1469749Y721035D03*
X1479757Y722865D03*
X1469749Y723992D03*
X1474949D03*
X1472349D03*
Y727099D03*
X1469749D03*
X1474949D03*
X1481665Y745809D03*
X1477177Y803488D03*
X1478177Y817013D03*
X1480898Y1485895D03*
X1474198Y1495595D03*
X1498543Y587841D03*
X1492264Y721149D03*
X1486417Y729637D03*
Y732237D03*
X1489017Y729687D03*
Y732237D03*
X1492264Y724106D03*
X1487667Y727137D03*
X1492687Y727083D03*
X1495131Y727099D03*
X1497631D03*
X1486417Y734837D03*
X1489017D03*
X1484265Y745809D03*
X1489177Y803488D03*
X1498177Y817013D03*
X1494298Y1505295D03*
X1501278Y699221D03*
X1506187Y717236D03*
Y711636D03*
X1501327D03*
X1503757D03*
X1501327Y717404D03*
X1503757D03*
X1502831Y721035D03*
X1500231D03*
X1512757Y722897D03*
X1500231Y723992D03*
X1502831D03*
X1505431D03*
X1508031D03*
X1500231Y727099D03*
X1502831D03*
X1505431D03*
X1508031D03*
X1505905Y746119D03*
X1508505D03*
X1507698Y1485895D03*
X1500998Y1495595D03*
X1499351Y1737117D03*
X1519930Y543470D03*
X1516357Y555318D03*
X1516257Y559977D03*
X1525064Y721149D03*
Y724106D03*
X1521817Y729637D03*
Y732237D03*
X1525487Y727083D03*
X1527931Y727099D03*
X1519217Y729637D03*
Y732237D03*
X1520467Y727137D03*
X1521817Y734837D03*
X1519217D03*
X1515895Y746119D03*
X1518495D03*
X1521098Y1505295D03*
X1527798Y1495595D03*
X1521351Y1737117D03*
X1541580Y-19575D03*
X1541666Y69340D03*
X1532853Y560264D03*
X1534078Y699221D03*
X1536557Y711636D03*
X1534127D03*
X1538987Y717236D03*
Y711636D03*
X1534127Y717236D03*
X1536557D03*
X1535631Y721035D03*
X1533031D03*
X1538231Y723992D03*
X1540831D03*
X1538231Y727099D03*
X1540831D03*
X1530431D03*
X1533031Y723992D03*
X1535631D03*
X1533031Y727099D03*
X1535631D03*
X1543563Y757803D03*
X1543585Y762919D03*
X1543574Y760361D03*
X1534317Y1216828D03*
X1531227Y1227648D03*
X1540227D03*
X1534498Y1485895D03*
X1543351Y1737117D03*
X1554510Y28406D03*
X1547424D03*
X1554510Y40020D03*
X1547424D03*
X1552662Y75343D03*
X1546257Y701097D03*
X1558194Y702166D03*
Y699209D03*
X1552347Y712897D03*
X1554947D03*
X1552347Y710297D03*
Y707697D03*
X1554947Y710297D03*
Y707697D03*
X1553597Y705197D03*
X1558617Y705143D03*
X1551250Y723840D03*
X1553750D03*
X1545557Y722897D03*
X1556555Y740617D03*
X1556544Y738059D03*
X1554055Y740617D03*
X1554044Y738059D03*
X1546965Y746119D03*
X1546954Y743561D03*
X1548119Y751952D03*
X1545619D03*
X1548119Y754832D03*
X1545619D03*
X1546063Y757803D03*
X1546085Y762919D03*
X1546074Y760361D03*
X1549877Y1217288D03*
Y1221288D03*
X1547898Y1485895D03*
X1561597Y28406D03*
X1568683D03*
Y40020D03*
X1561597D03*
X1563666Y69340D03*
X1567208Y677281D03*
X1572117Y695296D03*
X1568761Y702052D03*
X1571361D03*
X1568761Y699095D03*
X1566161Y702052D03*
Y699095D03*
X1569687Y689696D03*
X1572117D03*
X1567257D03*
Y695296D03*
X1569687D03*
X1563561Y705159D03*
X1561061D03*
X1568761D03*
X1571361D03*
X1566161D03*
X1568660Y1283460D03*
X1572036Y1306083D03*
X1565351Y1737117D03*
X1575770Y28406D03*
X1582857D03*
Y40020D03*
X1575770D03*
X1574666Y75340D03*
X1585666Y69340D03*
X1579748Y536344D03*
X1576843Y674425D03*
X1579807Y671268D03*
X1586367Y671428D03*
X1587717Y676528D03*
Y673928D03*
X1585117Y676528D03*
Y673928D03*
Y679128D03*
X1587717D03*
X1578757Y700965D03*
X1573961Y702052D03*
X1586070Y696830D03*
Y694330D03*
X1573961Y705159D03*
X1578904Y721340D03*
Y723840D03*
X1584849Y793506D03*
X1587028Y1307137D03*
X1582160Y1485895D03*
X1575460Y1495595D03*
X1587351Y1737117D03*
X1589943Y28406D03*
X1597030D03*
Y40020D03*
X1589943D03*
X1596666Y75340D03*
X1599837Y295328D03*
X1593214Y531226D03*
X1599978Y643512D03*
X1600027Y655927D03*
X1602457D03*
X1591387Y671374D03*
X1593831Y671390D03*
X1596331D03*
X1601531D03*
Y668283D03*
Y665326D03*
X1598931Y671390D03*
Y668283D03*
Y665326D03*
X1600027Y661527D03*
X1602457D03*
X1590964Y668397D03*
Y665440D03*
X1594539Y1295288D03*
X1595560Y1505295D03*
X1602260Y1495595D03*
X1604117Y28406D03*
Y40020D03*
X1607666Y69343D03*
X1609355Y592794D03*
X1615677Y648488D03*
X1604887Y655927D03*
X1618117Y657528D03*
Y654928D03*
X1611557Y667165D03*
X1606731Y671390D03*
Y668283D03*
X1604131Y671390D03*
Y668283D03*
X1604887Y661527D03*
X1618117Y660128D03*
X1613154Y688238D03*
Y690738D03*
X1605447Y1288748D03*
X1608960Y1485895D03*
X1609351Y1737117D03*
X1632896Y28406D03*
X1625809D03*
X1632896Y40020D03*
X1625809D03*
X1618666Y75340D03*
X1631558Y588513D03*
X1628756Y588591D03*
X1624067Y588474D03*
X1621187Y588591D03*
X1632978Y624512D03*
X1633027Y636927D03*
Y642527D03*
X1620717Y657528D03*
X1631931Y652390D03*
Y649283D03*
X1626831Y652390D03*
X1629331D03*
X1631931Y646326D03*
X1624387Y652374D03*
X1619367Y652428D03*
X1620717Y654928D03*
X1623964Y649397D03*
Y646440D03*
X1621050Y671768D03*
X1623550D03*
X1620717Y660128D03*
X1628946Y790296D03*
Y800335D03*
Y827107D03*
Y837146D03*
Y863918D03*
Y873957D03*
Y900729D03*
Y910768D03*
Y937540D03*
Y947579D03*
Y1084784D03*
Y1094823D03*
Y1121595D03*
Y1131634D03*
Y1158406D03*
Y1168445D03*
Y1195217D03*
Y1205256D03*
Y1232028D03*
Y1242067D03*
X1629060Y1495595D03*
X1622360Y1505295D03*
X1631351Y1737117D03*
X1647069Y28406D03*
X1639983D03*
X1647069Y40020D03*
X1639983D03*
X1641870Y75340D03*
X1645123Y624478D03*
X1637887Y642527D03*
Y636927D03*
X1635457D03*
Y642527D03*
X1644457Y648265D03*
X1639731Y652390D03*
X1634531D03*
X1637131D03*
X1639731Y649283D03*
X1634531D03*
X1637131D03*
X1634531Y646326D03*
X1643183Y1419441D03*
X1643283Y1431541D03*
X1635760Y1485895D03*
X1654156Y28406D03*
Y40020D03*
X1652870Y69340D03*
X1650917Y657528D03*
Y654928D03*
X1653517Y657528D03*
X1652167Y652428D03*
X1653517Y654928D03*
X1648604Y671768D03*
X1650917Y660128D03*
X1659618Y659021D03*
X1662298D03*
X1651104Y671768D03*
X1653517Y660128D03*
X1656938Y659021D03*
X1651959Y689800D03*
X1658647Y790296D03*
Y800335D03*
Y827107D03*
Y837146D03*
Y863918D03*
Y873957D03*
Y900729D03*
Y910768D03*
Y937540D03*
Y947579D03*
Y1084784D03*
Y1094823D03*
Y1121595D03*
Y1131634D03*
Y1158406D03*
Y1168445D03*
Y1205256D03*
Y1195217D03*
Y1232028D03*
Y1242067D03*
X1649283Y1419441D03*
Y1431541D03*
X1655383D03*
Y1419441D03*
X1655957Y1445116D03*
X1662560Y1485895D03*
X1649160Y1505295D03*
X1655860Y1495595D03*
X1653351Y1737117D03*
X1677030Y28406D03*
X1669943D03*
X1677030Y40020D03*
X1669943D03*
X1663866Y75343D03*
X1674870Y69340D03*
X1668516Y599956D03*
X1674516D03*
X1668516Y609450D03*
X1671516Y599956D03*
X1674516Y609450D03*
X1677516Y599956D03*
X1671516Y609450D03*
X1677516D03*
X1667498Y659021D03*
X1664898D03*
X1675960Y1485895D03*
X1668000Y1711759D03*
Y1726909D03*
X1675351Y1737117D03*
X1684117Y28406D03*
X1691203D03*
Y40020D03*
X1684117D03*
X1686004Y75340D03*
X1688348Y790296D03*
Y800335D03*
Y827107D03*
Y837146D03*
Y863918D03*
Y873957D03*
Y910768D03*
Y900729D03*
Y937540D03*
Y947579D03*
Y1084784D03*
Y1094823D03*
Y1131634D03*
Y1121595D03*
Y1158406D03*
Y1168445D03*
Y1205256D03*
Y1195217D03*
Y1232028D03*
Y1242067D03*
X1684677Y1440258D03*
X1687357Y1440268D03*
X1698290Y28406D03*
X1705376D03*
X1698290Y40020D03*
X1697000Y69343D03*
X1701121Y641658D03*
X1706101D03*
X1695529Y1545193D03*
X1703000Y1711759D03*
X1697351Y1737117D03*
X1708004Y75340D03*
X1708305Y679720D03*
X1718049Y790296D03*
Y800335D03*
Y827107D03*
Y837146D03*
Y863918D03*
Y873957D03*
Y910768D03*
Y900729D03*
Y937540D03*
Y947579D03*
Y1084784D03*
Y1094823D03*
Y1131634D03*
Y1121595D03*
Y1158406D03*
Y1168445D03*
Y1195217D03*
Y1205256D03*
Y1232028D03*
Y1242067D03*
X1719351Y1737117D03*
X1735375Y-40925D03*
X1732350Y-39605D03*
X1735390Y-38410D03*
X1738628Y-40911D03*
X1738658Y-35881D03*
X1738673Y-33366D03*
X1738643Y-38396D03*
X1749571Y255317D03*
Y252317D03*
X1745502Y660088D03*
X1747750Y790296D03*
Y800335D03*
Y827107D03*
Y837146D03*
Y863918D03*
Y873957D03*
Y910768D03*
Y900729D03*
Y937540D03*
Y947579D03*
Y1084784D03*
Y1094823D03*
Y1131634D03*
Y1121595D03*
Y1158406D03*
Y1168445D03*
Y1205256D03*
Y1195217D03*
Y1232028D03*
Y1242067D03*
X1742120Y1708265D03*
Y1723415D03*
X1741351Y1737117D03*
X1753388Y28406D03*
X1760475D03*
X1754364Y100353D03*
X1764644Y122973D03*
X1755969Y251524D03*
Y248524D03*
X1763509Y251341D03*
Y248341D03*
X1763351Y1737117D03*
X1771881Y128439D03*
Y125939D03*
Y123439D03*
X1781966Y128501D03*
Y126001D03*
Y123501D03*
X1775984Y253779D03*
Y256779D03*
X1777450Y790296D03*
Y800335D03*
Y827107D03*
Y837146D03*
Y863918D03*
Y873957D03*
Y910768D03*
Y900729D03*
Y937540D03*
Y947579D03*
Y1084784D03*
Y1094823D03*
Y1131634D03*
Y1121595D03*
Y1158406D03*
Y1168445D03*
Y1205256D03*
Y1195217D03*
Y1232028D03*
Y1242067D03*
X1785072Y53161D03*
X1789811Y178083D03*
X1794629Y193323D03*
X1791645Y193397D03*
X1795219Y185910D03*
X1795949Y205580D03*
X1795909Y209128D03*
X1795365Y197567D03*
X1796019Y202030D03*
X1791445Y197497D03*
X1783592Y763765D03*
X1804111Y178083D03*
X1807711D03*
Y175083D03*
X1803165Y196127D03*
X1797621Y193373D03*
X1800389Y193424D03*
X1803045Y193397D03*
X1798943Y204744D03*
Y209044D03*
X1802276Y209013D03*
X1805235Y208950D03*
X1802276Y204713D03*
X1800125Y201857D03*
X1805235Y204650D03*
X1799629Y198870D03*
X1803145Y198697D03*
X1817674Y188699D03*
X1829732Y367359D03*
G54D24*
X67725Y1538946D03*
X74912D03*
X72585D03*
X70155D03*
X103468D03*
X105898D03*
X108328D03*
X110655D03*
X1757438Y1571982D03*
X1755008D03*
X1762195D03*
X1759868D03*
X1793181D03*
X1790751D03*
X1795611D03*
X1797938D03*
G54D28*
X130000Y1719450D03*
X543277Y88632D03*
X538620Y93289D03*
G54D64*
X1156378Y133866D03*
X1183858Y207205D03*
X1173858D03*
X1193858D03*
X1351260Y164213D03*
Y174213D03*
X1361260Y164213D03*
Y174213D03*
X1371260Y164213D03*
X1381260D03*
X1371260Y174213D03*
X1381260D03*
X1391260Y164213D03*
Y174213D03*
G54D20*
X50880Y1415563D03*
Y1418963D03*
X61157Y69340D03*
X64557D03*
X58349Y1406331D03*
Y1409731D03*
X78265Y26477D03*
X74865D03*
X81970Y19541D03*
X72153Y75343D03*
X75553D03*
X69323Y780257D03*
Y786950D03*
Y803682D03*
Y793643D03*
Y796989D03*
Y817068D03*
Y810375D03*
Y823761D03*
Y830454D03*
Y833800D03*
Y840493D03*
Y847186D03*
Y853879D03*
Y860572D03*
Y877304D03*
Y867265D03*
Y870611D03*
Y883997D03*
Y890690D03*
Y897383D03*
Y904076D03*
Y907423D03*
Y914115D03*
Y920808D03*
Y927501D03*
Y934194D03*
Y940887D03*
Y950926D03*
Y944234D03*
Y964312D03*
Y957619D03*
Y971005D03*
Y977698D03*
Y984391D03*
Y1001123D03*
Y997777D03*
Y991084D03*
Y1031241D03*
Y1037934D03*
Y1044627D03*
Y1058013D03*
Y1051320D03*
Y1074745D03*
Y1081438D03*
Y1088131D03*
Y1098171D03*
Y1104863D03*
Y1091478D03*
Y1111556D03*
Y1118249D03*
Y1134982D03*
Y1124942D03*
Y1128289D03*
Y1148367D03*
Y1141675D03*
Y1155060D03*
Y1161753D03*
Y1165100D03*
Y1171793D03*
Y1178486D03*
Y1185178D03*
Y1191871D03*
Y1208604D03*
Y1198564D03*
Y1201911D03*
Y1215297D03*
Y1221989D03*
Y1228682D03*
Y1235375D03*
Y1238722D03*
Y1245415D03*
Y1252108D03*
X85370Y19541D03*
X92438Y26477D03*
X89038D03*
X96143Y19541D03*
X94157Y75340D03*
X83157Y69340D03*
X97557Y75340D03*
X86557Y69340D03*
X85465Y776911D03*
Y783604D03*
Y790297D03*
Y800336D03*
Y807029D03*
Y793643D03*
Y813722D03*
Y820415D03*
Y837147D03*
Y830454D03*
Y827108D03*
Y843840D03*
Y850533D03*
Y857226D03*
Y863919D03*
Y873958D03*
Y880651D03*
Y867265D03*
Y887344D03*
Y894037D03*
Y910769D03*
Y904076D03*
Y900730D03*
Y924155D03*
Y917462D03*
Y930848D03*
Y940887D03*
Y937541D03*
Y947580D03*
Y954273D03*
Y967659D03*
Y974352D03*
Y981045D03*
Y987737D03*
Y994430D03*
Y1001123D03*
Y1027895D03*
Y1034588D03*
Y1041281D03*
Y1047974D03*
Y1054667D03*
Y1061360D03*
Y1071399D03*
Y1064706D03*
Y1078092D03*
Y1088131D03*
Y1084785D03*
Y1094824D03*
Y1101517D03*
Y1108210D03*
Y1114903D03*
Y1131635D03*
Y1124942D03*
Y1121596D03*
Y1138328D03*
Y1145021D03*
Y1151714D03*
Y1161753D03*
Y1158407D03*
Y1168446D03*
Y1175139D03*
Y1181832D03*
Y1188525D03*
Y1205257D03*
Y1198564D03*
Y1195218D03*
Y1211950D03*
Y1218643D03*
Y1225336D03*
Y1235375D03*
Y1232029D03*
Y1242068D03*
Y1248761D03*
X99543Y19541D03*
X106611Y26477D03*
X103211D03*
X110316Y19541D03*
X105157Y69340D03*
X108557D03*
X99024Y780257D03*
Y786950D03*
Y803682D03*
Y793643D03*
Y796989D03*
Y817068D03*
Y810375D03*
Y823761D03*
Y830454D03*
Y833800D03*
Y840493D03*
Y847186D03*
Y853879D03*
Y860572D03*
Y877304D03*
Y867265D03*
Y870611D03*
Y883997D03*
Y890690D03*
Y897383D03*
Y904076D03*
Y907423D03*
Y914115D03*
Y920808D03*
Y927501D03*
Y934194D03*
Y940887D03*
Y950926D03*
Y944234D03*
Y964312D03*
Y957619D03*
Y971005D03*
Y977698D03*
Y984391D03*
Y1001123D03*
Y997777D03*
Y991084D03*
Y1031241D03*
Y1037934D03*
Y1044627D03*
Y1058013D03*
Y1051320D03*
Y1074745D03*
Y1081438D03*
Y1088131D03*
Y1098171D03*
Y1104863D03*
Y1091478D03*
Y1111556D03*
Y1118249D03*
Y1134982D03*
Y1124942D03*
Y1128289D03*
Y1148367D03*
Y1141675D03*
Y1155060D03*
Y1161753D03*
Y1165100D03*
Y1171793D03*
Y1178486D03*
Y1185178D03*
Y1191871D03*
Y1208604D03*
Y1198564D03*
Y1201911D03*
Y1215297D03*
Y1221989D03*
Y1228682D03*
Y1235375D03*
Y1238722D03*
Y1245415D03*
Y1252108D03*
X112473Y1660235D03*
X109073D03*
X107569Y1685763D03*
X110969D03*
X113716Y19541D03*
X120785Y26477D03*
X117385D03*
X124490Y19541D03*
X116157Y75340D03*
X127153Y69343D03*
X119557Y75340D03*
X115166Y776911D03*
Y783604D03*
Y790297D03*
Y800336D03*
Y807029D03*
Y793643D03*
Y813722D03*
Y820415D03*
Y837147D03*
Y830454D03*
Y827108D03*
Y843840D03*
Y850533D03*
Y857226D03*
Y863919D03*
Y873958D03*
Y880651D03*
Y867265D03*
Y887344D03*
Y894037D03*
Y910769D03*
Y904076D03*
Y900730D03*
Y924155D03*
Y917462D03*
Y930848D03*
Y940887D03*
Y937541D03*
Y947580D03*
Y954273D03*
Y967659D03*
Y974352D03*
Y981045D03*
Y987737D03*
Y994430D03*
Y1001123D03*
Y1027895D03*
Y1034588D03*
Y1041281D03*
Y1047974D03*
Y1054667D03*
Y1061360D03*
Y1071399D03*
Y1064706D03*
Y1078092D03*
Y1088131D03*
Y1084785D03*
Y1094824D03*
Y1101517D03*
Y1108210D03*
Y1114903D03*
Y1131635D03*
Y1124942D03*
Y1121596D03*
Y1138328D03*
Y1145021D03*
Y1151714D03*
Y1161753D03*
Y1158407D03*
Y1168446D03*
Y1175139D03*
Y1181832D03*
Y1188525D03*
Y1205257D03*
Y1198564D03*
Y1195218D03*
Y1211950D03*
Y1218643D03*
Y1225336D03*
Y1235375D03*
Y1232029D03*
Y1242068D03*
Y1248761D03*
X127890Y19541D03*
X138157Y75340D03*
X141557D03*
X130553Y69343D03*
X128724Y780257D03*
Y786950D03*
Y803682D03*
Y793643D03*
Y796989D03*
Y817068D03*
Y810375D03*
Y823761D03*
Y830454D03*
Y833800D03*
Y840493D03*
Y847186D03*
Y853879D03*
Y860572D03*
Y877304D03*
Y867265D03*
Y870611D03*
Y883997D03*
Y890690D03*
Y897383D03*
Y904076D03*
Y907423D03*
Y914115D03*
Y920808D03*
Y927501D03*
Y934194D03*
Y940887D03*
Y950926D03*
Y944234D03*
Y964312D03*
Y957619D03*
Y971005D03*
Y977698D03*
Y984391D03*
Y1001123D03*
Y997777D03*
Y991084D03*
Y1031241D03*
Y1037934D03*
Y1044627D03*
Y1058013D03*
Y1051320D03*
Y1074745D03*
Y1081438D03*
Y1088131D03*
Y1098171D03*
Y1104863D03*
Y1091478D03*
Y1111556D03*
Y1118249D03*
Y1134982D03*
Y1124942D03*
Y1128289D03*
Y1148367D03*
Y1141675D03*
Y1155060D03*
Y1161753D03*
Y1165100D03*
Y1171793D03*
Y1178486D03*
Y1185178D03*
Y1191871D03*
Y1208604D03*
Y1198564D03*
Y1201911D03*
Y1215297D03*
Y1221989D03*
Y1228682D03*
Y1235375D03*
Y1238722D03*
Y1245415D03*
Y1252108D03*
X156651Y26477D03*
X153251D03*
X149153Y69343D03*
X152553D03*
X144866Y776911D03*
Y783604D03*
Y790297D03*
Y800336D03*
Y807029D03*
Y793643D03*
Y813722D03*
Y820415D03*
Y837147D03*
Y830454D03*
Y827108D03*
Y843840D03*
Y850533D03*
Y857226D03*
Y863919D03*
Y873958D03*
Y880651D03*
Y867265D03*
Y887344D03*
Y894037D03*
Y910769D03*
Y904076D03*
Y900730D03*
Y924155D03*
Y917462D03*
Y930848D03*
Y940887D03*
Y937541D03*
Y947580D03*
Y954273D03*
Y967659D03*
Y974352D03*
Y981045D03*
Y987737D03*
Y994430D03*
Y1001123D03*
Y1027895D03*
Y1034588D03*
Y1041281D03*
Y1047974D03*
Y1054667D03*
Y1061360D03*
Y1071399D03*
Y1064706D03*
Y1078092D03*
Y1088131D03*
Y1084785D03*
Y1094824D03*
Y1101517D03*
Y1108210D03*
Y1114903D03*
Y1131635D03*
Y1124942D03*
Y1121596D03*
Y1138328D03*
Y1145021D03*
Y1151714D03*
Y1161753D03*
Y1158407D03*
Y1168446D03*
Y1175139D03*
Y1181832D03*
Y1188525D03*
Y1205257D03*
Y1198564D03*
Y1195218D03*
Y1211950D03*
Y1218643D03*
Y1225336D03*
Y1235375D03*
Y1232029D03*
Y1242068D03*
Y1248761D03*
X170824Y26477D03*
X163756Y19541D03*
X167424Y26477D03*
X160356Y19541D03*
X161361Y75340D03*
X164761D03*
X158425Y780257D03*
Y786950D03*
Y803682D03*
Y793643D03*
Y796989D03*
Y817068D03*
Y810375D03*
Y823761D03*
Y830454D03*
Y833800D03*
Y840493D03*
Y847186D03*
Y853879D03*
Y860572D03*
Y877304D03*
Y867265D03*
Y870611D03*
Y883997D03*
Y890690D03*
Y897383D03*
Y904076D03*
Y907423D03*
Y914115D03*
Y920808D03*
Y927501D03*
Y934194D03*
Y940887D03*
Y950926D03*
Y944234D03*
Y964312D03*
Y957619D03*
Y971005D03*
Y977698D03*
Y984391D03*
Y1001123D03*
Y997777D03*
Y991084D03*
Y1031241D03*
Y1037934D03*
Y1044627D03*
Y1058013D03*
Y1051320D03*
Y1074745D03*
Y1081438D03*
Y1088131D03*
Y1098171D03*
Y1104863D03*
Y1091478D03*
Y1111556D03*
Y1118249D03*
Y1134982D03*
Y1124942D03*
Y1128289D03*
Y1148367D03*
Y1141675D03*
Y1155060D03*
Y1161753D03*
Y1165100D03*
Y1171793D03*
Y1178486D03*
Y1185178D03*
Y1191871D03*
Y1208604D03*
Y1198564D03*
Y1201911D03*
Y1215297D03*
Y1221989D03*
Y1228682D03*
Y1235375D03*
Y1238722D03*
Y1245415D03*
Y1252108D03*
X169351Y1462595D03*
X163113Y1483590D03*
Y1480190D03*
Y1501990D03*
Y1505390D03*
X177929Y19541D03*
X174529D03*
X183357Y75343D03*
X172361Y69340D03*
X186757Y75343D03*
X175761Y69340D03*
X174567Y776911D03*
Y783604D03*
Y790297D03*
Y800336D03*
Y807029D03*
Y793643D03*
Y813722D03*
Y820415D03*
Y837147D03*
Y830454D03*
Y827108D03*
Y843840D03*
Y850533D03*
Y857226D03*
Y863919D03*
Y873958D03*
Y880651D03*
Y867265D03*
Y887344D03*
Y894037D03*
Y910769D03*
Y904076D03*
Y900730D03*
Y924155D03*
Y917462D03*
Y930848D03*
Y940887D03*
Y937541D03*
Y947580D03*
Y954273D03*
Y967659D03*
Y974352D03*
Y981045D03*
Y987737D03*
Y994430D03*
Y1001123D03*
Y1027895D03*
Y1034588D03*
Y1041281D03*
Y1047974D03*
Y1054667D03*
Y1061360D03*
Y1071399D03*
Y1064706D03*
Y1078092D03*
Y1088131D03*
Y1084785D03*
Y1094824D03*
Y1101517D03*
Y1108210D03*
Y1114903D03*
Y1131635D03*
Y1124942D03*
Y1121596D03*
Y1138328D03*
Y1145021D03*
Y1151714D03*
Y1161753D03*
Y1158407D03*
Y1168446D03*
Y1175139D03*
Y1181832D03*
Y1188525D03*
Y1205257D03*
Y1198564D03*
Y1195218D03*
Y1211950D03*
Y1218643D03*
Y1225336D03*
Y1235375D03*
Y1232029D03*
Y1242068D03*
Y1248761D03*
X172751Y1462595D03*
X179451Y1452895D03*
X176051D03*
X200785Y26477D03*
X197385D03*
X194361Y69340D03*
X197761D03*
X188126Y780257D03*
Y786950D03*
Y803682D03*
Y793643D03*
Y796989D03*
Y817068D03*
Y810375D03*
Y823761D03*
Y830454D03*
Y833800D03*
Y840493D03*
Y847186D03*
Y853879D03*
Y860572D03*
Y877304D03*
Y867265D03*
Y870611D03*
Y883997D03*
Y890690D03*
Y897383D03*
Y904076D03*
Y907423D03*
Y914115D03*
Y920808D03*
Y927501D03*
Y934194D03*
Y940887D03*
Y950926D03*
Y944234D03*
Y964312D03*
Y957619D03*
Y971005D03*
Y977698D03*
Y984391D03*
Y1001123D03*
Y997777D03*
Y991084D03*
Y1031241D03*
Y1037934D03*
Y1044627D03*
Y1058013D03*
Y1051320D03*
Y1074745D03*
Y1081438D03*
Y1088131D03*
Y1098171D03*
Y1104863D03*
Y1091478D03*
Y1111556D03*
Y1118249D03*
Y1134982D03*
Y1124942D03*
Y1128289D03*
Y1148367D03*
Y1141675D03*
Y1155060D03*
Y1161753D03*
Y1165100D03*
Y1171793D03*
Y1178486D03*
Y1185178D03*
Y1191871D03*
Y1208604D03*
Y1198564D03*
Y1201911D03*
Y1215297D03*
Y1221989D03*
Y1228682D03*
Y1235375D03*
Y1238722D03*
Y1245415D03*
Y1252108D03*
X199551Y1462595D03*
X196151D03*
X192851Y1472295D03*
X189451D03*
X188166Y1592380D03*
X200226D03*
X191566D03*
X188166Y1624292D03*
X200226D03*
X191566D03*
X207890Y19541D03*
X214958Y26477D03*
X204490Y19541D03*
X211558Y26477D03*
X216491Y69343D03*
X205495Y75340D03*
X208895D03*
X204268Y776911D03*
Y783604D03*
Y790297D03*
Y800336D03*
Y807029D03*
Y793643D03*
Y813722D03*
Y820415D03*
Y837147D03*
Y830454D03*
Y827108D03*
Y843840D03*
Y850533D03*
Y857226D03*
Y863919D03*
Y873958D03*
Y880651D03*
Y867265D03*
Y887344D03*
Y894037D03*
Y910769D03*
Y904076D03*
Y900730D03*
Y924155D03*
Y917462D03*
Y930848D03*
Y940887D03*
Y937541D03*
Y947580D03*
Y954273D03*
Y967659D03*
Y974352D03*
Y981045D03*
Y987737D03*
Y994430D03*
Y1001123D03*
Y1027895D03*
Y1034588D03*
Y1041281D03*
Y1047974D03*
Y1054667D03*
Y1061360D03*
Y1071399D03*
Y1064706D03*
Y1078092D03*
Y1088131D03*
Y1084785D03*
Y1094824D03*
Y1101517D03*
Y1108210D03*
Y1114903D03*
Y1131635D03*
Y1124942D03*
Y1121596D03*
Y1138328D03*
Y1145021D03*
Y1151714D03*
Y1161753D03*
Y1158407D03*
Y1168446D03*
Y1175139D03*
Y1181832D03*
Y1188525D03*
Y1205257D03*
Y1198564D03*
Y1195218D03*
Y1211950D03*
Y1218643D03*
Y1225336D03*
Y1235375D03*
Y1232029D03*
Y1242068D03*
Y1248761D03*
X206251Y1452895D03*
X202851D03*
X216251Y1472295D03*
X212286Y1592380D03*
X203626D03*
X215686D03*
X212286Y1624292D03*
X203626D03*
X215686D03*
X222063Y19541D03*
X218663D03*
X227495Y75340D03*
X230895D03*
X219891Y69343D03*
X226351Y1462595D03*
X222951D03*
X229651Y1452895D03*
X219651Y1472295D03*
X224346Y1592380D03*
X227746D03*
X224346Y1624292D03*
X227746D03*
X233051Y1452895D03*
X246451Y1472295D03*
X243051D03*
X236406Y1592380D03*
X239806D03*
X236406Y1624292D03*
X239806D03*
X253151Y1462595D03*
X259851Y1452895D03*
X249751Y1462595D03*
X256451Y1452895D03*
X248466Y1592380D03*
X260526D03*
X251866D03*
X248466Y1624292D03*
X260526D03*
X251866D03*
X269851Y1452895D03*
X273251D03*
X272586Y1592380D03*
X263926D03*
X275986D03*
X272586Y1624292D03*
X263926D03*
X275986D03*
X280621Y1484082D03*
Y1480682D03*
X291175Y1483590D03*
Y1480190D03*
X280621Y1497482D03*
Y1494082D03*
X291175Y1501990D03*
Y1505390D03*
X284646Y1592380D03*
X288046D03*
X284646Y1624292D03*
X288046D03*
X300813Y1462595D03*
X297413D03*
X304113Y1452895D03*
X296706Y1592380D03*
X300106D03*
X296706Y1624292D03*
X300106D03*
X307513Y1452895D03*
X320913Y1472295D03*
X317513D03*
X316316Y1544997D03*
X321040D03*
X316316Y1548397D03*
X321040D03*
X308766Y1592380D03*
X320826D03*
X312166D03*
X308766Y1624292D03*
X320826D03*
X312166D03*
X327613Y1462595D03*
X334313Y1452895D03*
X324213Y1462595D03*
X330913Y1452895D03*
X325765Y1544997D03*
X330489D03*
X335214D03*
X325765Y1548397D03*
X330489D03*
X335214D03*
X332886Y1592380D03*
X324226D03*
X332886Y1624292D03*
X324226D03*
X351013Y1462595D03*
X347713Y1472295D03*
X344313D03*
X339938Y1544997D03*
X344663D03*
X349387D03*
X339938Y1548397D03*
X344663D03*
X349387D03*
X344946Y1592380D03*
X336286D03*
X348346D03*
X344946Y1624292D03*
X336286D03*
X348346D03*
X354413Y1462595D03*
X361113Y1452895D03*
X357713D03*
X363561Y1544997D03*
X354112D03*
X358836D03*
X363561Y1548397D03*
X354112D03*
X358836D03*
X357006Y1592380D03*
X360406D03*
X357006Y1624292D03*
X360406D03*
X371999Y819527D03*
X372000Y831797D03*
Y835197D03*
X371999Y822927D03*
X372000Y846427D03*
Y843027D03*
X377813Y1462595D03*
X374513Y1472295D03*
X371113D03*
X368285Y1544997D03*
X373009D03*
X377733D03*
X368285Y1548397D03*
X373009D03*
X377733D03*
X369066Y1592380D03*
X372466D03*
X369066Y1624292D03*
X372466D03*
X390841Y-25571D03*
Y-22171D03*
X385001Y816927D03*
Y813527D03*
X381213Y1462595D03*
X387913Y1452895D03*
X384513D03*
X382458Y1544997D03*
X387182D03*
X382458Y1548397D03*
X387182D03*
X400426Y112815D03*
Y116215D03*
X405606Y125815D03*
Y129715D03*
X401313Y1452895D03*
X397913D03*
X408683Y1480682D03*
Y1484082D03*
Y1497482D03*
Y1494082D03*
X417486Y124179D03*
Y127579D03*
X436924Y1462595D03*
X433524D03*
X440224Y1452895D03*
X427286Y1483590D03*
Y1480190D03*
Y1501990D03*
Y1505390D03*
X455502Y88711D03*
X452102D03*
X448414Y94684D03*
X445014D03*
X443624Y1452895D03*
X453624Y1472295D03*
X452427Y1544997D03*
Y1548397D03*
X452339Y1592380D03*
Y1624292D03*
X462456Y95101D03*
X459056D03*
X463724Y1462595D03*
X470424Y1452895D03*
X460324Y1462595D03*
X467024Y1452895D03*
X457024Y1472295D03*
X457151Y1544997D03*
X461876D03*
X466600D03*
X457151Y1548397D03*
X461876D03*
X466600D03*
X464399Y1592380D03*
X455739D03*
X467799D03*
X464399Y1624292D03*
X455739D03*
X467799D03*
X476295Y130020D03*
X472895D03*
X482255Y133222D03*
Y129822D03*
X483824Y1472295D03*
X480424D03*
X471325Y1544997D03*
X476049D03*
X480774D03*
X471325Y1548397D03*
X476049D03*
X480774D03*
X476459Y1592380D03*
X479859D03*
X476459Y1624292D03*
X479859D03*
X490380Y131442D03*
X493780D03*
X490524Y1462595D03*
X497224Y1452895D03*
X487124Y1462595D03*
X493824Y1452895D03*
X499672Y1544997D03*
X485498D03*
X490223D03*
X494947D03*
X499672Y1548397D03*
X485498D03*
X490223D03*
X494947D03*
X488519Y1592380D03*
X491919D03*
X488519Y1624292D03*
X491919D03*
X514240Y97146D03*
X513924Y1462595D03*
X510624Y1472295D03*
X507224D03*
X504396Y1544997D03*
X509120D03*
X513844D03*
X504396Y1548397D03*
X509120D03*
X513844D03*
X500579Y1592380D03*
X512639D03*
X503979D03*
X500579Y1624292D03*
X512639D03*
X503979D03*
X526460Y100895D03*
Y97495D03*
X517640Y97146D03*
X517324Y1462595D03*
X524024Y1452895D03*
X520624D03*
X518569Y1544997D03*
X523293D03*
X518569Y1548397D03*
X523293D03*
X524699Y1592380D03*
X516039D03*
X528099D03*
X524699Y1624292D03*
X516039D03*
X528099D03*
X533918Y47067D03*
X537318D03*
X537424Y1452895D03*
X534024D03*
X544794Y1480682D03*
Y1484082D03*
Y1497482D03*
Y1494082D03*
X536759Y1592380D03*
X540159D03*
X536759Y1624292D03*
X540159D03*
X559069Y105385D03*
Y101985D03*
X552105Y112203D03*
X555505D03*
X555348Y1483590D03*
Y1480190D03*
Y1501990D03*
Y1505390D03*
X548819Y1592380D03*
X552219D03*
X548819Y1624292D03*
X552219D03*
X564986Y1462595D03*
X571686Y1452895D03*
X561586Y1462595D03*
X568286Y1452895D03*
X572939Y1592380D03*
X560879D03*
X564279D03*
X572939Y1624292D03*
X560879D03*
X564279D03*
X588386Y1462595D03*
X585086Y1472295D03*
X581686D03*
X584999Y1592380D03*
X576339D03*
X588399D03*
X584999Y1624292D03*
X576339D03*
X588399D03*
X591786Y1462595D03*
X598486Y1452895D03*
X595086D03*
X597059Y1592380D03*
X600459D03*
X597059Y1624292D03*
X600459D03*
X618586Y1462595D03*
X615186D03*
X611886Y1472295D03*
X608486D03*
X609119Y1592380D03*
X612519D03*
X609119Y1624292D03*
X612519D03*
X625286Y1452895D03*
X621886D03*
X621179Y1592380D03*
X633239D03*
X624579D03*
X621179Y1624292D03*
X633239D03*
X624579D03*
X645386Y1462595D03*
X641986D03*
X648686Y1452895D03*
X638686Y1472295D03*
X635286D03*
X636639Y1592380D03*
Y1624292D03*
X653999Y1426757D03*
Y1423357D03*
X652086Y1452895D03*
X662086D03*
X677055Y780257D03*
Y786950D03*
Y803682D03*
Y793643D03*
Y796989D03*
Y817068D03*
Y810375D03*
Y823761D03*
Y830454D03*
Y833800D03*
Y840493D03*
Y847186D03*
Y853879D03*
Y860572D03*
Y877304D03*
Y867265D03*
Y870611D03*
Y883997D03*
Y890690D03*
Y897383D03*
Y904076D03*
Y907423D03*
Y914115D03*
Y920808D03*
Y927501D03*
Y934194D03*
Y940887D03*
Y950926D03*
Y944234D03*
Y964312D03*
Y957619D03*
Y971005D03*
Y977698D03*
Y984391D03*
Y1001123D03*
Y997777D03*
Y991084D03*
Y1031241D03*
Y1037934D03*
Y1044627D03*
Y1058013D03*
Y1051320D03*
Y1074745D03*
Y1081438D03*
Y1088131D03*
Y1098171D03*
Y1104863D03*
Y1091478D03*
Y1111556D03*
Y1118249D03*
Y1134982D03*
Y1124942D03*
Y1128289D03*
Y1148367D03*
Y1141675D03*
Y1155060D03*
Y1161753D03*
Y1165100D03*
Y1171793D03*
Y1178486D03*
Y1185178D03*
Y1191871D03*
Y1208604D03*
Y1198564D03*
Y1201911D03*
Y1215297D03*
Y1221989D03*
Y1228682D03*
Y1235375D03*
Y1238722D03*
Y1245415D03*
Y1252108D03*
X665486Y1452895D03*
X672856Y1484082D03*
Y1480682D03*
Y1497482D03*
Y1494082D03*
X693197Y776911D03*
Y783604D03*
Y790297D03*
Y800336D03*
Y807029D03*
Y793643D03*
Y813722D03*
Y820415D03*
Y837147D03*
Y830454D03*
Y827108D03*
Y843840D03*
Y850533D03*
Y857226D03*
Y863919D03*
Y873958D03*
Y880651D03*
Y867265D03*
Y887344D03*
Y894037D03*
Y910769D03*
Y904076D03*
Y900730D03*
Y924155D03*
Y917462D03*
Y930848D03*
Y940887D03*
Y937541D03*
Y947580D03*
Y954273D03*
Y967659D03*
Y974352D03*
Y981045D03*
Y987737D03*
Y994430D03*
Y1001123D03*
Y1027895D03*
Y1034588D03*
Y1041281D03*
Y1047974D03*
Y1054667D03*
Y1061360D03*
Y1071399D03*
Y1064706D03*
Y1078092D03*
Y1088131D03*
Y1084785D03*
Y1094824D03*
Y1101517D03*
Y1108210D03*
Y1114903D03*
Y1131635D03*
Y1124942D03*
Y1121596D03*
Y1138328D03*
Y1145021D03*
Y1151714D03*
Y1161753D03*
Y1158407D03*
Y1168446D03*
Y1175139D03*
Y1181832D03*
Y1188525D03*
Y1205257D03*
Y1198564D03*
Y1195218D03*
Y1211950D03*
Y1218643D03*
Y1225336D03*
Y1235375D03*
Y1232029D03*
Y1242068D03*
Y1248761D03*
X691276Y1455112D03*
X704771Y179599D03*
Y182999D03*
Y194810D03*
Y191410D03*
Y206621D03*
Y203221D03*
Y218432D03*
Y215032D03*
X706756Y780257D03*
Y786950D03*
Y803682D03*
Y793643D03*
Y796989D03*
Y817068D03*
Y810375D03*
Y823761D03*
Y830454D03*
Y833800D03*
Y840493D03*
Y847186D03*
Y853879D03*
Y860572D03*
Y877304D03*
Y867265D03*
Y870611D03*
Y883997D03*
Y890690D03*
Y897383D03*
Y904076D03*
Y907423D03*
Y914115D03*
Y920808D03*
Y927501D03*
Y934194D03*
Y940887D03*
Y950926D03*
Y944234D03*
Y964312D03*
Y957619D03*
Y971005D03*
Y977698D03*
Y984391D03*
Y1001123D03*
Y997777D03*
Y991084D03*
Y1031241D03*
Y1037934D03*
Y1044627D03*
Y1058013D03*
Y1051320D03*
Y1074745D03*
Y1081438D03*
Y1088131D03*
Y1098171D03*
Y1104863D03*
Y1091478D03*
Y1111556D03*
Y1118249D03*
Y1134982D03*
Y1124942D03*
Y1128289D03*
Y1148367D03*
Y1141675D03*
Y1155060D03*
Y1161753D03*
Y1165100D03*
Y1171793D03*
Y1178486D03*
Y1185178D03*
Y1191871D03*
Y1208604D03*
Y1198564D03*
Y1201911D03*
Y1215297D03*
Y1221989D03*
Y1228682D03*
Y1235375D03*
Y1238722D03*
Y1245415D03*
Y1252108D03*
X694676Y1455112D03*
X716699Y177087D03*
Y173687D03*
Y189087D03*
Y185687D03*
Y200587D03*
Y197187D03*
Y209021D03*
Y212421D03*
X722898Y776911D03*
Y783604D03*
Y790297D03*
Y800336D03*
Y807029D03*
Y793643D03*
Y813722D03*
Y820415D03*
Y837147D03*
Y830454D03*
Y827108D03*
Y843840D03*
Y850533D03*
Y857226D03*
Y863919D03*
Y873958D03*
Y880651D03*
Y867265D03*
Y887344D03*
Y894037D03*
Y910769D03*
Y904076D03*
Y900730D03*
Y924155D03*
Y917462D03*
Y930848D03*
Y940887D03*
Y937541D03*
Y947580D03*
Y954273D03*
Y967659D03*
Y974352D03*
Y981045D03*
Y987737D03*
Y994430D03*
Y1001123D03*
Y1027895D03*
Y1034588D03*
Y1041281D03*
Y1047974D03*
Y1054667D03*
Y1061360D03*
Y1071399D03*
Y1064706D03*
Y1078092D03*
Y1088131D03*
Y1084785D03*
Y1094824D03*
Y1101517D03*
Y1108210D03*
Y1114903D03*
Y1131635D03*
Y1124942D03*
Y1121596D03*
Y1138328D03*
Y1145021D03*
Y1151714D03*
Y1161753D03*
Y1158407D03*
Y1168446D03*
Y1175139D03*
Y1181832D03*
Y1188525D03*
Y1205257D03*
Y1198564D03*
Y1195218D03*
Y1211950D03*
Y1218643D03*
Y1225336D03*
Y1235375D03*
Y1232029D03*
Y1242068D03*
Y1248761D03*
X725925Y-25571D03*
Y-22171D03*
X736457Y780257D03*
Y786950D03*
Y803682D03*
Y793643D03*
Y796989D03*
Y817068D03*
Y810375D03*
Y823761D03*
Y830454D03*
Y833800D03*
Y840493D03*
Y847186D03*
Y853879D03*
Y860572D03*
Y877304D03*
Y867265D03*
Y870611D03*
Y883997D03*
Y890690D03*
Y897383D03*
Y904076D03*
Y907423D03*
Y914115D03*
Y920808D03*
Y927501D03*
Y934194D03*
Y940887D03*
Y950926D03*
Y944234D03*
Y964312D03*
Y957619D03*
Y971005D03*
Y977698D03*
Y984391D03*
Y1001123D03*
Y997777D03*
Y991084D03*
Y1031241D03*
Y1037934D03*
Y1044627D03*
Y1058013D03*
Y1051320D03*
Y1074745D03*
Y1081438D03*
Y1088131D03*
Y1098171D03*
Y1104863D03*
Y1091478D03*
Y1111556D03*
Y1118249D03*
Y1134982D03*
Y1124942D03*
Y1128289D03*
Y1148367D03*
Y1141675D03*
Y1155060D03*
Y1161753D03*
Y1165100D03*
Y1171793D03*
Y1178486D03*
Y1185178D03*
Y1191871D03*
Y1208604D03*
Y1198564D03*
Y1201911D03*
Y1215297D03*
Y1221989D03*
Y1228682D03*
Y1235375D03*
Y1238722D03*
Y1245415D03*
Y1252108D03*
X752599Y776911D03*
Y783604D03*
Y790297D03*
Y800336D03*
Y807029D03*
Y793643D03*
Y813722D03*
Y820415D03*
Y837147D03*
Y830454D03*
Y827108D03*
Y843840D03*
Y850533D03*
Y857226D03*
Y863919D03*
Y873958D03*
Y880651D03*
Y867265D03*
Y887344D03*
Y894037D03*
Y910769D03*
Y904076D03*
Y900730D03*
Y924155D03*
Y917462D03*
Y930848D03*
Y940887D03*
Y937541D03*
Y947580D03*
Y954273D03*
Y967659D03*
Y974352D03*
Y981045D03*
Y987737D03*
Y994430D03*
Y1001123D03*
Y1027895D03*
Y1034588D03*
Y1041281D03*
Y1047974D03*
Y1054667D03*
Y1061360D03*
Y1071399D03*
Y1064706D03*
Y1078092D03*
Y1088131D03*
Y1084785D03*
Y1094824D03*
Y1101517D03*
Y1108210D03*
Y1114903D03*
Y1131635D03*
Y1124942D03*
Y1121596D03*
Y1138328D03*
Y1145021D03*
Y1151714D03*
Y1161753D03*
Y1158407D03*
Y1168446D03*
Y1175139D03*
Y1181832D03*
Y1188525D03*
Y1205257D03*
Y1198564D03*
Y1195218D03*
Y1211950D03*
Y1218643D03*
Y1225336D03*
Y1235375D03*
Y1232029D03*
Y1242068D03*
Y1248761D03*
X766158Y780257D03*
Y786950D03*
Y803682D03*
Y793643D03*
Y796989D03*
Y817068D03*
Y810375D03*
Y823761D03*
Y830454D03*
Y833800D03*
Y840493D03*
Y847186D03*
Y853879D03*
Y860572D03*
Y877304D03*
Y867265D03*
Y870611D03*
Y883997D03*
Y890690D03*
Y897383D03*
Y904076D03*
Y907423D03*
Y914115D03*
Y920808D03*
Y927501D03*
Y934194D03*
Y940887D03*
Y950926D03*
Y944234D03*
Y964312D03*
Y957619D03*
Y971005D03*
Y977698D03*
Y984391D03*
Y1001123D03*
Y997777D03*
Y991084D03*
Y1031241D03*
Y1037934D03*
Y1044627D03*
Y1058013D03*
Y1051320D03*
Y1074745D03*
Y1081438D03*
Y1088131D03*
Y1098171D03*
Y1104863D03*
Y1091478D03*
Y1111556D03*
Y1118249D03*
Y1134982D03*
Y1124942D03*
Y1128289D03*
Y1148367D03*
Y1141675D03*
Y1155060D03*
Y1161753D03*
Y1165100D03*
Y1171793D03*
Y1178486D03*
Y1185178D03*
Y1191871D03*
Y1208604D03*
Y1198564D03*
Y1201911D03*
Y1215297D03*
Y1221989D03*
Y1228682D03*
Y1235375D03*
Y1238722D03*
Y1245415D03*
Y1252108D03*
X782300Y776911D03*
Y783604D03*
Y790297D03*
Y800336D03*
Y807029D03*
Y793643D03*
Y813722D03*
Y820415D03*
Y837147D03*
Y830454D03*
Y827108D03*
Y843840D03*
Y850533D03*
Y857226D03*
Y863919D03*
Y873958D03*
Y880651D03*
Y867265D03*
Y887344D03*
Y894037D03*
Y910769D03*
Y904076D03*
Y900730D03*
Y924155D03*
Y917462D03*
Y930848D03*
Y940887D03*
Y937541D03*
Y947580D03*
Y954273D03*
Y967659D03*
Y974352D03*
Y981045D03*
Y987737D03*
Y994430D03*
Y1001123D03*
Y1027895D03*
Y1034588D03*
Y1041281D03*
Y1047974D03*
Y1054667D03*
Y1061360D03*
Y1071399D03*
Y1064706D03*
Y1078092D03*
Y1088131D03*
Y1084785D03*
Y1094824D03*
Y1101517D03*
Y1108210D03*
Y1114903D03*
Y1131635D03*
Y1124942D03*
Y1121596D03*
Y1138328D03*
Y1145021D03*
Y1151714D03*
Y1161753D03*
Y1158407D03*
Y1168446D03*
Y1175139D03*
Y1181832D03*
Y1188525D03*
Y1205257D03*
Y1198564D03*
Y1195218D03*
Y1211950D03*
Y1218643D03*
Y1225336D03*
Y1235375D03*
Y1232029D03*
Y1242068D03*
Y1248761D03*
X795858Y780257D03*
Y786950D03*
Y803682D03*
Y793643D03*
Y796989D03*
Y817068D03*
Y810375D03*
Y823761D03*
Y830454D03*
Y833800D03*
Y840493D03*
Y847186D03*
Y853879D03*
Y860572D03*
Y877304D03*
Y867265D03*
Y870611D03*
Y883997D03*
Y890690D03*
Y897383D03*
Y904076D03*
Y907423D03*
Y914115D03*
Y920808D03*
Y927501D03*
Y934194D03*
Y940887D03*
Y950926D03*
Y944234D03*
Y964312D03*
Y957619D03*
Y971005D03*
Y977698D03*
Y984391D03*
Y1001123D03*
Y997777D03*
Y991084D03*
Y1031241D03*
Y1037934D03*
Y1044627D03*
Y1058013D03*
Y1051320D03*
Y1074745D03*
Y1081438D03*
Y1088131D03*
Y1098171D03*
Y1104863D03*
Y1091478D03*
Y1111556D03*
Y1118249D03*
Y1134982D03*
Y1124942D03*
Y1128289D03*
Y1148367D03*
Y1141675D03*
Y1155060D03*
Y1161753D03*
Y1165100D03*
Y1171793D03*
Y1178486D03*
Y1185178D03*
Y1191871D03*
Y1208604D03*
Y1198564D03*
Y1201911D03*
Y1215297D03*
Y1221989D03*
Y1228682D03*
Y1235375D03*
Y1238722D03*
Y1245415D03*
Y1252108D03*
X812000Y776911D03*
Y783604D03*
Y790297D03*
Y800336D03*
Y807029D03*
Y793643D03*
Y813722D03*
Y820415D03*
Y837147D03*
Y830454D03*
Y827108D03*
Y843840D03*
Y850533D03*
Y857226D03*
Y863919D03*
Y873958D03*
Y880651D03*
Y867265D03*
Y887344D03*
Y894037D03*
Y910769D03*
Y904076D03*
Y900730D03*
Y924155D03*
Y917462D03*
Y930848D03*
Y940887D03*
Y937541D03*
Y947580D03*
Y954273D03*
Y967659D03*
Y974352D03*
Y981045D03*
Y987737D03*
Y994430D03*
Y1001123D03*
Y1027895D03*
Y1034588D03*
Y1041281D03*
Y1047974D03*
Y1054667D03*
Y1061360D03*
Y1071399D03*
Y1064706D03*
Y1078092D03*
Y1088131D03*
Y1084785D03*
Y1094824D03*
Y1101517D03*
Y1108210D03*
Y1114903D03*
Y1131635D03*
Y1124942D03*
Y1121596D03*
Y1138328D03*
Y1145021D03*
Y1151714D03*
Y1161753D03*
Y1158407D03*
Y1168446D03*
Y1175139D03*
Y1181832D03*
Y1188525D03*
Y1205257D03*
Y1198564D03*
Y1195218D03*
Y1211950D03*
Y1218643D03*
Y1225336D03*
Y1235375D03*
Y1232029D03*
Y1242068D03*
Y1248761D03*
X814296Y1384045D03*
Y1387445D03*
X842320Y-21711D03*
Y-18311D03*
Y-11711D03*
Y-8311D03*
Y18289D03*
Y21689D03*
X1007587Y805418D03*
Y816352D03*
Y819752D03*
Y808818D03*
Y827354D03*
Y830754D03*
Y838356D03*
Y841756D03*
X1045465Y780256D03*
Y786949D03*
Y803681D03*
Y793642D03*
Y796988D03*
Y817067D03*
Y810374D03*
Y823760D03*
Y830453D03*
Y833799D03*
Y840492D03*
Y847185D03*
Y853878D03*
Y860571D03*
Y877303D03*
Y867264D03*
Y870610D03*
Y883996D03*
Y890689D03*
Y897382D03*
Y904075D03*
Y907422D03*
Y914114D03*
Y920807D03*
Y927500D03*
Y934193D03*
Y940886D03*
Y950925D03*
Y944233D03*
Y964311D03*
Y957618D03*
Y971004D03*
Y977697D03*
Y984390D03*
Y1001122D03*
Y997776D03*
Y991083D03*
Y1031240D03*
Y1037933D03*
Y1044626D03*
Y1058012D03*
Y1051319D03*
Y1074744D03*
Y1081437D03*
Y1088130D03*
Y1098170D03*
Y1104862D03*
Y1091477D03*
Y1111555D03*
Y1118248D03*
Y1134981D03*
Y1124941D03*
Y1128288D03*
Y1148366D03*
Y1141674D03*
Y1155059D03*
Y1161752D03*
Y1165099D03*
Y1171792D03*
Y1178485D03*
Y1185177D03*
Y1191870D03*
Y1208603D03*
Y1198563D03*
Y1201910D03*
Y1215296D03*
Y1221988D03*
Y1228681D03*
Y1235374D03*
Y1238721D03*
Y1245414D03*
Y1252107D03*
X1061607Y776910D03*
Y783603D03*
Y790296D03*
Y800335D03*
Y807028D03*
Y793642D03*
Y813721D03*
Y820414D03*
Y837146D03*
Y830453D03*
Y827107D03*
Y843839D03*
Y850532D03*
Y857225D03*
Y863918D03*
Y873957D03*
Y880650D03*
Y867264D03*
Y887343D03*
Y894036D03*
Y910768D03*
Y904075D03*
Y900729D03*
Y924154D03*
Y917461D03*
Y930847D03*
Y940886D03*
Y937540D03*
Y947579D03*
Y954272D03*
Y967658D03*
Y974351D03*
Y981044D03*
Y987736D03*
Y994429D03*
Y1001122D03*
Y1027894D03*
Y1034587D03*
Y1041280D03*
Y1047973D03*
Y1054666D03*
Y1061359D03*
Y1071398D03*
Y1064705D03*
Y1078091D03*
Y1088130D03*
Y1084784D03*
Y1094823D03*
Y1101516D03*
Y1108209D03*
Y1114902D03*
Y1131634D03*
Y1124941D03*
Y1121595D03*
Y1138327D03*
Y1145020D03*
Y1151713D03*
Y1161752D03*
Y1158406D03*
Y1168445D03*
Y1175138D03*
Y1181831D03*
Y1188524D03*
Y1205256D03*
Y1198563D03*
Y1195217D03*
Y1211949D03*
Y1218642D03*
Y1225335D03*
Y1235374D03*
Y1232028D03*
Y1242067D03*
Y1248760D03*
X1075166Y780256D03*
Y786949D03*
Y803681D03*
Y793642D03*
Y796988D03*
Y817067D03*
Y810374D03*
Y823760D03*
Y830453D03*
Y833799D03*
Y840492D03*
Y847185D03*
Y853878D03*
Y860571D03*
Y877303D03*
Y867264D03*
Y870610D03*
Y883996D03*
Y890689D03*
Y897382D03*
Y904075D03*
Y907422D03*
Y914114D03*
Y920807D03*
Y927500D03*
Y934193D03*
Y940886D03*
Y950925D03*
Y944233D03*
Y964311D03*
Y957618D03*
Y971004D03*
Y977697D03*
Y984390D03*
Y1001122D03*
Y997776D03*
Y991083D03*
Y1031240D03*
Y1037933D03*
Y1044626D03*
Y1058012D03*
Y1051319D03*
Y1074744D03*
Y1081437D03*
Y1088130D03*
Y1098170D03*
Y1104862D03*
Y1091477D03*
Y1111555D03*
Y1118248D03*
Y1134981D03*
Y1124941D03*
Y1128288D03*
Y1148366D03*
Y1141674D03*
Y1155059D03*
Y1161752D03*
Y1165099D03*
Y1171792D03*
Y1178485D03*
Y1185177D03*
Y1191870D03*
Y1208603D03*
Y1198563D03*
Y1201910D03*
Y1215296D03*
Y1221988D03*
Y1228681D03*
Y1235374D03*
Y1238721D03*
Y1245414D03*
Y1252107D03*
X1091308Y776910D03*
Y783603D03*
Y790296D03*
Y800335D03*
Y807028D03*
Y793642D03*
Y813721D03*
Y820414D03*
Y837146D03*
Y830453D03*
Y827107D03*
Y843839D03*
Y850532D03*
Y857225D03*
Y863918D03*
Y873957D03*
Y880650D03*
Y867264D03*
Y887343D03*
Y894036D03*
Y910768D03*
Y904075D03*
Y900729D03*
Y924154D03*
Y917461D03*
Y930847D03*
Y940886D03*
Y937540D03*
Y947579D03*
Y954272D03*
Y967658D03*
Y974351D03*
Y981044D03*
Y987736D03*
Y994429D03*
Y1001122D03*
Y1027894D03*
Y1034587D03*
Y1041280D03*
Y1047973D03*
Y1054666D03*
Y1061359D03*
Y1071398D03*
Y1064705D03*
Y1078091D03*
Y1088130D03*
Y1084784D03*
Y1094823D03*
Y1101516D03*
Y1108209D03*
Y1114902D03*
Y1131634D03*
Y1124941D03*
Y1121595D03*
Y1138327D03*
Y1145020D03*
Y1151713D03*
Y1161752D03*
Y1158406D03*
Y1168445D03*
Y1175138D03*
Y1181831D03*
Y1188524D03*
Y1205256D03*
Y1198563D03*
Y1195217D03*
Y1211949D03*
Y1218642D03*
Y1225335D03*
Y1235374D03*
Y1232028D03*
Y1242067D03*
Y1248760D03*
X1104866Y780256D03*
Y786949D03*
Y803681D03*
Y793642D03*
Y796988D03*
Y817067D03*
Y810374D03*
Y823760D03*
Y830453D03*
Y833799D03*
Y840492D03*
Y847185D03*
Y853878D03*
Y860571D03*
Y877303D03*
Y867264D03*
Y870610D03*
Y883996D03*
Y890689D03*
Y897382D03*
Y904075D03*
Y907422D03*
Y914114D03*
Y920807D03*
Y927500D03*
Y934193D03*
Y940886D03*
Y950925D03*
Y944233D03*
Y964311D03*
Y957618D03*
Y971004D03*
Y977697D03*
Y984390D03*
Y1001122D03*
Y997776D03*
Y991083D03*
Y1031240D03*
Y1037933D03*
Y1044626D03*
Y1058012D03*
Y1051319D03*
Y1074744D03*
Y1081437D03*
Y1088130D03*
Y1098170D03*
Y1104862D03*
Y1091477D03*
Y1111555D03*
Y1118248D03*
Y1134981D03*
Y1124941D03*
Y1128288D03*
Y1148366D03*
Y1141674D03*
Y1155059D03*
Y1161752D03*
Y1165099D03*
Y1171792D03*
Y1178485D03*
Y1185177D03*
Y1191870D03*
Y1208603D03*
Y1198563D03*
Y1201910D03*
Y1215296D03*
Y1221988D03*
Y1228681D03*
Y1235374D03*
Y1238721D03*
Y1245414D03*
Y1252107D03*
X1121008Y776910D03*
Y783603D03*
Y790296D03*
Y800335D03*
Y807028D03*
Y793642D03*
Y813721D03*
Y820414D03*
Y837146D03*
Y830453D03*
Y827107D03*
Y843839D03*
Y850532D03*
Y857225D03*
Y863918D03*
Y873957D03*
Y880650D03*
Y867264D03*
Y887343D03*
Y894036D03*
Y910768D03*
Y904075D03*
Y900729D03*
Y924154D03*
Y917461D03*
Y930847D03*
Y940886D03*
Y937540D03*
Y947579D03*
Y954272D03*
Y967658D03*
Y974351D03*
Y981044D03*
Y987736D03*
Y994429D03*
Y1001122D03*
Y1027894D03*
Y1034587D03*
Y1041280D03*
Y1047973D03*
Y1054666D03*
Y1061359D03*
Y1071398D03*
Y1064705D03*
Y1078091D03*
Y1088130D03*
Y1084784D03*
Y1094823D03*
Y1101516D03*
Y1108209D03*
Y1114902D03*
Y1131634D03*
Y1124941D03*
Y1121595D03*
Y1138327D03*
Y1145020D03*
Y1151713D03*
Y1161752D03*
Y1158406D03*
Y1168445D03*
Y1175138D03*
Y1181831D03*
Y1188524D03*
Y1205256D03*
Y1198563D03*
Y1195217D03*
Y1211949D03*
Y1218642D03*
Y1225335D03*
Y1235374D03*
Y1232028D03*
Y1242067D03*
Y1248760D03*
X1134567Y780256D03*
Y786949D03*
Y803681D03*
Y793642D03*
Y796988D03*
Y817067D03*
Y810374D03*
Y823760D03*
Y830453D03*
Y833799D03*
Y840492D03*
Y847185D03*
Y853878D03*
Y860571D03*
Y877303D03*
Y867264D03*
Y870610D03*
Y883996D03*
Y890689D03*
Y897382D03*
Y904075D03*
Y907422D03*
Y914114D03*
Y920807D03*
Y927500D03*
Y934193D03*
Y940886D03*
Y950925D03*
Y944233D03*
Y964311D03*
Y957618D03*
Y971004D03*
Y977697D03*
Y984390D03*
Y1001122D03*
Y997776D03*
Y991083D03*
Y1031240D03*
Y1037933D03*
Y1044626D03*
Y1058012D03*
Y1051319D03*
Y1074744D03*
Y1081437D03*
Y1088130D03*
Y1098170D03*
Y1104862D03*
Y1091477D03*
Y1111555D03*
Y1118248D03*
Y1134981D03*
Y1124941D03*
Y1128288D03*
Y1148366D03*
Y1141674D03*
Y1155059D03*
Y1161752D03*
Y1165099D03*
Y1171792D03*
Y1178485D03*
Y1185177D03*
Y1191870D03*
Y1208603D03*
Y1198563D03*
Y1201910D03*
Y1215296D03*
Y1221988D03*
Y1228681D03*
Y1235374D03*
Y1238721D03*
Y1245414D03*
Y1252107D03*
X1150709Y776910D03*
Y783603D03*
Y790296D03*
Y800335D03*
Y807028D03*
Y793642D03*
Y813721D03*
Y820414D03*
Y837146D03*
Y830453D03*
Y827107D03*
Y843839D03*
Y850532D03*
Y857225D03*
Y863918D03*
Y873957D03*
Y880650D03*
Y867264D03*
Y887343D03*
Y894036D03*
Y910768D03*
Y904075D03*
Y900729D03*
Y924154D03*
Y917461D03*
Y930847D03*
Y940886D03*
Y937540D03*
Y947579D03*
Y954272D03*
Y967658D03*
Y974351D03*
Y981044D03*
Y987736D03*
Y994429D03*
Y1001122D03*
Y1027894D03*
Y1034587D03*
Y1041280D03*
Y1047973D03*
Y1054666D03*
Y1061359D03*
Y1071398D03*
Y1064705D03*
Y1078091D03*
Y1088130D03*
Y1084784D03*
Y1094823D03*
Y1101516D03*
Y1108209D03*
Y1114902D03*
Y1131634D03*
Y1124941D03*
Y1121595D03*
Y1138327D03*
Y1145020D03*
Y1151713D03*
Y1161752D03*
Y1158406D03*
Y1168445D03*
Y1175138D03*
Y1181831D03*
Y1188524D03*
Y1205256D03*
Y1198563D03*
Y1195217D03*
Y1211949D03*
Y1218642D03*
Y1225335D03*
Y1235374D03*
Y1232028D03*
Y1242067D03*
Y1248760D03*
X1164268Y780256D03*
Y786949D03*
Y803681D03*
Y793642D03*
Y796988D03*
Y817067D03*
Y810374D03*
Y823760D03*
Y830453D03*
Y833799D03*
Y840492D03*
Y847185D03*
Y853878D03*
Y860571D03*
Y877303D03*
Y867264D03*
Y870610D03*
Y883996D03*
Y890689D03*
Y897382D03*
Y904075D03*
Y907422D03*
Y914114D03*
Y920807D03*
Y927500D03*
Y934193D03*
Y940886D03*
Y950925D03*
Y944233D03*
Y964311D03*
Y957618D03*
Y971004D03*
Y977697D03*
Y984390D03*
Y1001122D03*
Y997776D03*
Y991083D03*
Y1031240D03*
Y1037933D03*
Y1044626D03*
Y1058012D03*
Y1051319D03*
Y1074744D03*
Y1081437D03*
Y1088130D03*
Y1098170D03*
Y1104862D03*
Y1091477D03*
Y1111555D03*
Y1118248D03*
Y1134981D03*
Y1124941D03*
Y1128288D03*
Y1148366D03*
Y1141674D03*
Y1155059D03*
Y1161752D03*
Y1165099D03*
Y1171792D03*
Y1178485D03*
Y1185177D03*
Y1191870D03*
Y1208603D03*
Y1198563D03*
Y1201910D03*
Y1215296D03*
Y1221988D03*
Y1228681D03*
Y1235374D03*
Y1238721D03*
Y1245414D03*
Y1252107D03*
X1170986Y1516590D03*
Y1513190D03*
Y1534990D03*
Y1538390D03*
X1177404Y-21711D03*
Y-18311D03*
Y-11711D03*
Y-8311D03*
Y18289D03*
Y21689D03*
X1180410Y776910D03*
Y783603D03*
Y790296D03*
Y800335D03*
Y807028D03*
Y793642D03*
Y813721D03*
Y820414D03*
Y837146D03*
Y830453D03*
Y827107D03*
Y843839D03*
Y850532D03*
Y857225D03*
Y863918D03*
Y873957D03*
Y880650D03*
Y867264D03*
Y887343D03*
Y894036D03*
Y910768D03*
Y904075D03*
Y900729D03*
Y924154D03*
Y917461D03*
Y930847D03*
Y940886D03*
Y937540D03*
Y947579D03*
Y954272D03*
Y967658D03*
Y974351D03*
Y981044D03*
Y987736D03*
Y994429D03*
Y1001122D03*
Y1027894D03*
Y1034587D03*
Y1041280D03*
Y1047973D03*
Y1054666D03*
Y1061359D03*
Y1071398D03*
Y1064705D03*
Y1078091D03*
Y1088130D03*
Y1084784D03*
Y1094823D03*
Y1101516D03*
Y1108209D03*
Y1114902D03*
Y1131634D03*
Y1124941D03*
Y1121595D03*
Y1138327D03*
Y1145020D03*
Y1151713D03*
Y1161752D03*
Y1158406D03*
Y1168445D03*
Y1175138D03*
Y1181831D03*
Y1188524D03*
Y1205256D03*
Y1198563D03*
Y1195217D03*
Y1211949D03*
Y1218642D03*
Y1225335D03*
Y1235374D03*
Y1232028D03*
Y1242067D03*
Y1248760D03*
X1183924Y1485895D03*
X1180624Y1495595D03*
X1177224D03*
X1187324Y1485895D03*
X1200724Y1505295D03*
X1197324D03*
X1196039Y1625380D03*
X1199439D03*
X1196039Y1657292D03*
X1199439D03*
X1214124Y1485895D03*
X1210724D03*
X1207424Y1495595D03*
X1204024D03*
X1208099Y1625380D03*
X1211499D03*
X1208099Y1657292D03*
X1211499D03*
X1227524Y1505295D03*
X1224124D03*
X1230824Y1495595D03*
X1220159Y1625380D03*
X1223559D03*
X1220159Y1657292D03*
X1223559D03*
X1240924Y1485895D03*
X1237524D03*
X1234224Y1495595D03*
X1232219Y1625380D03*
X1244279D03*
X1235619D03*
X1232219Y1657292D03*
X1244279D03*
X1235619D03*
X1245840Y-18311D03*
Y-21711D03*
Y1689D03*
Y-1711D03*
Y11689D03*
Y8289D03*
X1254324Y1505295D03*
X1250924D03*
X1257624Y1495595D03*
X1256339Y1625380D03*
X1247679D03*
X1259739D03*
X1256339Y1657292D03*
X1247679D03*
X1259739D03*
X1267724Y1485895D03*
X1264324D03*
X1261024Y1495595D03*
X1268399Y1625380D03*
X1271799D03*
X1268399Y1657292D03*
X1271799D03*
X1277724Y1485895D03*
X1281124D03*
X1288494Y1517082D03*
Y1513682D03*
Y1530482D03*
Y1527082D03*
X1280459Y1625380D03*
X1283859D03*
X1280459Y1657292D03*
X1283859D03*
X1305286Y1495595D03*
X1299048Y1516590D03*
Y1513190D03*
Y1534990D03*
Y1538390D03*
X1292519Y1625380D03*
X1304579D03*
X1295919D03*
X1292519Y1657292D03*
X1304579D03*
X1295919D03*
X1315386Y1485895D03*
X1311986D03*
X1308686Y1495595D03*
X1316639Y1625380D03*
X1320039D03*
X1307979D03*
X1316639Y1657292D03*
X1320039D03*
X1307979D03*
X1328786Y1505295D03*
X1325386D03*
X1332086Y1495595D03*
X1324189Y1577997D03*
X1328913D03*
X1333638D03*
X1324189Y1581397D03*
X1328913D03*
X1333638D03*
X1328699Y1625380D03*
X1332099D03*
X1328699Y1657292D03*
X1332099D03*
X1342186Y1485895D03*
X1338786D03*
X1335486Y1495595D03*
X1338362Y1577997D03*
X1343087D03*
X1347811D03*
X1338362Y1581397D03*
X1343087D03*
X1347811D03*
X1340759Y1625380D03*
X1344159D03*
X1340759Y1657292D03*
X1344159D03*
X1355586Y1505295D03*
X1362286Y1495595D03*
X1352186Y1505295D03*
X1358886Y1495595D03*
X1352536Y1577997D03*
X1357260D03*
X1361985D03*
X1352536Y1581397D03*
X1357260D03*
X1361985D03*
X1352819Y1625380D03*
X1356219D03*
X1352819Y1657292D03*
X1356219D03*
X1368986Y1485895D03*
X1365586D03*
X1378986Y1505295D03*
X1371434Y1577997D03*
X1376158D03*
X1366709D03*
X1371434Y1581397D03*
X1376158D03*
X1366709D03*
X1364879Y1625380D03*
X1376939D03*
X1368279D03*
X1364879Y1657292D03*
X1376939D03*
X1368279D03*
X1392386Y1485895D03*
X1382386Y1505295D03*
X1389086Y1495595D03*
X1385686D03*
X1380882Y1577997D03*
X1385606D03*
X1390331D03*
X1380882Y1581397D03*
X1385606D03*
X1390331D03*
X1380339Y1625380D03*
Y1657292D03*
X1395786Y1485895D03*
X1409186D03*
X1405786D03*
X1395055Y1577997D03*
Y1581397D03*
X1416556Y1513682D03*
Y1517082D03*
Y1530482D03*
Y1527082D03*
X1436263Y-18311D03*
Y-21711D03*
Y1689D03*
Y-1711D03*
Y11689D03*
Y8289D03*
X1435160Y1516590D03*
Y1513190D03*
Y1534990D03*
Y1538390D03*
X1451498Y1485895D03*
X1448098D03*
X1444798Y1495595D03*
X1441398D03*
X1464898Y1505295D03*
X1461498D03*
X1468198Y1495595D03*
X1460301Y1577997D03*
X1465025D03*
X1460301Y1581397D03*
X1465025D03*
X1460213Y1625380D03*
X1463613D03*
X1460213Y1657292D03*
X1463613D03*
X1478298Y1485895D03*
X1474898D03*
X1471598Y1495595D03*
X1469750Y1577997D03*
X1474474D03*
X1479199D03*
X1483923D03*
X1469750Y1581397D03*
X1474474D03*
X1479199D03*
X1483923D03*
X1472273Y1625380D03*
X1475673D03*
X1472273Y1657292D03*
X1475673D03*
X1491698Y1505295D03*
X1488298D03*
X1498398Y1495595D03*
X1494998D03*
X1488648Y1577997D03*
X1493372D03*
X1498097D03*
X1488648Y1581397D03*
X1493372D03*
X1498097D03*
X1484333Y1625380D03*
X1496393D03*
X1487733D03*
X1484333Y1657292D03*
X1496393D03*
X1487733D03*
X1505098Y1485895D03*
X1501698D03*
X1507546Y1577997D03*
X1512270D03*
X1502821D03*
X1507546Y1581397D03*
X1512270D03*
X1502821D03*
X1508453Y1625380D03*
X1499793D03*
X1511853D03*
X1508453Y1657292D03*
X1499793D03*
X1511853D03*
X1528498Y1485895D03*
X1518498Y1505295D03*
X1525198Y1495595D03*
X1515098Y1505295D03*
X1521798Y1495595D03*
X1516994Y1577997D03*
X1521718D03*
X1526443D03*
X1516994Y1581397D03*
X1521718D03*
X1526443D03*
X1520513Y1625380D03*
X1523913D03*
X1520513Y1657292D03*
X1523913D03*
X1539134Y-22512D03*
Y-25912D03*
X1535566Y69340D03*
X1538966D03*
X1531898Y1485895D03*
X1541898D03*
X1531167Y1577997D03*
Y1581397D03*
X1532573Y1625380D03*
X1535973D03*
X1532573Y1657292D03*
X1535973D03*
X1552674Y26477D03*
X1556379Y19541D03*
X1549274Y26477D03*
X1557566Y69340D03*
X1546562Y75343D03*
X1549962D03*
X1545298Y1485895D03*
X1552668Y1513682D03*
Y1517082D03*
Y1530482D03*
Y1527082D03*
X1544633Y1625380D03*
X1556693D03*
X1548033D03*
X1544633Y1657292D03*
X1556693D03*
X1548033D03*
X1566847Y26477D03*
X1559779Y19541D03*
X1570552D03*
X1563447Y26477D03*
X1568566Y75340D03*
X1571966D03*
X1560966Y69340D03*
X1572860Y1495595D03*
X1569460D03*
X1563222Y1516590D03*
Y1513190D03*
Y1534990D03*
Y1538390D03*
X1568753Y1625380D03*
X1560093D03*
X1572153D03*
X1568753Y1657292D03*
X1560093D03*
X1572153D03*
X1588125Y19541D03*
X1581020Y26477D03*
X1573952Y19541D03*
X1584725D03*
X1577620Y26477D03*
X1579566Y69340D03*
X1582966D03*
X1579560Y1485895D03*
X1576160D03*
X1580813Y1625380D03*
X1584213D03*
X1580813Y1657292D03*
X1584213D03*
X1602299Y19541D03*
X1595194Y26477D03*
X1598899Y19541D03*
X1591794Y26477D03*
X1590566Y75340D03*
X1601562Y69343D03*
X1593966Y75340D03*
X1602960Y1485895D03*
X1592960Y1505295D03*
X1599660Y1495595D03*
X1589560Y1505295D03*
X1596260Y1495595D03*
X1592873Y1625380D03*
X1596273D03*
X1592873Y1657292D03*
X1596273D03*
X1612566Y75340D03*
X1615966D03*
X1604962Y69343D03*
X1606360Y1485895D03*
X1616360Y1505295D03*
X1604933Y1625380D03*
X1616993D03*
X1608333D03*
X1604933Y1657292D03*
X1616993D03*
X1608333D03*
X1631060Y26477D03*
X1627660D03*
X1623562Y69343D03*
X1626962D03*
X1633160Y1485895D03*
X1629760D03*
X1619760Y1505295D03*
X1626460Y1495595D03*
X1623060D03*
X1629053Y1625380D03*
X1620393D03*
X1632453D03*
X1629053Y1657292D03*
X1620393D03*
X1632453D03*
X1645233Y26477D03*
X1638165Y19541D03*
X1641833Y26477D03*
X1634765Y19541D03*
X1646770Y69340D03*
X1635770Y75340D03*
X1639170D03*
X1646560Y1505295D03*
X1643160D03*
X1641113Y1625380D03*
X1644513D03*
X1641113Y1657292D03*
X1644513D03*
X1652338Y19541D03*
X1648938D03*
X1657766Y75343D03*
X1661166D03*
X1650170Y69340D03*
X1653197Y780256D03*
Y786949D03*
Y803681D03*
Y793642D03*
Y796988D03*
Y817067D03*
Y810374D03*
Y823760D03*
Y830453D03*
Y833799D03*
Y840492D03*
Y847185D03*
Y853878D03*
Y860571D03*
Y877303D03*
Y867264D03*
Y870610D03*
Y883996D03*
Y890689D03*
Y897382D03*
Y904075D03*
Y907422D03*
Y914114D03*
Y920807D03*
Y927500D03*
Y934193D03*
Y940886D03*
Y950925D03*
Y944233D03*
Y964311D03*
Y957618D03*
Y971004D03*
Y977697D03*
Y984390D03*
Y1001122D03*
Y997776D03*
Y991083D03*
Y1031240D03*
Y1037933D03*
Y1044626D03*
Y1058012D03*
Y1051319D03*
Y1074744D03*
Y1081437D03*
Y1088130D03*
Y1098170D03*
Y1104862D03*
Y1091477D03*
Y1111555D03*
Y1118248D03*
Y1134981D03*
Y1124941D03*
Y1128288D03*
Y1148366D03*
Y1141674D03*
Y1155059D03*
Y1161752D03*
Y1165099D03*
Y1171792D03*
Y1178485D03*
Y1185177D03*
Y1191870D03*
Y1208603D03*
Y1198563D03*
Y1201910D03*
Y1215296D03*
Y1221988D03*
Y1228681D03*
Y1235374D03*
Y1238721D03*
Y1245414D03*
Y1252107D03*
X1659960Y1485895D03*
X1656560D03*
X1653260Y1495595D03*
X1649860D03*
X1675194Y26477D03*
X1671794D03*
X1668770Y69340D03*
X1672170D03*
X1669339Y776910D03*
Y783603D03*
Y790296D03*
Y800335D03*
Y807028D03*
Y793642D03*
Y813721D03*
Y820414D03*
Y837146D03*
Y830453D03*
Y827107D03*
Y843839D03*
Y850532D03*
Y857225D03*
Y863918D03*
Y873957D03*
Y880650D03*
Y867264D03*
Y887343D03*
Y894036D03*
Y910768D03*
Y904075D03*
Y900729D03*
Y924154D03*
Y917461D03*
Y930847D03*
Y940886D03*
Y937540D03*
Y947579D03*
Y954272D03*
Y967658D03*
Y974351D03*
Y981044D03*
Y987736D03*
Y994429D03*
Y1001122D03*
Y1027894D03*
Y1034587D03*
Y1041280D03*
Y1047973D03*
Y1054666D03*
Y1061359D03*
Y1071398D03*
Y1064705D03*
Y1078091D03*
Y1088130D03*
Y1084784D03*
Y1094823D03*
Y1101516D03*
Y1108209D03*
Y1114902D03*
Y1131634D03*
Y1124941D03*
Y1121595D03*
Y1138327D03*
Y1145020D03*
Y1151713D03*
Y1161752D03*
Y1158406D03*
Y1168445D03*
Y1175138D03*
Y1181831D03*
Y1188524D03*
Y1205256D03*
Y1198563D03*
Y1195217D03*
Y1211949D03*
Y1218642D03*
Y1225335D03*
Y1235374D03*
Y1232028D03*
Y1242067D03*
Y1248760D03*
X1673360Y1485895D03*
X1669960D03*
X1689367Y26477D03*
X1682299Y19541D03*
X1685967Y26477D03*
X1678899Y19541D03*
X1690900Y69343D03*
X1679904Y75340D03*
X1683304D03*
X1682898Y780256D03*
Y786949D03*
Y803681D03*
Y793642D03*
Y796988D03*
Y817067D03*
Y810374D03*
Y823760D03*
Y830453D03*
Y833799D03*
Y840492D03*
Y847185D03*
Y853878D03*
Y860571D03*
Y877303D03*
Y867264D03*
Y870610D03*
Y883996D03*
Y890689D03*
Y897382D03*
Y904075D03*
Y907422D03*
Y914114D03*
Y920807D03*
Y927500D03*
Y934193D03*
Y940886D03*
Y950925D03*
Y944233D03*
Y964311D03*
Y957618D03*
Y971004D03*
Y977697D03*
Y984390D03*
Y1001122D03*
Y997776D03*
Y991083D03*
Y1031240D03*
Y1037933D03*
Y1044626D03*
Y1058012D03*
Y1051319D03*
Y1074744D03*
Y1081437D03*
Y1088130D03*
Y1098170D03*
Y1104862D03*
Y1091477D03*
Y1111555D03*
Y1118248D03*
Y1134981D03*
Y1124941D03*
Y1128288D03*
Y1148366D03*
Y1141674D03*
Y1155059D03*
Y1161752D03*
Y1165099D03*
Y1171792D03*
Y1178485D03*
Y1185177D03*
Y1191870D03*
Y1208603D03*
Y1198563D03*
Y1201910D03*
Y1215296D03*
Y1221988D03*
Y1228681D03*
Y1235374D03*
Y1238721D03*
Y1245414D03*
Y1252107D03*
X1680730Y1517082D03*
Y1513682D03*
Y1530482D03*
Y1527082D03*
X1696472Y19541D03*
X1693072D03*
X1701904Y75340D03*
X1705304D03*
X1694300Y69343D03*
X1699040Y776910D03*
Y783603D03*
Y790296D03*
Y800335D03*
Y807028D03*
Y793642D03*
Y813721D03*
Y820414D03*
Y837146D03*
Y830453D03*
Y827107D03*
Y843839D03*
Y850532D03*
Y857225D03*
Y863918D03*
Y873957D03*
Y880650D03*
Y867264D03*
Y887343D03*
Y894036D03*
Y910768D03*
Y904075D03*
Y900729D03*
Y924154D03*
Y917461D03*
Y930847D03*
Y940886D03*
Y937540D03*
Y947579D03*
Y954272D03*
Y967658D03*
Y974351D03*
Y981044D03*
Y987736D03*
Y994429D03*
Y1001122D03*
Y1027894D03*
Y1034587D03*
Y1041280D03*
Y1047973D03*
Y1054666D03*
Y1061359D03*
Y1071398D03*
Y1064705D03*
Y1078091D03*
Y1088130D03*
Y1084784D03*
Y1094823D03*
Y1101516D03*
Y1108209D03*
Y1114902D03*
Y1131634D03*
Y1124941D03*
Y1121595D03*
Y1138327D03*
Y1145020D03*
Y1151713D03*
Y1161752D03*
Y1158406D03*
Y1168445D03*
Y1175138D03*
Y1181831D03*
Y1188524D03*
Y1205256D03*
Y1198563D03*
Y1195217D03*
Y1211949D03*
Y1218642D03*
Y1225335D03*
Y1235374D03*
Y1232028D03*
Y1242067D03*
Y1248760D03*
X1712599Y780256D03*
Y786949D03*
Y803681D03*
Y793642D03*
Y796988D03*
Y817067D03*
Y810374D03*
Y823760D03*
Y830453D03*
Y833799D03*
Y840492D03*
Y847185D03*
Y853878D03*
Y860571D03*
Y877303D03*
Y867264D03*
Y870610D03*
Y883996D03*
Y890689D03*
Y897382D03*
Y904075D03*
Y907422D03*
Y914114D03*
Y920807D03*
Y927500D03*
Y934193D03*
Y940886D03*
Y950925D03*
Y944233D03*
Y964311D03*
Y957618D03*
Y971004D03*
Y977697D03*
Y984390D03*
Y1001122D03*
Y997776D03*
Y991083D03*
Y1031240D03*
Y1037933D03*
Y1044626D03*
Y1058012D03*
Y1051319D03*
Y1074744D03*
Y1081437D03*
Y1088130D03*
Y1098170D03*
Y1104862D03*
Y1091477D03*
Y1111555D03*
Y1118248D03*
Y1134981D03*
Y1124941D03*
Y1128288D03*
Y1148366D03*
Y1141674D03*
Y1155059D03*
Y1161752D03*
Y1165099D03*
Y1171792D03*
Y1178485D03*
Y1185177D03*
Y1191870D03*
Y1208603D03*
Y1198563D03*
Y1201910D03*
Y1215296D03*
Y1221988D03*
Y1228681D03*
Y1235374D03*
Y1238721D03*
Y1245414D03*
Y1252107D03*
X1729557Y-22512D03*
Y-25912D03*
X1728741Y776910D03*
Y783603D03*
Y790296D03*
Y800335D03*
Y807028D03*
Y793642D03*
Y813721D03*
Y820414D03*
Y837146D03*
Y830453D03*
Y827107D03*
Y843839D03*
Y850532D03*
Y857225D03*
Y863918D03*
Y873957D03*
Y880650D03*
Y867264D03*
Y887343D03*
Y894036D03*
Y910768D03*
Y904075D03*
Y900729D03*
Y924154D03*
Y917461D03*
Y930847D03*
Y940886D03*
Y937540D03*
Y947579D03*
Y954272D03*
Y967658D03*
Y974351D03*
Y981044D03*
Y987736D03*
Y994429D03*
Y1001122D03*
Y1027894D03*
Y1034587D03*
Y1041280D03*
Y1047973D03*
Y1054666D03*
Y1061359D03*
Y1071398D03*
Y1064705D03*
Y1078091D03*
Y1088130D03*
Y1084784D03*
Y1094823D03*
Y1101516D03*
Y1108209D03*
Y1114902D03*
Y1131634D03*
Y1124941D03*
Y1121595D03*
Y1138327D03*
Y1145020D03*
Y1151713D03*
Y1161752D03*
Y1158406D03*
Y1168445D03*
Y1175138D03*
Y1181831D03*
Y1188524D03*
Y1205256D03*
Y1198563D03*
Y1195217D03*
Y1211949D03*
Y1218642D03*
Y1225335D03*
Y1235374D03*
Y1232028D03*
Y1242067D03*
Y1248760D03*
X1742300Y780256D03*
Y786949D03*
Y803681D03*
Y793642D03*
Y796988D03*
Y817067D03*
Y810374D03*
Y823760D03*
Y830453D03*
Y833799D03*
Y840492D03*
Y847185D03*
Y853878D03*
Y860571D03*
Y877303D03*
Y867264D03*
Y870610D03*
Y883996D03*
Y890689D03*
Y897382D03*
Y904075D03*
Y907422D03*
Y914114D03*
Y920807D03*
Y927500D03*
Y934193D03*
Y940886D03*
Y950925D03*
Y944233D03*
Y964311D03*
Y957618D03*
Y971004D03*
Y977697D03*
Y984390D03*
Y1001122D03*
Y997776D03*
Y991083D03*
Y1031240D03*
Y1037933D03*
Y1044626D03*
Y1058012D03*
Y1051319D03*
Y1074744D03*
Y1081437D03*
Y1088130D03*
Y1098170D03*
Y1104862D03*
Y1091477D03*
Y1111555D03*
Y1118248D03*
Y1134981D03*
Y1124941D03*
Y1128288D03*
Y1148366D03*
Y1141674D03*
Y1155059D03*
Y1161752D03*
Y1165099D03*
Y1171792D03*
Y1178485D03*
Y1185177D03*
Y1191870D03*
Y1208603D03*
Y1198563D03*
Y1201910D03*
Y1215296D03*
Y1221988D03*
Y1228681D03*
Y1235374D03*
Y1238721D03*
Y1245414D03*
Y1252107D03*
X1758442Y776910D03*
Y783603D03*
Y790296D03*
Y800335D03*
Y807028D03*
Y793642D03*
Y813721D03*
Y820414D03*
Y837146D03*
Y830453D03*
Y827107D03*
Y843839D03*
Y850532D03*
Y857225D03*
Y863918D03*
Y873957D03*
Y880650D03*
Y867264D03*
Y887343D03*
Y894036D03*
Y910768D03*
Y904075D03*
Y900729D03*
Y924154D03*
Y917461D03*
Y930847D03*
Y940886D03*
Y937540D03*
Y947579D03*
Y954272D03*
Y967658D03*
Y974351D03*
Y981044D03*
Y987736D03*
Y994429D03*
Y1001122D03*
Y1027894D03*
Y1034587D03*
Y1041280D03*
Y1047973D03*
Y1054666D03*
Y1061359D03*
Y1071398D03*
Y1064705D03*
Y1078091D03*
Y1088130D03*
Y1084784D03*
Y1094823D03*
Y1101516D03*
Y1108209D03*
Y1114902D03*
Y1131634D03*
Y1124941D03*
Y1121595D03*
Y1138327D03*
Y1145020D03*
Y1151713D03*
Y1161752D03*
Y1158406D03*
Y1168445D03*
Y1175138D03*
Y1181831D03*
Y1188524D03*
Y1205256D03*
Y1198563D03*
Y1195217D03*
Y1211949D03*
Y1218642D03*
Y1225335D03*
Y1235374D03*
Y1232028D03*
Y1242067D03*
Y1248760D03*
X1772000Y780256D03*
Y786949D03*
Y803681D03*
Y793642D03*
Y796988D03*
Y817067D03*
Y810374D03*
Y823760D03*
Y830453D03*
Y833799D03*
Y840492D03*
Y847185D03*
Y853878D03*
Y860571D03*
Y877303D03*
Y867264D03*
Y870610D03*
Y883996D03*
Y890689D03*
Y897382D03*
Y904075D03*
Y907422D03*
Y914114D03*
Y920807D03*
Y927500D03*
Y934193D03*
Y940886D03*
Y950925D03*
Y944233D03*
Y964311D03*
Y957618D03*
Y971004D03*
Y977697D03*
Y984390D03*
Y1001122D03*
Y997776D03*
Y991083D03*
Y1031240D03*
Y1037933D03*
Y1044626D03*
Y1058012D03*
Y1051319D03*
Y1074744D03*
Y1081437D03*
Y1088130D03*
Y1098170D03*
Y1104862D03*
Y1091477D03*
Y1111555D03*
Y1118248D03*
Y1134981D03*
Y1124941D03*
Y1128288D03*
Y1148366D03*
Y1141674D03*
Y1155059D03*
Y1161752D03*
Y1165099D03*
Y1171792D03*
Y1178485D03*
Y1185177D03*
Y1191870D03*
Y1208603D03*
Y1198563D03*
Y1201910D03*
Y1215296D03*
Y1221988D03*
Y1228681D03*
Y1235374D03*
Y1238721D03*
Y1245414D03*
Y1252107D03*
X1788142Y776910D03*
Y783603D03*
Y790296D03*
Y800335D03*
Y807028D03*
Y793642D03*
Y813721D03*
Y820414D03*
Y837146D03*
Y830453D03*
Y827107D03*
Y843839D03*
Y850532D03*
Y857225D03*
Y863918D03*
Y873957D03*
Y880650D03*
Y867264D03*
Y887343D03*
Y894036D03*
Y910768D03*
Y904075D03*
Y900729D03*
Y924154D03*
Y917461D03*
Y930847D03*
Y940886D03*
Y937540D03*
Y947579D03*
Y954272D03*
Y967658D03*
Y974351D03*
Y981044D03*
Y987736D03*
Y994429D03*
Y1001122D03*
Y1027894D03*
Y1034587D03*
Y1041280D03*
Y1047973D03*
Y1054666D03*
Y1061359D03*
Y1071398D03*
Y1064705D03*
Y1078091D03*
Y1088130D03*
Y1084784D03*
Y1094823D03*
Y1101516D03*
Y1108209D03*
Y1114902D03*
Y1131634D03*
Y1124941D03*
Y1121595D03*
Y1138327D03*
Y1145020D03*
Y1151713D03*
Y1161752D03*
Y1158406D03*
Y1168445D03*
Y1175138D03*
Y1181831D03*
Y1188524D03*
Y1205256D03*
Y1198563D03*
Y1195217D03*
Y1211949D03*
Y1218642D03*
Y1225335D03*
Y1235374D03*
Y1232028D03*
Y1242067D03*
Y1248760D03*
G54D22*
X60303Y20354D03*
X312921Y24291D03*
X505185Y41141D03*
X757803Y45078D03*
X929331Y160413D03*
X922441Y237697D03*
X1534712Y20354D03*
X1787330Y24291D03*
G54D32*
X205478Y1536063D03*
X210202D03*
X219651D03*
X229100D03*
X233824D03*
X243273D03*
X253002Y1514243D03*
X252722Y1536063D03*
X302413Y906182D03*
Y912560D03*
Y918938D03*
Y925316D03*
Y931694D03*
Y938072D03*
Y944450D03*
Y950828D03*
Y957206D03*
Y963584D03*
Y969962D03*
Y976340D03*
Y982718D03*
Y989096D03*
Y995474D03*
Y1008230D03*
Y1001852D03*
X303594Y1030198D03*
Y1036576D03*
Y1042954D03*
Y1055710D03*
Y1049332D03*
Y1062088D03*
Y1074844D03*
Y1068466D03*
Y1081222D03*
Y1087600D03*
Y1093978D03*
Y1100356D03*
Y1106734D03*
Y1113112D03*
Y1119490D03*
Y1125868D03*
Y1132246D03*
Y1138623D03*
Y1145001D03*
Y1157757D03*
Y1151379D03*
X333540Y1536063D03*
X338264D03*
X347713D03*
X357162D03*
X361886D03*
X380784D03*
X371335D03*
X381064Y1514243D03*
X408614Y997608D03*
X410464Y1007175D03*
X404923Y1010366D03*
X423417Y997608D03*
X416015D03*
X430819D03*
X445622D03*
X453023D03*
X467826D03*
X460425D03*
X469651Y1536063D03*
X483824D03*
X474375D03*
X497997D03*
X493273D03*
X507446D03*
X526370Y1165290D03*
X515268D03*
X518969D03*
X522670D03*
X517175Y1514243D03*
X516895Y1536063D03*
X533772Y1165290D03*
X530071D03*
X602437Y1536063D03*
X597713D03*
X611886D03*
X626059D03*
X621335D03*
X645237Y1514243D03*
X644957Y1536063D03*
X635508D03*
X1213351Y1569063D03*
X1227524D03*
X1218075D03*
X1241697D03*
X1236973D03*
X1251146D03*
X1260875Y1547243D03*
X1260595Y1569063D03*
X1278555Y906181D03*
Y912559D03*
Y918937D03*
Y925315D03*
Y931693D03*
Y938071D03*
Y950827D03*
Y944449D03*
Y957205D03*
Y963583D03*
Y969961D03*
Y976339D03*
Y982717D03*
Y995473D03*
Y989095D03*
Y1008229D03*
Y1001851D03*
X1279736Y1030197D03*
Y1042953D03*
Y1036575D03*
Y1055709D03*
Y1049331D03*
Y1062087D03*
Y1068465D03*
Y1074843D03*
Y1081221D03*
Y1087599D03*
Y1093977D03*
Y1100355D03*
Y1106733D03*
Y1113111D03*
Y1119489D03*
Y1125867D03*
Y1132245D03*
Y1138622D03*
Y1145000D03*
Y1151378D03*
Y1157756D03*
X1346137Y1569063D03*
X1341413D03*
X1355586D03*
X1379208D03*
X1369759D03*
X1365035D03*
X1384756Y997607D03*
X1392157D03*
X1386606Y1007174D03*
X1381065Y1010365D03*
X1388937Y1547243D03*
X1388657Y1569063D03*
X1406961Y997607D03*
X1399559D03*
X1421764D03*
X1436567D03*
X1429165D03*
X1443968D03*
X1482249Y1569063D03*
X1477525D03*
X1491698D03*
X1502512Y1165289D03*
X1505871Y1569063D03*
X1501147D03*
X1525049Y1547243D03*
X1524769Y1569063D03*
X1515320D03*
X1610311D03*
X1605587D03*
X1629209D03*
X1619760D03*
X1643382D03*
X1633933D03*
X1653111Y1547243D03*
X1652831Y1569063D03*
G54D44*
X381770Y-30570D03*
X385023Y-30584D03*
X388048Y-29264D03*
X381755Y-28055D03*
X385008Y-28069D03*
X381740Y-25540D03*
X381725Y-23025D03*
X723479Y-19234D03*
Y-9234D03*
X833421Y-36647D03*
X839699Y-35341D03*
X833406Y-34132D03*
X836674Y-36661D03*
X836659Y-34146D03*
X833391Y-31617D03*
X833376Y-29102D03*
X836644Y-31631D03*
X836629Y-29116D03*
X1174958Y-15374D03*
Y-5374D03*
Y24626D03*
X1433817Y-25374D03*
Y-15374D03*
Y14626D03*
X1530063Y-40911D03*
X1530033Y-35881D03*
X1530018Y-33366D03*
X1530048Y-38396D03*
X1533316Y-40925D03*
X1536341Y-39605D03*
X1533301Y-38410D03*
X1727111Y-19575D03*
G54D82*
X1898799Y1198198D03*
X1908799D03*
X1921395Y-39963D03*
X1931395D03*
X1942395Y572417D03*
X1940886Y1198170D03*
X1963362Y-39821D03*
X1952395Y572417D03*
X1950886Y1198170D03*
X1973362Y-39821D03*
X1984482Y572389D03*
X1982856Y1198350D03*
X1992856D03*
X2005452Y-39811D03*
X1994482Y572389D03*
X2015452Y-39811D03*
X2026452Y572569D03*
X2036452D03*
X2047419Y-39669D03*
X2057419D03*
X2068539Y572541D03*
X2078539D03*
G54D48*
X539016Y274272D03*
X559016D03*
X569016D03*
X579016D03*
X589016D03*
X599016D03*
X609016D03*
G54D62*
X918780Y1684890D03*
Y1694890D03*
Y1714890D03*
X928780Y1684890D03*
Y1694890D03*
Y1704890D03*
Y1714890D03*
X938780Y1684890D03*
Y1694890D03*
Y1704890D03*
Y1714890D03*
G54D67*
X1225530Y67471D03*
X1454797Y80345D03*
G54D80*
X1900275Y-29973D03*
Y562227D03*
X1898799Y1208198D03*
Y1800398D03*
X1910275Y-29973D03*
Y562227D03*
X1908799Y1208198D03*
Y1800398D03*
X1921395Y-29963D03*
X1931395D03*
Y562237D03*
X1921395D03*
X1931395Y582237D03*
X1921395D03*
Y1174437D03*
X1931395D03*
X1929766Y1208160D03*
X1919766D03*
Y1800360D03*
X1929766D03*
X1942395Y-29783D03*
Y562417D03*
Y582417D03*
Y1174617D03*
X1940886Y1208170D03*
Y1800370D03*
X1952395Y-29783D03*
Y562417D03*
Y582417D03*
Y1174617D03*
X1950886Y1208170D03*
X1961856D03*
X1950886Y1800370D03*
X1961856D03*
X1963362Y-29821D03*
X1973362D03*
Y562379D03*
X1963362D03*
X1973362Y582379D03*
X1963362D03*
Y1174579D03*
X1973362D03*
X1971856Y1208170D03*
Y1800370D03*
X1984482Y-29811D03*
Y562389D03*
Y582389D03*
Y1174589D03*
X1982856Y1208350D03*
Y1800550D03*
X1994482Y-29811D03*
X2005452D03*
X1994482Y562389D03*
X2005452D03*
Y582389D03*
X1994482D03*
Y1174589D03*
X2005452D03*
X1992856Y1208350D03*
X2003823Y1208312D03*
X1992856Y1800550D03*
X2003823Y1800512D03*
X2015452Y-29811D03*
Y562389D03*
Y582389D03*
Y1174589D03*
X2013823Y1208312D03*
Y1800512D03*
X2036452Y-29631D03*
X2026452D03*
Y562569D03*
X2036452D03*
X2026452Y582569D03*
X2036452D03*
Y1174769D03*
X2026452D03*
X2047419Y-29669D03*
Y562531D03*
Y582531D03*
Y1174731D03*
X2057419Y-29669D03*
Y562531D03*
Y582531D03*
Y1174731D03*
X2068539Y582541D03*
X2078539D03*
Y1174741D03*
X2068539D03*
G54D81*
X1900275Y572227D03*
X1910275D03*
X1921395Y1184437D03*
X1931395D03*
X1919766Y1810360D03*
X1929766D03*
X1942395Y572417D03*
X1952395D03*
X1963362Y1184579D03*
X1961856Y1810370D03*
X1973362Y1184579D03*
X1971856Y1810370D03*
X1984482Y572389D03*
X1994482D03*
X2005452Y1184589D03*
X2003823Y1810512D03*
X2015452Y1184589D03*
X2013823Y1810512D03*
X2026452Y572569D03*
X2036452D03*
X2047419Y1184731D03*
X2057419D03*
G54D51*
X676509Y224606D03*
G54D31*
X188155Y1516970D03*
X192879D03*
X197604D03*
X189730Y1519698D03*
X194454D03*
X199178D03*
X188155Y1530608D03*
X192879D03*
X197604D03*
X189730Y1533336D03*
X194454D03*
X199178D03*
X202328Y1516970D03*
X207052D03*
X211777D03*
X216501D03*
X203903Y1519698D03*
X208627D03*
X213352D03*
X202328Y1530608D03*
X207052D03*
X211777D03*
X216501D03*
X203903Y1533336D03*
X208627D03*
X213352D03*
X221226Y1516970D03*
X218076Y1519698D03*
X222800D03*
X221226Y1530608D03*
X225950D03*
X230674D03*
X218076Y1533336D03*
X222800D03*
X227525D03*
X235399Y1530608D03*
X240123D03*
X244848D03*
X236974Y1533336D03*
X241698D03*
X246422D03*
X232249D03*
X249572Y1530608D03*
X254297D03*
X259021D03*
X251147Y1533336D03*
X255871D03*
X260596D03*
X317957Y886002D03*
X319807Y889191D03*
Y895569D03*
X317957Y892380D03*
X319807Y908325D03*
X317957Y898758D03*
X319807Y901947D03*
X317957Y905135D03*
Y911513D03*
Y917891D03*
X319807Y921080D03*
X317957Y924269D03*
X319807Y914702D03*
Y927458D03*
X317957Y937025D03*
X319807Y940214D03*
Y933836D03*
X317957Y930647D03*
Y943403D03*
X319807Y946592D03*
X317957Y956159D03*
X319807Y952970D03*
X317957Y949781D03*
Y962537D03*
X319807Y965726D03*
Y959348D03*
X317957Y968915D03*
Y975293D03*
X319807Y978482D03*
Y972104D03*
X317957Y994427D03*
X319807Y997616D03*
X317957Y1000805D03*
X319807Y991238D03*
Y1010372D03*
X317957Y1007183D03*
X319807Y1003994D03*
X320988Y1034434D03*
X319138Y1037623D03*
X320988Y1040812D03*
X319138Y1044001D03*
X320988Y1059946D03*
X319138Y1050379D03*
X320988Y1053568D03*
Y1072702D03*
X319138Y1063135D03*
Y1069513D03*
X320988Y1066324D03*
X319138Y1075891D03*
X320988Y1079080D03*
X319138Y1082269D03*
Y1088647D03*
X320988Y1085458D03*
X319138Y1101403D03*
X320988Y1091836D03*
X319138Y1095025D03*
X320988Y1098214D03*
Y1104592D03*
Y1110970D03*
X319138Y1114159D03*
X320988Y1117348D03*
X319138Y1107781D03*
Y1120537D03*
X320988Y1130103D03*
X319138Y1133293D03*
Y1126915D03*
X320988Y1123726D03*
Y1136481D03*
X319138Y1139670D03*
X320988Y1149237D03*
X319138Y1146048D03*
X320988Y1142859D03*
X319138Y1152426D03*
X316217Y1516970D03*
X320941D03*
X317792Y1519698D03*
X316217Y1530608D03*
X320941D03*
X317792Y1533336D03*
X323508Y889191D03*
X325358Y892380D03*
X323508Y895569D03*
X332760Y886002D03*
X330910Y889191D03*
Y895569D03*
X332760Y892380D03*
X325358Y911513D03*
X323508Y901947D03*
X325358Y905135D03*
X323508Y908325D03*
X325358Y898758D03*
X330910Y908325D03*
X332760Y898758D03*
X330910Y901947D03*
X332760Y905135D03*
Y911513D03*
X323508Y921080D03*
X325358Y924269D03*
X323508Y914702D03*
X325358Y917891D03*
X332760D03*
X330910Y921080D03*
X332760Y924269D03*
X330910Y914702D03*
X323508Y927458D03*
X325358Y930647D03*
X323508Y940214D03*
Y933836D03*
X325358Y937025D03*
X330910Y927458D03*
X332760Y937025D03*
X330910Y940214D03*
Y933836D03*
X332760Y930647D03*
X325358Y943403D03*
X323508Y946592D03*
X325358Y949781D03*
X323508Y952970D03*
X325358Y956159D03*
X332760Y943403D03*
X330910Y946592D03*
X332760Y956159D03*
X330910Y952970D03*
X332760Y949781D03*
X323508Y965726D03*
X325358Y968915D03*
X323508Y959348D03*
X325358Y962537D03*
X332760D03*
X330910Y965726D03*
Y959348D03*
X332760Y968915D03*
X323508Y984860D03*
Y978482D03*
X325358Y981671D03*
X323508Y972104D03*
X325358Y975293D03*
X332760D03*
X330910Y978482D03*
Y972104D03*
X325358Y988049D03*
X323508Y997616D03*
X325358Y1000805D03*
Y994427D03*
X332760D03*
X330910Y997616D03*
X332760Y1000805D03*
X330910Y991238D03*
X323508Y1003994D03*
X325358Y1007183D03*
X330910Y1010372D03*
X332760Y1007183D03*
X330910Y1003994D03*
X326539Y1031245D03*
X324689Y1034434D03*
X326539Y1037623D03*
X324689Y1040812D03*
X332091Y1034434D03*
X333941Y1037623D03*
X332091Y1040812D03*
X333941Y1044001D03*
X326539Y1050379D03*
X324689Y1047190D03*
X332091Y1059946D03*
X333941Y1050379D03*
X332091Y1053568D03*
X326539Y1063135D03*
X324689Y1066324D03*
X326539Y1069513D03*
X324689Y1072702D03*
X332091D03*
X333941Y1063135D03*
Y1069513D03*
X332091Y1066324D03*
X326539Y1075891D03*
X324689Y1079080D03*
X326539Y1082269D03*
X324689Y1085458D03*
X326539Y1088647D03*
X333941Y1075891D03*
X332091Y1079080D03*
X333941Y1082269D03*
Y1088647D03*
X332091Y1085458D03*
X324689Y1104592D03*
X326539Y1095025D03*
X324689Y1098214D03*
X326539Y1101403D03*
X324689Y1091836D03*
X333941Y1101403D03*
X332091Y1091836D03*
X333941Y1095025D03*
X332091Y1098214D03*
Y1104592D03*
X326539Y1114159D03*
X324689Y1117348D03*
X326539Y1107781D03*
X324689Y1110970D03*
X332091D03*
X333941Y1114159D03*
X332091Y1117348D03*
X333941Y1107781D03*
X326539Y1120537D03*
X324689Y1123726D03*
X326539Y1133293D03*
Y1126915D03*
X324689Y1130103D03*
X333941Y1120537D03*
X332091Y1130103D03*
X333941Y1133293D03*
Y1126915D03*
X332091Y1123726D03*
X324689Y1136481D03*
X326539Y1139670D03*
X324689Y1142859D03*
X326539Y1146048D03*
X324689Y1149237D03*
X332091Y1136481D03*
X333941Y1139670D03*
X332091Y1149237D03*
X333941Y1146048D03*
X332091Y1142859D03*
X326539Y1152426D03*
X324689Y1155615D03*
X333941Y1152426D03*
X332091Y1155615D03*
X325666Y1516970D03*
X330390D03*
X335114D03*
X322516Y1519698D03*
X327240D03*
X331965D03*
X325666Y1530608D03*
X330390D03*
X335114D03*
X322516Y1533336D03*
X327240D03*
X331965D03*
X343862Y886002D03*
X349414Y889191D03*
X345713D03*
Y895569D03*
X349414D03*
X343862Y892380D03*
X338311Y889191D03*
X336461Y892380D03*
X338311Y895569D03*
X345713Y908325D03*
X343862Y898758D03*
X349414Y901947D03*
X345713D03*
X343862Y905135D03*
X349414Y908325D03*
X343862Y911513D03*
X336461D03*
X338311Y901947D03*
X336461Y905135D03*
X338311Y908325D03*
X336461Y898758D03*
X343862Y917891D03*
X349414Y921080D03*
X345713D03*
X343862Y924269D03*
X345713Y914702D03*
X349414D03*
X338311Y921080D03*
X336461Y924269D03*
X338311Y914702D03*
X336461Y917891D03*
X349414Y927458D03*
X345713D03*
X343862Y937025D03*
X349414Y940214D03*
X345713D03*
Y933836D03*
X349414D03*
X343862Y930647D03*
X338311Y927458D03*
X336461Y930647D03*
X338311Y940214D03*
Y933836D03*
X336461Y937025D03*
X343862Y943403D03*
X349414Y946592D03*
X345713D03*
X343862Y956159D03*
X345713Y952970D03*
X349414D03*
X343862Y949781D03*
X336461Y943403D03*
X338311Y946592D03*
X336461Y949781D03*
X338311Y952970D03*
X336461Y956159D03*
X343862Y962537D03*
X349414Y965726D03*
X345713D03*
X349414Y959348D03*
X345713D03*
X343862Y968915D03*
X338311Y965726D03*
X336461Y968915D03*
X338311Y959348D03*
X336461Y962537D03*
X349414Y984860D03*
X343862Y975293D03*
X349414Y978482D03*
X345713D03*
Y972104D03*
X349414D03*
X338311Y984860D03*
Y978482D03*
X336461Y981671D03*
X338311Y972104D03*
X336461Y975293D03*
X343862Y994427D03*
X345713Y997616D03*
X349414D03*
X343862Y1000805D03*
X345713Y991238D03*
X336461Y988049D03*
X338311Y997616D03*
X336461Y1000805D03*
Y994427D03*
X345713Y1010372D03*
X343862Y1007183D03*
X345713Y1003994D03*
X349414D03*
X338311D03*
X336461Y1007183D03*
X350595Y1034434D03*
X346894D03*
X345043Y1037623D03*
X350595Y1040812D03*
X346894D03*
X345043Y1044001D03*
X337642Y1031245D03*
X339492Y1034434D03*
X337642Y1037623D03*
X339492Y1040812D03*
X346894Y1059946D03*
X350595Y1047190D03*
X345043Y1050379D03*
X346894Y1053568D03*
X337642Y1050379D03*
X339492Y1047190D03*
X346894Y1072702D03*
X345043Y1063135D03*
X350595Y1066324D03*
X345043Y1069513D03*
X350595Y1072702D03*
X346894Y1066324D03*
X337642Y1063135D03*
X339492Y1066324D03*
X337642Y1069513D03*
X339492Y1072702D03*
X345043Y1075891D03*
X350595Y1079080D03*
X346894D03*
X345043Y1082269D03*
X350595Y1085458D03*
X345043Y1088647D03*
X346894Y1085458D03*
X337642Y1075891D03*
X339492Y1079080D03*
X337642Y1082269D03*
X339492Y1085458D03*
X337642Y1088647D03*
X345043Y1101403D03*
X350595Y1104592D03*
X346894Y1091836D03*
X345043Y1095025D03*
X350595Y1098214D03*
X346894D03*
Y1104592D03*
X350595Y1091836D03*
X339492Y1104592D03*
X337642Y1095025D03*
X339492Y1098214D03*
X337642Y1101403D03*
X339492Y1091836D03*
X346894Y1110970D03*
X345043Y1114159D03*
X350595Y1117348D03*
X346894D03*
X345043Y1107781D03*
X350595Y1110970D03*
X337642Y1114159D03*
X339492Y1117348D03*
X337642Y1107781D03*
X339492Y1110970D03*
X345043Y1120537D03*
X350595Y1123726D03*
X346894Y1130103D03*
X345043Y1133293D03*
Y1126915D03*
X346894Y1123726D03*
X350595Y1130103D03*
X337642Y1120537D03*
X339492Y1123726D03*
X337642Y1133293D03*
Y1126915D03*
X339492Y1130103D03*
X350595Y1136481D03*
X346894D03*
X345043Y1139670D03*
X350595Y1142859D03*
X346894Y1149237D03*
X345043Y1146048D03*
X346894Y1142859D03*
X350595Y1149237D03*
X339492Y1136481D03*
X337642Y1139670D03*
X339492Y1142859D03*
X337642Y1146048D03*
X339492Y1149237D03*
X345043Y1152426D03*
X350595Y1155615D03*
X337642Y1152426D03*
X339839Y1516970D03*
X344563D03*
X349288D03*
X336689Y1519698D03*
X341414D03*
X346138D03*
X350862D03*
X339839Y1530608D03*
X344563D03*
X349288D03*
X336689Y1533336D03*
X341414D03*
X346138D03*
X350862D03*
X351264Y892380D03*
X358665Y886002D03*
X364217Y889191D03*
X356815D03*
X362366Y892380D03*
X356815Y895569D03*
X364217D03*
X358665Y892380D03*
X351264Y911513D03*
Y905135D03*
Y898758D03*
X356815Y908325D03*
X362366Y911513D03*
X358665Y898758D03*
X364217Y901947D03*
X356815D03*
X362366Y905135D03*
X358665D03*
X364217Y908325D03*
X358665Y911513D03*
X362366Y898758D03*
X351264Y924269D03*
Y917891D03*
X358665D03*
X364217Y921080D03*
X356815D03*
X362366Y924269D03*
X358665D03*
X356815Y914702D03*
X364217D03*
X362366Y917891D03*
X351264Y930647D03*
Y937025D03*
X364217Y927458D03*
X356815D03*
X362366Y930647D03*
X358665Y937025D03*
X364217Y940214D03*
X356815D03*
Y933836D03*
X364217D03*
X358665Y930647D03*
X362366Y937025D03*
X351264Y943403D03*
Y949781D03*
Y956159D03*
X362366Y943403D03*
X358665D03*
X364217Y946592D03*
X356815D03*
X362366Y949781D03*
X358665Y956159D03*
X356815Y952970D03*
X364217D03*
X358665Y949781D03*
X362366Y956159D03*
X351264Y968915D03*
Y962537D03*
X358665D03*
X364217Y965726D03*
X356815D03*
X362366Y968915D03*
X364217Y959348D03*
X356815D03*
X362366Y962537D03*
X358665Y968915D03*
X351264Y981671D03*
Y975293D03*
X364217Y984860D03*
X358665Y975293D03*
X364217Y978482D03*
X356815D03*
X362366Y981671D03*
X356815Y972104D03*
X364217D03*
X362366Y975293D03*
X351264Y988049D03*
Y1000805D03*
Y994427D03*
X362366Y988049D03*
X358665Y994427D03*
X356815Y997616D03*
X364217D03*
X362366Y1000805D03*
X358665D03*
X356815Y991238D03*
X362366Y994427D03*
X351264Y1007183D03*
X356815Y1010372D03*
X358665Y1007183D03*
X356815Y1003994D03*
X364217D03*
X362366Y1007183D03*
X352445Y1031245D03*
Y1037623D03*
X363547Y1031245D03*
X365398Y1034434D03*
X357996D03*
X359847Y1037623D03*
X363547D03*
X365398Y1040812D03*
X357996D03*
X359847Y1044001D03*
X352445Y1050379D03*
X363547D03*
X357996Y1059946D03*
X365398Y1047190D03*
X359847Y1050379D03*
X357996Y1053568D03*
X352445Y1063135D03*
Y1069513D03*
X357996Y1072702D03*
X363547Y1063135D03*
X359847D03*
X365398Y1066324D03*
X363547Y1069513D03*
X359847D03*
X365398Y1072702D03*
X357996Y1066324D03*
X352445Y1075891D03*
Y1082269D03*
Y1088647D03*
X363547Y1075891D03*
X359847D03*
X365398Y1079080D03*
X357996D03*
X363547Y1082269D03*
X359847D03*
X365398Y1085458D03*
X359847Y1088647D03*
X363547D03*
X357996Y1085458D03*
X352445Y1095025D03*
Y1101403D03*
X359847D03*
X365398Y1104592D03*
X357996Y1091836D03*
X363547Y1095025D03*
X359847D03*
X365398Y1098214D03*
X357996D03*
X363547Y1101403D03*
X357996Y1104592D03*
X365398Y1091836D03*
X352445Y1114159D03*
Y1107781D03*
X357996Y1110970D03*
X363547Y1114159D03*
X359847D03*
X365398Y1117348D03*
X357996D03*
X359847Y1107781D03*
X363547D03*
X365398Y1110970D03*
X352445Y1120537D03*
Y1133293D03*
Y1126915D03*
X363547Y1120537D03*
X359847D03*
X365398Y1123726D03*
X357996Y1130103D03*
X363547Y1133293D03*
X359847D03*
Y1126915D03*
X363547D03*
X357996Y1123726D03*
X365398Y1130103D03*
X352445Y1139670D03*
Y1146048D03*
X365398Y1136481D03*
X357996D03*
X363547Y1139670D03*
X359847D03*
X365398Y1142859D03*
X357996Y1149237D03*
X359847Y1146048D03*
X363547D03*
X357996Y1142859D03*
X365398Y1149237D03*
X352445Y1152426D03*
X363547D03*
X359847D03*
X357996Y1155615D03*
X363461Y1516970D03*
X354012D03*
X358736D03*
X365036Y1519698D03*
X355587D03*
X360311D03*
X363461Y1530608D03*
X354012D03*
X358736D03*
X365036Y1533336D03*
X355587D03*
X360311D03*
X369768Y886002D03*
X375319Y889191D03*
X371618D03*
X377169Y892380D03*
X371618Y895569D03*
X375319D03*
X369768Y892380D03*
X371618Y908325D03*
X377169Y911513D03*
X369768Y898758D03*
X375319Y901947D03*
X371618D03*
X377169Y905135D03*
X369768D03*
X375319Y908325D03*
X369768Y911513D03*
X377169Y898758D03*
X369768Y917891D03*
X375319Y921080D03*
X371618D03*
X377169Y924269D03*
X369768D03*
X371618Y914702D03*
X375319D03*
X377169Y917891D03*
X375319Y927458D03*
X371618D03*
X377169Y930647D03*
X369768Y937025D03*
X375319Y940214D03*
X371618D03*
Y933836D03*
X375319D03*
X369768Y930647D03*
X377169Y937025D03*
Y943403D03*
X369768D03*
X375319Y946592D03*
X371618D03*
X377169Y949781D03*
X369768Y956159D03*
X371618Y952970D03*
X375319D03*
X369768Y949781D03*
X377169Y956159D03*
X369768Y962537D03*
X375319Y965726D03*
X371618D03*
X377169Y968915D03*
X375319Y959348D03*
X371618D03*
X377169Y962537D03*
X369768Y968915D03*
X375319Y984860D03*
X369768Y975293D03*
X375319Y978482D03*
X371618D03*
X377169Y981671D03*
X371618Y972104D03*
X375319D03*
X377169Y975293D03*
Y988049D03*
X369768Y994427D03*
X371618Y997616D03*
X375319D03*
X377169Y1000805D03*
X369768D03*
X371618Y991238D03*
X377169Y994427D03*
X371618Y1010372D03*
X369768Y1007183D03*
X371618Y1003994D03*
X375319D03*
X377169Y1007183D03*
X378351Y1031245D03*
X376500Y1034434D03*
X372799D03*
X370949Y1037623D03*
X378351D03*
X376500Y1040812D03*
X372799D03*
X370949Y1044001D03*
X378351Y1050379D03*
X372799Y1059946D03*
X376500Y1047190D03*
X370949Y1050379D03*
X372799Y1053568D03*
Y1072702D03*
X378351Y1063135D03*
X370949D03*
X376500Y1066324D03*
X378351Y1069513D03*
X370949D03*
X376500Y1072702D03*
X372799Y1066324D03*
X378351Y1075891D03*
X370949D03*
X376500Y1079080D03*
X372799D03*
X378351Y1082269D03*
X370949D03*
X376500Y1085458D03*
X370949Y1088647D03*
X378351D03*
X372799Y1085458D03*
X370949Y1101403D03*
X376500Y1104592D03*
X372799Y1091836D03*
X378351Y1095025D03*
X370949D03*
X376500Y1098214D03*
X372799D03*
X378351Y1101403D03*
X372799Y1104592D03*
X376500Y1091836D03*
X372799Y1110970D03*
X378351Y1114159D03*
X370949D03*
X376500Y1117348D03*
X372799D03*
X370949Y1107781D03*
X378351D03*
X376500Y1110970D03*
X378351Y1120537D03*
X370949D03*
X376500Y1123726D03*
X372799Y1130103D03*
X378351Y1133293D03*
X370949D03*
Y1126915D03*
X378351D03*
X372799Y1123726D03*
X376500Y1130103D03*
Y1136481D03*
X372799D03*
X378351Y1139670D03*
X370949D03*
X376500Y1142859D03*
X372799Y1149237D03*
X370949Y1146048D03*
X378351D03*
X372799Y1142859D03*
X376500Y1149237D03*
X378351Y1152426D03*
X370949D03*
X376500Y1155615D03*
X368185Y1516970D03*
X372910D03*
X377634D03*
X369760Y1519698D03*
X374484D03*
X379209D03*
X368185Y1530608D03*
X372910D03*
X377634D03*
X369760Y1533336D03*
X374484D03*
X379209D03*
X388272Y892380D03*
X384571D03*
X395673D03*
X388272Y911513D03*
Y898758D03*
Y905135D03*
X384571Y911513D03*
Y898758D03*
Y905135D03*
X395673Y898758D03*
Y905135D03*
Y911513D03*
X388272Y924269D03*
Y917891D03*
X384571Y924269D03*
Y917891D03*
X395673Y924269D03*
Y917891D03*
X388272Y930647D03*
X384571D03*
X395673D03*
X384571Y949781D03*
Y943403D03*
Y956159D03*
X395673Y949781D03*
Y943403D03*
Y956159D03*
X388272Y949781D03*
Y943403D03*
Y956159D03*
X395673Y962537D03*
Y968915D03*
X384571Y962537D03*
Y968915D03*
X388272Y962537D03*
Y968915D03*
X395673Y975293D03*
X384571D03*
X388272D03*
X385752Y1069513D03*
Y1063135D03*
X389453Y1069513D03*
Y1063135D03*
X385752Y1075891D03*
X389453D03*
X385752Y1088647D03*
Y1082269D03*
X389453Y1088647D03*
Y1082269D03*
X385752Y1095025D03*
X389453D03*
Y1114159D03*
Y1107781D03*
X385752Y1114159D03*
Y1107781D03*
X389453Y1120537D03*
X385752D03*
X389453Y1126915D03*
Y1133293D03*
X385752Y1126915D03*
Y1133293D03*
X389453Y1139670D03*
Y1146048D03*
X385752Y1139670D03*
Y1146048D03*
Y1158804D03*
X382051D03*
X393154D03*
X389453Y1152426D03*
X385752D03*
X382359Y1516970D03*
X387083D03*
X383933Y1519698D03*
X388658D03*
X382359Y1530608D03*
X387083D03*
X383933Y1533336D03*
X388658D03*
X399374Y892380D03*
X410477D03*
X406776D03*
X399374Y898758D03*
Y905135D03*
X410477Y898758D03*
Y905135D03*
X406776Y898758D03*
Y905135D03*
X399374Y911513D03*
X410477D03*
X406776D03*
X399374Y924269D03*
Y917891D03*
X410477D03*
Y924269D03*
X406776Y917891D03*
Y924269D03*
X399374Y930647D03*
X406776Y949781D03*
Y943403D03*
Y956159D03*
X399374Y949781D03*
Y943403D03*
Y956159D03*
X410477Y949781D03*
Y943403D03*
Y956159D03*
X406776Y962537D03*
Y968915D03*
X399374Y962537D03*
Y968915D03*
X410477Y962537D03*
Y968915D03*
X406776Y975293D03*
X399374D03*
X410477D03*
X396855Y1069513D03*
Y1063135D03*
X407957Y1069513D03*
X400555D03*
Y1063135D03*
X396855Y1075891D03*
X407957D03*
X400555D03*
X396855Y1088647D03*
Y1082269D03*
X407957Y1088647D03*
Y1082269D03*
X400555Y1088647D03*
Y1082269D03*
X396855Y1095025D03*
X407957D03*
X400555D03*
Y1114159D03*
Y1107781D03*
X396855Y1114159D03*
Y1107781D03*
X407957Y1114159D03*
X400555Y1120537D03*
Y1126915D03*
X396855Y1120537D03*
Y1126915D03*
X407957Y1120537D03*
Y1126915D03*
X400555Y1133293D03*
X396855D03*
X407957D03*
X400555Y1139670D03*
Y1146048D03*
X396855Y1139670D03*
Y1146048D03*
X407957Y1139670D03*
Y1146048D03*
X396855Y1158804D03*
X407957D03*
X404256D03*
X400555Y1152426D03*
X396855D03*
X407957D03*
X421579Y892380D03*
X417878D03*
X421579Y898758D03*
Y905135D03*
X417878Y898758D03*
Y905135D03*
X421579Y911513D03*
X417878D03*
X421579Y917891D03*
Y924269D03*
X417878Y917891D03*
Y924269D03*
Y937025D03*
X421579D03*
X417878Y943403D03*
Y956159D03*
Y949781D03*
X421579Y943403D03*
Y956159D03*
Y949781D03*
X417878Y962537D03*
Y968915D03*
X421579Y962537D03*
Y968915D03*
X417878Y975293D03*
X421579D03*
X411658Y1069513D03*
Y1075891D03*
X419059Y1082269D03*
Y1088647D03*
X422760Y1082269D03*
X411658Y1088647D03*
Y1082269D03*
X422760Y1088647D03*
X419059Y1095025D03*
Y1101403D03*
X422760Y1095025D03*
Y1101403D03*
X411658Y1095025D03*
X422760Y1114159D03*
X411658D03*
X419059D03*
X422760Y1120537D03*
Y1126915D03*
X411658Y1120537D03*
Y1126915D03*
X419059Y1120537D03*
Y1126915D03*
X422760Y1133293D03*
X411658D03*
X419059D03*
X422760Y1139670D03*
Y1146048D03*
X411658Y1139670D03*
Y1146048D03*
X419059Y1139670D03*
Y1146048D03*
Y1158804D03*
X415358D03*
X411658Y1152426D03*
X422760D03*
X419059D03*
X430831Y895569D03*
X427130D03*
X430831Y901947D03*
Y908325D03*
X427130Y901947D03*
Y908325D03*
X430831Y914702D03*
Y921080D03*
X427130Y914702D03*
Y921080D03*
X430831Y927458D03*
X427130D03*
Y940214D03*
X430831D03*
X427130Y946592D03*
Y952970D03*
X430831Y946592D03*
Y952970D03*
X427130Y959348D03*
Y965726D03*
X430831Y959348D03*
Y965726D03*
X427130Y978482D03*
Y972104D03*
X430831Y978482D03*
Y972104D03*
X428311Y1085458D03*
X432012D03*
X428311Y1098214D03*
Y1091836D03*
X432012Y1098214D03*
Y1091836D03*
Y1117348D03*
Y1110970D03*
X428311Y1117348D03*
Y1110970D03*
X432012Y1123726D03*
X428311D03*
X432012Y1130103D03*
X428311D03*
X432012Y1142859D03*
Y1136481D03*
X428311Y1142859D03*
Y1136481D03*
X449310Y895569D03*
X453011D03*
X449310Y908325D03*
Y901947D03*
X453011Y908325D03*
Y901947D03*
X449310Y921080D03*
Y914702D03*
X453011Y921080D03*
Y914702D03*
Y940214D03*
X449310D03*
Y927458D03*
X453011D03*
Y952970D03*
Y946592D03*
X449310Y952970D03*
Y946592D03*
X454192Y1059946D03*
X450491D03*
X454192Y1066324D03*
Y1072702D03*
X450491Y1066324D03*
Y1072702D03*
X454192Y1079080D03*
X450491D03*
X454192Y1085458D03*
X450491D03*
X454192Y1091836D03*
Y1098214D03*
X450491Y1091836D03*
Y1098214D03*
Y1110970D03*
Y1117348D03*
X454192Y1110970D03*
Y1117348D03*
X450491Y1123726D03*
X454192D03*
X450491Y1130103D03*
X454192D03*
X450491Y1136481D03*
Y1142859D03*
X454192Y1136481D03*
Y1142859D03*
X452328Y1516970D03*
X453903Y1519698D03*
X452328Y1530608D03*
X453903Y1533336D03*
X458562Y892380D03*
X469664D03*
X462263D03*
X458562Y905135D03*
Y898758D03*
X469664Y905135D03*
Y898758D03*
X462263Y905135D03*
Y898758D03*
X458562Y911513D03*
X469664D03*
X462263D03*
X458562Y924269D03*
Y917891D03*
X469664Y924269D03*
Y917891D03*
X462263Y924269D03*
Y917891D03*
Y937025D03*
X458562D03*
X462263Y956159D03*
Y943403D03*
Y949781D03*
X458562Y956159D03*
Y943403D03*
Y949781D03*
X469664Y956159D03*
Y943403D03*
Y949781D03*
X463444Y1063135D03*
Y1069513D03*
X459743Y1063135D03*
Y1069513D03*
X463444Y1075891D03*
X459743D03*
X463444Y1082269D03*
Y1088647D03*
X459743Y1082269D03*
Y1088647D03*
X463444Y1101403D03*
Y1095025D03*
X459743Y1101403D03*
Y1095025D03*
Y1114159D03*
X463444D03*
X459743Y1126915D03*
Y1120537D03*
X463444Y1126915D03*
Y1120537D03*
X459743Y1133293D03*
X463444D03*
X459743Y1146048D03*
Y1139670D03*
X463444Y1146048D03*
Y1139670D03*
X457052Y1516970D03*
X461777D03*
X466501D03*
X458627Y1519698D03*
X463351D03*
X468076D03*
X457052Y1530608D03*
X461777D03*
X466501D03*
X458627Y1533336D03*
X463351D03*
X468076D03*
X480767Y892380D03*
X484467D03*
X473365D03*
X480767Y898758D03*
Y905135D03*
X484467Y898758D03*
X473365Y905135D03*
Y898758D03*
X484467Y905135D03*
X480767Y911513D03*
X484467D03*
X473365D03*
X480767Y917891D03*
Y924269D03*
X484467Y917891D03*
Y924269D03*
X473365D03*
Y917891D03*
X480767Y930647D03*
X484467D03*
Y956159D03*
Y943403D03*
Y949781D03*
X473365Y956159D03*
Y943403D03*
Y949781D03*
X480767Y956159D03*
Y943403D03*
Y949781D03*
X474546Y1063135D03*
Y1069513D03*
X481948Y1063135D03*
Y1069513D03*
X470845Y1063135D03*
Y1069513D03*
X474546Y1075891D03*
X481948D03*
X470845D03*
X474546Y1082269D03*
Y1088647D03*
X481948Y1082269D03*
Y1088647D03*
X470845Y1082269D03*
Y1088647D03*
X474546Y1095025D03*
X481948D03*
X470845D03*
X481948Y1114159D03*
X470845D03*
X481948Y1107781D03*
X474546Y1114159D03*
X481948Y1126915D03*
Y1120537D03*
X470845Y1126915D03*
Y1120537D03*
X474546Y1126915D03*
Y1120537D03*
X470845Y1133293D03*
X481948D03*
X474546D03*
X481948Y1146048D03*
Y1139670D03*
X470845Y1146048D03*
Y1139670D03*
X474546Y1146048D03*
Y1139670D03*
X471225Y1516970D03*
X475950D03*
X480674D03*
X472800Y1519698D03*
X477525D03*
X482249D03*
X471225Y1530608D03*
X475950D03*
X480674D03*
X472800Y1533336D03*
X477525D03*
X482249D03*
X491869Y892380D03*
X495570D03*
X491869Y905135D03*
Y898758D03*
Y911513D03*
X495570Y905135D03*
Y898758D03*
Y911513D03*
X491869Y917891D03*
Y924269D03*
X495570Y917891D03*
Y924269D03*
X491869Y930647D03*
X495570D03*
Y956159D03*
Y943403D03*
Y949781D03*
X491869Y956159D03*
Y943403D03*
Y949781D03*
X485649Y1063135D03*
Y1069513D03*
X496751Y1063135D03*
Y1069513D03*
X493050Y1063135D03*
Y1069513D03*
X485649Y1075891D03*
X496751D03*
X493050D03*
X485649Y1082269D03*
Y1088647D03*
X496751Y1082269D03*
Y1088647D03*
X493050Y1082269D03*
Y1088647D03*
X485649Y1095025D03*
X496751D03*
X493050D03*
Y1107781D03*
Y1114159D03*
X485649D03*
X496751Y1107781D03*
Y1114159D03*
X485649Y1107781D03*
X493050Y1120537D03*
X485649Y1126915D03*
Y1120537D03*
X496751D03*
X493050Y1133293D03*
Y1126915D03*
X496751Y1133293D03*
Y1126915D03*
X485649Y1133293D03*
X493050Y1146048D03*
Y1139670D03*
X485649Y1146048D03*
Y1139670D03*
X496751Y1146048D03*
Y1139670D03*
X499572Y1516970D03*
X485399D03*
X490123D03*
X494847D03*
X486973Y1519698D03*
X491698D03*
X496422D03*
X499572Y1530608D03*
X485399D03*
X490123D03*
X494847D03*
X486973Y1533336D03*
X491698D03*
X496422D03*
X510373Y886002D03*
X504822Y889191D03*
X508523D03*
X502971Y892380D03*
X508523Y895569D03*
X504822D03*
X510373Y892380D03*
X508523Y908325D03*
X502971Y911513D03*
X510373Y898758D03*
X504822Y901947D03*
X508523D03*
X502971Y905135D03*
X510373D03*
X504822Y908325D03*
X510373Y911513D03*
X502971Y898758D03*
X510373Y917891D03*
X504822Y921080D03*
X508523D03*
X502971Y924269D03*
X510373D03*
X508523Y914702D03*
X504822D03*
X502971Y917891D03*
X504822Y927458D03*
X508523D03*
X502971Y930647D03*
X510373Y937025D03*
X504822Y940214D03*
X508523D03*
Y933836D03*
X504822D03*
X510373Y930647D03*
X502971Y937025D03*
Y943403D03*
X510373D03*
X504822Y946592D03*
X508523D03*
X502971Y949781D03*
X510373Y956159D03*
X508523Y952970D03*
X504822D03*
X510373Y949781D03*
X502971Y956159D03*
X510373Y962537D03*
X504822Y965726D03*
X508523D03*
X502971Y968915D03*
X504822Y959348D03*
X508523D03*
X502971Y962537D03*
X510373Y968915D03*
X504822Y984860D03*
X510373Y975293D03*
X504822Y978482D03*
X508523D03*
X502971Y981671D03*
X508523Y972104D03*
X504822D03*
X502971Y975293D03*
Y988049D03*
X510373Y994427D03*
X508523Y997616D03*
X504822D03*
X502971Y1000805D03*
X510373D03*
Y988049D03*
X504822Y991238D03*
X508523Y1010372D03*
X510373Y1007183D03*
X508523Y1003994D03*
X504822D03*
X502971Y1007183D03*
X504153Y1031245D03*
X506003Y1034434D03*
X509704D03*
X511554Y1037623D03*
X504153D03*
X506003Y1040812D03*
X509704D03*
X504153Y1044001D03*
Y1050379D03*
X509704Y1059946D03*
X506003Y1047190D03*
X511554Y1050379D03*
X509704Y1053568D03*
Y1072702D03*
X504153Y1063135D03*
X511554D03*
X506003Y1066324D03*
X504153Y1069513D03*
X511554D03*
X506003Y1072702D03*
X509704Y1066324D03*
X504153Y1075891D03*
X511554D03*
X506003Y1079080D03*
X509704D03*
X504153Y1082269D03*
X511554D03*
X506003Y1085458D03*
X511554Y1088647D03*
X504153D03*
X509704Y1085458D03*
X511554Y1101403D03*
X506003Y1104592D03*
X509704Y1091836D03*
X504153Y1095025D03*
X511554D03*
X506003Y1098214D03*
X509704D03*
X504153Y1101403D03*
X509704Y1104592D03*
X506003Y1091836D03*
X509704Y1110970D03*
X504153Y1114159D03*
X511554D03*
X506003Y1117348D03*
X509704D03*
X511554Y1107781D03*
X504153D03*
X506003Y1110970D03*
X504153Y1120537D03*
X511554D03*
X506003Y1123726D03*
X509704Y1130103D03*
X504153Y1133293D03*
X511554D03*
Y1126915D03*
X504153D03*
X509704Y1123726D03*
X506003Y1130103D03*
Y1136481D03*
X509704D03*
X504153Y1139670D03*
X511554D03*
X506003Y1142859D03*
X509704Y1149237D03*
X511554Y1146048D03*
X504153D03*
X509704Y1142859D03*
X506003Y1149237D03*
X504153Y1152426D03*
X511554D03*
X506003Y1155615D03*
X504296Y1516970D03*
X509021D03*
X513745D03*
X501147Y1519698D03*
X505871D03*
X510595D03*
X504296Y1530608D03*
X509021D03*
X513745D03*
X501147Y1533336D03*
X505871D03*
X510595D03*
X528877Y892380D03*
X521475Y886002D03*
X515924Y889191D03*
X523326D03*
X517775Y892380D03*
X523326Y895569D03*
X515924D03*
X521475Y892380D03*
X528877Y911513D03*
Y905135D03*
Y898758D03*
X523326Y908325D03*
X517775Y911513D03*
X521475Y898758D03*
X515924Y901947D03*
X523326D03*
X517775Y905135D03*
X521475D03*
X515924Y908325D03*
X521475Y911513D03*
X517775Y898758D03*
X528877Y924269D03*
Y917891D03*
X521475D03*
X515924Y921080D03*
X523326D03*
X517775Y924269D03*
X521475D03*
X523326Y914702D03*
X515924D03*
X517775Y917891D03*
X528877Y930647D03*
Y937025D03*
X515924Y927458D03*
X523326D03*
X517775Y930647D03*
X521475Y937025D03*
X515924Y940214D03*
X523326D03*
Y933836D03*
X515924D03*
X521475Y930647D03*
X517775Y937025D03*
X528877Y943403D03*
Y949781D03*
Y956159D03*
X517775Y943403D03*
X521475D03*
X515924Y946592D03*
X523326D03*
X517775Y949781D03*
X521475Y956159D03*
X523326Y952970D03*
X515924D03*
X521475Y949781D03*
X517775Y956159D03*
X528877Y968915D03*
Y962537D03*
X521475D03*
X515924Y965726D03*
X523326D03*
X517775Y968915D03*
X515924Y959348D03*
X523326D03*
X517775Y962537D03*
X521475Y968915D03*
X528877Y981671D03*
Y975293D03*
X515924Y984860D03*
X521475Y975293D03*
X515924Y978482D03*
X523326D03*
X517775Y981671D03*
X523326Y972104D03*
X515924D03*
X517775Y975293D03*
X528877Y988049D03*
Y1000805D03*
X517775Y988049D03*
X521475Y994427D03*
X523326Y997616D03*
X515924D03*
X517775Y1000805D03*
X521475D03*
Y988049D03*
X515924Y991238D03*
X528877Y1007183D03*
X523326Y1010372D03*
X521475Y1007183D03*
X523326Y1003994D03*
X515924D03*
X517775Y1007183D03*
X518956Y1031245D03*
X517105Y1034434D03*
X524507D03*
X522657Y1037623D03*
X518956D03*
X517105Y1040812D03*
X524507D03*
X518956Y1044001D03*
Y1050379D03*
X524507Y1059946D03*
X517105Y1047190D03*
X522657Y1050379D03*
X524507Y1053568D03*
Y1072702D03*
X518956Y1063135D03*
X522657D03*
X517105Y1066324D03*
X518956Y1069513D03*
X522657D03*
X517105Y1072702D03*
X524507Y1066324D03*
X518956Y1075891D03*
X522657D03*
X517105Y1079080D03*
X524507D03*
X518956Y1082269D03*
X522657D03*
X517105Y1085458D03*
X522657Y1088647D03*
X518956D03*
X524507Y1085458D03*
X522657Y1101403D03*
X517105Y1104592D03*
X524507Y1091836D03*
X518956Y1095025D03*
X522657D03*
X517105Y1098214D03*
X524507D03*
X518956Y1101403D03*
X524507Y1104592D03*
X517105Y1091836D03*
X524507Y1110970D03*
X518956Y1114159D03*
X522657D03*
X517105Y1117348D03*
X524507D03*
X522657Y1107781D03*
X518956D03*
X517105Y1110970D03*
X518956Y1120537D03*
X522657D03*
X517105Y1123726D03*
X524507Y1130103D03*
X518956Y1133293D03*
X522657D03*
Y1126915D03*
X518956D03*
X524507Y1123726D03*
X517105Y1130103D03*
Y1136481D03*
X524507D03*
X518956Y1139670D03*
X522657D03*
X517105Y1142859D03*
X524507Y1149237D03*
X522657Y1146048D03*
X518956D03*
X524507Y1142859D03*
X517105Y1149237D03*
X518956Y1152426D03*
X522657D03*
X524507Y1155615D03*
X518470Y1516970D03*
X523194D03*
X515320Y1519698D03*
X520044D03*
X524769D03*
X518470Y1530608D03*
X523194D03*
X515320Y1533336D03*
X520044D03*
X524769D03*
X536279Y886002D03*
X530727Y889191D03*
X534428D03*
Y895569D03*
X530727D03*
X536279Y892380D03*
X541830Y889191D03*
X543680Y892380D03*
X541830Y895569D03*
X534428Y908325D03*
X536279Y898758D03*
X530727Y901947D03*
X534428D03*
X536279Y905135D03*
X530727Y908325D03*
X536279Y911513D03*
X543680D03*
X541830Y901947D03*
X543680Y905135D03*
X541830Y908325D03*
X543680Y898758D03*
X536279Y917891D03*
X530727Y921080D03*
X534428D03*
X536279Y924269D03*
X534428Y914702D03*
X530727D03*
X541830Y921080D03*
X543680Y924269D03*
X541830Y914702D03*
X543680Y917891D03*
X530727Y927458D03*
X534428D03*
X536279Y937025D03*
X530727Y940214D03*
X534428D03*
Y933836D03*
X530727D03*
X536279Y930647D03*
X541830Y927458D03*
X543680Y930647D03*
X541830Y940214D03*
Y933836D03*
X543680Y937025D03*
X536279Y943403D03*
X530727Y946592D03*
X534428D03*
X536279Y956159D03*
X534428Y952970D03*
X530727D03*
X536279Y949781D03*
X543680Y943403D03*
X541830Y946592D03*
X543680Y949781D03*
X541830Y952970D03*
X543680Y956159D03*
X536279Y962537D03*
X530727Y965726D03*
X534428D03*
X530727Y959348D03*
X534428D03*
X536279Y968915D03*
X541830Y965726D03*
X543680Y968915D03*
X541830Y959348D03*
X543680Y962537D03*
X530727Y984860D03*
X536279Y975293D03*
X530727Y978482D03*
X534428D03*
Y972104D03*
X530727D03*
X541830Y984860D03*
Y978482D03*
X543680Y981671D03*
X541830Y972104D03*
X543680Y975293D03*
X536279Y994427D03*
X534428Y997616D03*
X530727D03*
X536279Y1000805D03*
Y988049D03*
X530727Y991238D03*
X543680Y988049D03*
X541830Y997616D03*
X543680Y1000805D03*
X541830Y991238D03*
X534428Y1010372D03*
X536279Y1007183D03*
X534428Y1003994D03*
X530727D03*
X541830D03*
X543680Y1007183D03*
X530058Y1031245D03*
X531908Y1034434D03*
X535609D03*
X537460Y1037623D03*
X530058D03*
X531908Y1040812D03*
X535609D03*
X530058Y1044001D03*
X543011Y1034434D03*
Y1040812D03*
X530058Y1050379D03*
X535609Y1059946D03*
X531908Y1047190D03*
X537460Y1050379D03*
X535609Y1053568D03*
X543011Y1047190D03*
X535609Y1072702D03*
X530058Y1063135D03*
X537460D03*
X531908Y1066324D03*
X530058Y1069513D03*
X537460D03*
X531908Y1072702D03*
X535609Y1066324D03*
X543011D03*
Y1072702D03*
X530058Y1075891D03*
X537460D03*
X531908Y1079080D03*
X535609D03*
X530058Y1082269D03*
X537460D03*
X531908Y1085458D03*
X537460Y1088647D03*
X530058D03*
X535609Y1085458D03*
X543011Y1079080D03*
Y1085458D03*
X537460Y1101403D03*
X531908Y1104592D03*
X535609Y1091836D03*
X530058Y1095025D03*
X537460D03*
X531908Y1098214D03*
X535609D03*
X530058Y1101403D03*
X535609Y1104592D03*
X531908Y1091836D03*
X543011Y1104592D03*
Y1098214D03*
Y1091836D03*
X535609Y1110970D03*
X530058Y1114159D03*
X537460D03*
X531908Y1117348D03*
X535609D03*
X537460Y1107781D03*
X530058D03*
X531908Y1110970D03*
X543011Y1117348D03*
Y1110970D03*
X530058Y1120537D03*
X537460D03*
X531908Y1123726D03*
X535609Y1130103D03*
X530058Y1133293D03*
X537460D03*
Y1126915D03*
X530058D03*
X535609Y1123726D03*
X531908Y1130103D03*
X543011Y1123726D03*
Y1130103D03*
X531908Y1136481D03*
X535609D03*
X530058Y1139670D03*
X537460D03*
X531908Y1142859D03*
X535609Y1149237D03*
X537460Y1146048D03*
X530058D03*
X535609Y1142859D03*
X531908Y1149237D03*
X543011Y1136481D03*
Y1142859D03*
Y1149237D03*
X530058Y1152426D03*
X537460D03*
X531908Y1155615D03*
X556633Y889191D03*
X554783Y892380D03*
X556633Y895569D03*
X547381Y886002D03*
X549231Y889191D03*
Y895569D03*
X547381Y892380D03*
X554783Y911513D03*
X556633Y901947D03*
X554783Y905135D03*
X556633Y908325D03*
X554783Y898758D03*
X549231Y908325D03*
X547381Y898758D03*
X549231Y901947D03*
X547381Y905135D03*
Y911513D03*
X556633Y921080D03*
X554783Y924269D03*
X556633Y914702D03*
X554783Y917891D03*
X547381D03*
X549231Y921080D03*
X547381Y924269D03*
X549231Y914702D03*
X556633Y927458D03*
X554783Y930647D03*
X556633Y940214D03*
Y933836D03*
X554783Y937025D03*
X549231Y927458D03*
X547381Y937025D03*
X549231Y940214D03*
Y933836D03*
X547381Y930647D03*
X554783Y943403D03*
X556633Y946592D03*
X554783Y949781D03*
X556633Y952970D03*
X554783Y956159D03*
X547381Y943403D03*
X549231Y946592D03*
X547381Y956159D03*
X549231Y952970D03*
X547381Y949781D03*
X556633Y965726D03*
X554783Y968915D03*
X556633Y959348D03*
X554783Y962537D03*
X547381D03*
X549231Y965726D03*
Y959348D03*
X547381Y968915D03*
X556633Y984860D03*
Y978482D03*
X554783Y981671D03*
X556633Y972104D03*
X554783Y975293D03*
X547381D03*
X549231Y978482D03*
Y972104D03*
X554783Y988049D03*
X556633Y997616D03*
X554783Y1000805D03*
X556633Y991238D03*
X547381Y994427D03*
X549231Y997616D03*
X547381Y1000805D03*
Y988049D03*
X556633Y1003994D03*
X554783Y1007183D03*
X549231Y1010372D03*
X547381Y1007183D03*
X549231Y1003994D03*
X555964Y1031245D03*
X557814Y1034434D03*
X555964Y1037623D03*
X557814Y1040812D03*
X555964Y1044001D03*
X544861Y1031245D03*
X550412Y1034434D03*
X548562Y1037623D03*
X544861D03*
X550412Y1040812D03*
X544861Y1044001D03*
X555964Y1050379D03*
X557814Y1047190D03*
X544861Y1050379D03*
X550412Y1059946D03*
X548562Y1050379D03*
X550412Y1053568D03*
X555964Y1063135D03*
X557814Y1066324D03*
X555964Y1069513D03*
X557814Y1072702D03*
X550412D03*
X544861Y1063135D03*
X548562D03*
X544861Y1069513D03*
X548562D03*
X550412Y1066324D03*
X555964Y1075891D03*
X557814Y1079080D03*
X555964Y1082269D03*
X557814Y1085458D03*
X555964Y1088647D03*
X544861Y1075891D03*
X548562D03*
X550412Y1079080D03*
X544861Y1082269D03*
X548562D03*
Y1088647D03*
X544861D03*
X550412Y1085458D03*
X557814Y1104592D03*
X555964Y1095025D03*
X557814Y1098214D03*
X555964Y1101403D03*
X557814Y1091836D03*
X548562Y1101403D03*
X550412Y1091836D03*
X544861Y1095025D03*
X548562D03*
X550412Y1098214D03*
X544861Y1101403D03*
X550412Y1104592D03*
X555964Y1114159D03*
X557814Y1117348D03*
X555964Y1107781D03*
X557814Y1110970D03*
X550412D03*
X544861Y1114159D03*
X548562D03*
X550412Y1117348D03*
X548562Y1107781D03*
X544861D03*
X555964Y1120537D03*
X557814Y1123726D03*
X555964Y1133293D03*
Y1126915D03*
X557814Y1130103D03*
X544861Y1120537D03*
X548562D03*
X550412Y1130103D03*
X544861Y1133293D03*
X548562D03*
Y1126915D03*
X544861D03*
X550412Y1123726D03*
X557814Y1136481D03*
X555964Y1139670D03*
X557814Y1142859D03*
X555964Y1146048D03*
X557814Y1149237D03*
X550412Y1136481D03*
X544861Y1139670D03*
X548562D03*
X550412Y1149237D03*
X548562Y1146048D03*
X544861D03*
X550412Y1142859D03*
X555964Y1152426D03*
X557814Y1155615D03*
X544861Y1152426D03*
X548562D03*
X550412Y1155615D03*
X562184Y886002D03*
X560334Y889191D03*
Y895569D03*
X562184Y892380D03*
X560334Y908325D03*
X562184Y898758D03*
X560334Y901947D03*
X562184Y905135D03*
Y911513D03*
Y917891D03*
X560334Y921080D03*
X562184Y924269D03*
X560334Y914702D03*
Y927458D03*
X562184Y937025D03*
X560334Y940214D03*
Y933836D03*
X562184Y930647D03*
Y943403D03*
X560334Y946592D03*
X562184Y956159D03*
X560334Y952970D03*
X562184Y949781D03*
Y962537D03*
X560334Y965726D03*
Y959348D03*
X562184Y968915D03*
Y975293D03*
X560334Y978482D03*
Y972104D03*
X562184Y994427D03*
X560334Y997616D03*
X562184Y1000805D03*
Y988049D03*
X560334Y1010372D03*
X562184Y1007183D03*
X560334Y1003994D03*
X561515Y1034434D03*
X563365Y1037623D03*
X561515Y1040812D03*
Y1059946D03*
X563365Y1050379D03*
X561515Y1053568D03*
Y1072702D03*
X563365Y1063135D03*
Y1069513D03*
X561515Y1066324D03*
X563365Y1075891D03*
X561515Y1079080D03*
X563365Y1082269D03*
Y1088647D03*
X561515Y1085458D03*
X563365Y1101403D03*
X561515Y1091836D03*
X563365Y1095025D03*
X561515Y1098214D03*
Y1104592D03*
Y1110970D03*
X563365Y1114159D03*
X561515Y1117348D03*
X563365Y1107781D03*
Y1120537D03*
X561515Y1130103D03*
X563365Y1133293D03*
Y1126915D03*
X561515Y1123726D03*
Y1136481D03*
X563365Y1139670D03*
X561515Y1149237D03*
X563365Y1146048D03*
X561515Y1142859D03*
X563365Y1152426D03*
X580390Y1516970D03*
X585114D03*
X581965Y1519698D03*
X586689D03*
X580390Y1530608D03*
X585114D03*
X581965Y1533336D03*
X586689D03*
X589839Y1516970D03*
X594563D03*
X599287D03*
X604012D03*
X591413Y1519698D03*
X596138D03*
X600862D03*
X589839Y1530608D03*
X594563D03*
X599287D03*
X604012D03*
X591413Y1533336D03*
X596138D03*
X600862D03*
X608736Y1516970D03*
X613461D03*
X618185D03*
X605587Y1519698D03*
X610311D03*
X615035D03*
X608736Y1530608D03*
X613461D03*
X618185D03*
X605587Y1533336D03*
X610311D03*
X615035D03*
X627634Y1516970D03*
X632358D03*
X622909D03*
X629209Y1519698D03*
X633933D03*
X619760D03*
X624484D03*
X627634Y1530608D03*
X632358D03*
X622909D03*
X629209Y1533336D03*
X633933D03*
X619760D03*
X624484D03*
X637083Y1516970D03*
X641807D03*
X646532D03*
X638657Y1519698D03*
X643382D03*
X648106D03*
X637083Y1530608D03*
X641807D03*
X646532D03*
X638657Y1533336D03*
X643382D03*
X648106D03*
X651256Y1516970D03*
X652831Y1519698D03*
X651256Y1530608D03*
X652831Y1533336D03*
X1196028Y1549970D03*
X1197603Y1552698D03*
X1196028Y1563608D03*
X1197603Y1566336D03*
X1200752Y1549970D03*
X1205477D03*
X1210201D03*
X1214925D03*
X1202327Y1552698D03*
X1207051D03*
X1211776D03*
X1200752Y1563608D03*
X1205477D03*
X1210201D03*
X1214925D03*
X1202327Y1566336D03*
X1207051D03*
X1211776D03*
X1219650Y1549970D03*
X1224374D03*
X1229099D03*
X1216500Y1552698D03*
X1221225D03*
X1225949D03*
X1219650Y1563608D03*
X1224374D03*
X1229099D03*
X1216500Y1566336D03*
X1221225D03*
X1225949D03*
X1230673Y1552698D03*
X1243272Y1563608D03*
X1233823D03*
X1238547D03*
X1244847Y1566336D03*
X1230673D03*
X1235398D03*
X1240122D03*
X1247996Y1563608D03*
X1252721D03*
X1257445D03*
X1249571Y1566336D03*
X1254295D03*
X1259020D03*
X1262170Y1563608D03*
X1266894D03*
X1263744Y1566336D03*
X1268469D03*
X1294099Y886001D03*
X1299650Y889190D03*
X1295949D03*
X1301500Y892379D03*
X1295949Y895568D03*
X1299650D03*
X1294099Y892379D03*
X1295949Y908324D03*
X1301500Y911512D03*
X1294099Y898757D03*
X1299650Y901946D03*
X1295949D03*
X1301500Y905134D03*
X1294099D03*
X1299650Y908324D03*
X1294099Y911512D03*
X1301500Y898757D03*
X1294099Y917890D03*
X1299650Y921079D03*
X1295949D03*
X1301500Y924268D03*
X1294099D03*
X1295949Y914701D03*
X1299650D03*
X1301500Y917890D03*
X1299650Y927457D03*
X1295949D03*
X1301500Y930646D03*
X1294099Y937024D03*
X1299650Y940213D03*
X1295949D03*
Y933835D03*
X1299650D03*
X1294099Y930646D03*
X1301500Y937024D03*
Y943402D03*
X1294099D03*
X1299650Y946591D03*
X1295949D03*
X1301500Y949780D03*
X1294099Y956158D03*
X1295949Y952969D03*
X1299650D03*
X1294099Y949780D03*
X1301500Y956158D03*
X1294099Y962536D03*
X1299650Y965725D03*
X1295949D03*
X1301500Y968914D03*
X1299650Y959347D03*
X1295949D03*
X1301500Y962536D03*
X1294099Y968914D03*
X1299650Y984859D03*
X1294099Y975292D03*
X1299650Y978481D03*
X1295949D03*
X1301500Y981670D03*
X1295949Y972103D03*
X1299650D03*
X1301500Y975292D03*
Y988048D03*
X1294099Y994426D03*
X1295949Y997615D03*
X1299650D03*
X1301500Y1000804D03*
X1294099D03*
X1295949Y991237D03*
X1301500Y994426D03*
X1295949Y1010371D03*
X1294099Y1007182D03*
X1295949Y1003993D03*
X1299650D03*
X1301500Y1007182D03*
X1302681Y1031244D03*
X1300831Y1034433D03*
X1297130D03*
X1295280Y1037622D03*
X1302681D03*
X1300831Y1040811D03*
X1297130D03*
X1295280Y1044000D03*
X1302681Y1050378D03*
X1297130Y1059945D03*
X1300831Y1047189D03*
X1295280Y1050378D03*
X1297130Y1053567D03*
Y1072701D03*
X1302681Y1063134D03*
X1295280D03*
X1300831Y1066323D03*
X1302681Y1069512D03*
X1295280D03*
X1300831Y1072701D03*
X1297130Y1066323D03*
X1302681Y1075890D03*
X1295280D03*
X1300831Y1079079D03*
X1297130D03*
X1302681Y1082268D03*
X1295280D03*
X1300831Y1085457D03*
X1295280Y1088646D03*
X1302681D03*
X1297130Y1085457D03*
X1295280Y1101402D03*
X1300831Y1104591D03*
X1297130Y1091835D03*
X1302681Y1095024D03*
X1295280D03*
X1300831Y1098213D03*
X1297130D03*
X1302681Y1101402D03*
X1297130Y1104591D03*
X1300831Y1091835D03*
X1297130Y1110969D03*
X1302681Y1114158D03*
X1295280D03*
X1300831Y1117347D03*
X1297130D03*
X1295280Y1107780D03*
X1302681D03*
X1300831Y1110969D03*
X1302681Y1120536D03*
X1295280D03*
X1300831Y1123725D03*
X1297130Y1130102D03*
X1302681Y1133292D03*
X1295280D03*
Y1126914D03*
X1302681D03*
X1297130Y1123725D03*
X1300831Y1130102D03*
Y1136480D03*
X1297130D03*
X1302681Y1139669D03*
X1295280D03*
X1300831Y1142858D03*
X1297130Y1149236D03*
X1295280Y1146047D03*
X1302681D03*
X1297130Y1142858D03*
X1300831Y1149236D03*
X1302681Y1152425D03*
X1295280D03*
X1300831Y1155614D03*
X1308902Y886001D03*
X1314453Y889190D03*
X1307052D03*
X1312603Y892379D03*
X1307052Y895568D03*
X1314453D03*
X1308902Y892379D03*
X1307052Y908324D03*
X1312603Y911512D03*
X1308902Y898757D03*
X1314453Y901946D03*
X1307052D03*
X1312603Y905134D03*
X1308902D03*
X1314453Y908324D03*
X1308902Y911512D03*
X1312603Y898757D03*
X1308902Y917890D03*
X1314453Y921079D03*
X1307052D03*
X1312603Y924268D03*
X1308902D03*
X1307052Y914701D03*
X1314453D03*
X1312603Y917890D03*
X1314453Y927457D03*
X1307052D03*
X1312603Y930646D03*
X1308902Y937024D03*
X1314453Y940213D03*
X1307052D03*
Y933835D03*
X1314453D03*
X1308902Y930646D03*
X1312603Y937024D03*
Y943402D03*
X1308902D03*
X1314453Y946591D03*
X1307052D03*
X1312603Y949780D03*
X1308902Y956158D03*
X1307052Y952969D03*
X1314453D03*
X1308902Y949780D03*
X1312603Y956158D03*
X1308902Y962536D03*
X1314453Y965725D03*
X1307052D03*
X1312603Y968914D03*
X1314453Y959347D03*
X1307052D03*
X1312603Y962536D03*
X1308902Y968914D03*
X1314453Y984859D03*
X1308902Y975292D03*
X1314453Y978481D03*
X1307052D03*
X1312603Y981670D03*
X1307052Y972103D03*
X1314453D03*
X1312603Y975292D03*
Y988048D03*
X1308902Y994426D03*
X1307052Y997615D03*
X1314453D03*
X1312603Y1000804D03*
X1308902D03*
X1307052Y991237D03*
X1312603Y994426D03*
X1307052Y1010371D03*
X1308902Y1007182D03*
X1307052Y1003993D03*
X1314453D03*
X1312603Y1007182D03*
X1313784Y1031244D03*
X1315634Y1034433D03*
X1308233D03*
X1310083Y1037622D03*
X1313784D03*
X1315634Y1040811D03*
X1308233D03*
X1310083Y1044000D03*
X1313784Y1050378D03*
X1308233Y1059945D03*
X1315634Y1047189D03*
X1310083Y1050378D03*
X1308233Y1053567D03*
Y1072701D03*
X1313784Y1063134D03*
X1310083D03*
X1315634Y1066323D03*
X1313784Y1069512D03*
X1310083D03*
X1315634Y1072701D03*
X1308233Y1066323D03*
X1313784Y1075890D03*
X1310083D03*
X1315634Y1079079D03*
X1308233D03*
X1313784Y1082268D03*
X1310083D03*
X1315634Y1085457D03*
X1310083Y1088646D03*
X1313784D03*
X1308233Y1085457D03*
X1310083Y1101402D03*
X1315634Y1104591D03*
X1308233Y1091835D03*
X1313784Y1095024D03*
X1310083D03*
X1315634Y1098213D03*
X1308233D03*
X1313784Y1101402D03*
X1308233Y1104591D03*
X1315634Y1091835D03*
X1308233Y1110969D03*
X1313784Y1114158D03*
X1310083D03*
X1315634Y1117347D03*
X1308233D03*
X1310083Y1107780D03*
X1313784D03*
X1315634Y1110969D03*
X1313784Y1120536D03*
X1310083D03*
X1315634Y1123725D03*
X1308233Y1130102D03*
X1313784Y1133292D03*
X1310083D03*
Y1126914D03*
X1313784D03*
X1308233Y1123725D03*
X1315634Y1130102D03*
Y1136480D03*
X1308233D03*
X1313784Y1139669D03*
X1310083D03*
X1315634Y1142858D03*
X1308233Y1149236D03*
X1310083Y1146047D03*
X1313784D03*
X1308233Y1142858D03*
X1315634Y1149236D03*
X1313784Y1152425D03*
X1310083D03*
X1308233Y1155614D03*
X1320004Y886001D03*
X1325556Y889190D03*
X1321855D03*
X1327406Y892379D03*
X1321855Y895568D03*
X1325556D03*
X1320004Y892379D03*
X1334807Y886001D03*
X1332957Y889190D03*
Y895568D03*
X1334807Y892379D03*
X1321855Y908324D03*
X1327406Y911512D03*
X1320004Y898757D03*
X1325556Y901946D03*
X1321855D03*
X1327406Y905134D03*
X1320004D03*
X1325556Y908324D03*
X1320004Y911512D03*
X1327406Y898757D03*
X1332957Y908324D03*
X1334807Y898757D03*
X1332957Y901946D03*
X1334807Y905134D03*
Y911512D03*
X1320004Y917890D03*
X1325556Y921079D03*
X1321855D03*
X1327406Y924268D03*
X1320004D03*
X1321855Y914701D03*
X1325556D03*
X1327406Y917890D03*
X1334807D03*
X1332957Y921079D03*
X1334807Y924268D03*
X1332957Y914701D03*
X1325556Y927457D03*
X1321855D03*
X1327406Y930646D03*
X1320004Y937024D03*
X1325556Y940213D03*
X1321855D03*
Y933835D03*
X1325556D03*
X1320004Y930646D03*
X1327406Y937024D03*
X1332957Y927457D03*
X1334807Y937024D03*
X1332957Y940213D03*
Y933835D03*
X1334807Y930646D03*
X1327406Y943402D03*
X1320004D03*
X1325556Y946591D03*
X1321855D03*
X1327406Y949780D03*
X1320004Y956158D03*
X1321855Y952969D03*
X1325556D03*
X1320004Y949780D03*
X1327406Y956158D03*
X1334807Y943402D03*
X1332957Y946591D03*
X1334807Y956158D03*
X1332957Y952969D03*
X1334807Y949780D03*
X1320004Y962536D03*
X1325556Y965725D03*
X1321855D03*
X1327406Y968914D03*
X1325556Y959347D03*
X1321855D03*
X1327406Y962536D03*
X1320004Y968914D03*
X1334807Y962536D03*
X1332957Y965725D03*
Y959347D03*
X1334807Y968914D03*
X1325556Y984859D03*
X1320004Y975292D03*
X1325556Y978481D03*
X1321855D03*
X1327406Y981670D03*
X1321855Y972103D03*
X1325556D03*
X1327406Y975292D03*
X1334807D03*
X1332957Y978481D03*
Y972103D03*
X1327406Y988048D03*
X1320004Y994426D03*
X1321855Y997615D03*
X1325556D03*
X1327406Y1000804D03*
X1320004D03*
X1321855Y991237D03*
X1327406Y994426D03*
X1334807D03*
X1332957Y997615D03*
X1334807Y1000804D03*
X1332957Y991237D03*
X1321855Y1010371D03*
X1320004Y1007182D03*
X1321855Y1003993D03*
X1325556D03*
X1327406Y1007182D03*
X1332957Y1010371D03*
X1334807Y1007182D03*
X1332957Y1003993D03*
X1328587Y1031244D03*
X1326737Y1034433D03*
X1323036D03*
X1321185Y1037622D03*
X1328587D03*
X1326737Y1040811D03*
X1323036D03*
X1321185Y1044000D03*
X1334138Y1034433D03*
Y1040811D03*
X1328587Y1050378D03*
X1323036Y1059945D03*
X1326737Y1047189D03*
X1321185Y1050378D03*
X1323036Y1053567D03*
X1334138Y1059945D03*
Y1053567D03*
X1323036Y1072701D03*
X1328587Y1063134D03*
X1321185D03*
X1326737Y1066323D03*
X1328587Y1069512D03*
X1321185D03*
X1326737Y1072701D03*
X1323036Y1066323D03*
X1334138Y1072701D03*
Y1066323D03*
X1328587Y1075890D03*
X1321185D03*
X1326737Y1079079D03*
X1323036D03*
X1328587Y1082268D03*
X1321185D03*
X1326737Y1085457D03*
X1321185Y1088646D03*
X1328587D03*
X1323036Y1085457D03*
X1334138Y1079079D03*
Y1085457D03*
X1321185Y1101402D03*
X1326737Y1104591D03*
X1323036Y1091835D03*
X1328587Y1095024D03*
X1321185D03*
X1326737Y1098213D03*
X1323036D03*
X1328587Y1101402D03*
X1323036Y1104591D03*
X1326737Y1091835D03*
X1334138D03*
Y1098213D03*
Y1104591D03*
X1323036Y1110969D03*
X1328587Y1114158D03*
X1321185D03*
X1326737Y1117347D03*
X1323036D03*
X1321185Y1107780D03*
X1328587D03*
X1326737Y1110969D03*
X1334138D03*
Y1117347D03*
X1328587Y1120536D03*
X1321185D03*
X1326737Y1123725D03*
X1323036Y1130102D03*
X1328587Y1133292D03*
X1321185D03*
Y1126914D03*
X1328587D03*
X1323036Y1123725D03*
X1326737Y1130102D03*
X1334138D03*
Y1123725D03*
X1326737Y1136480D03*
X1323036D03*
X1328587Y1139669D03*
X1321185D03*
X1326737Y1142858D03*
X1323036Y1149236D03*
X1321185Y1146047D03*
X1328587D03*
X1323036Y1142858D03*
X1326737Y1149236D03*
X1334138Y1136480D03*
Y1149236D03*
Y1142858D03*
X1328587Y1152425D03*
X1321185D03*
X1326737Y1155614D03*
X1334138D03*
X1324090Y1549970D03*
X1328814D03*
X1333539D03*
X1325665Y1552698D03*
X1330389D03*
X1324090Y1563608D03*
X1328814D03*
X1333539D03*
X1325665Y1566336D03*
X1330389D03*
X1345910Y886001D03*
X1347760Y889190D03*
Y895568D03*
X1345910Y892379D03*
X1340359Y889190D03*
X1338508Y892379D03*
X1340359Y895568D03*
X1347760Y908324D03*
X1345910Y898757D03*
X1347760Y901946D03*
X1345910Y905134D03*
Y911512D03*
X1338508D03*
X1340359Y901946D03*
X1338508Y905134D03*
X1340359Y908324D03*
X1338508Y898757D03*
X1345910Y917890D03*
X1347760Y921079D03*
X1345910Y924268D03*
X1347760Y914701D03*
X1340359Y921079D03*
X1338508Y924268D03*
X1340359Y914701D03*
X1338508Y917890D03*
X1347760Y927457D03*
X1345910Y937024D03*
X1347760Y940213D03*
Y933835D03*
X1345910Y930646D03*
X1340359Y927457D03*
X1338508Y930646D03*
X1340359Y940213D03*
Y933835D03*
X1338508Y937024D03*
X1345910Y943402D03*
X1347760Y946591D03*
X1345910Y956158D03*
X1347760Y952969D03*
X1345910Y949780D03*
X1338508Y943402D03*
X1340359Y946591D03*
X1338508Y949780D03*
X1340359Y952969D03*
X1338508Y956158D03*
X1345910Y962536D03*
X1347760Y965725D03*
Y959347D03*
X1345910Y968914D03*
X1340359Y965725D03*
X1338508Y968914D03*
X1340359Y959347D03*
X1338508Y962536D03*
X1345910Y975292D03*
X1347760Y978481D03*
Y972103D03*
X1340359Y984859D03*
Y978481D03*
X1338508Y981670D03*
X1340359Y972103D03*
X1338508Y975292D03*
X1345910Y994426D03*
X1347760Y997615D03*
X1345910Y1000804D03*
X1347760Y991237D03*
X1338508Y988048D03*
X1340359Y997615D03*
X1338508Y1000804D03*
Y994426D03*
X1347760Y1010371D03*
X1345910Y1007182D03*
X1347760Y1003993D03*
X1340359D03*
X1338508Y1007182D03*
X1348941Y1034433D03*
X1347091Y1037622D03*
X1348941Y1040811D03*
X1347091Y1044000D03*
X1339689Y1031244D03*
X1341540Y1034433D03*
X1335989Y1037622D03*
X1339689D03*
X1341540Y1040811D03*
X1335989Y1044000D03*
X1348941Y1059945D03*
X1347091Y1050378D03*
X1348941Y1053567D03*
X1339689Y1050378D03*
X1341540Y1047189D03*
X1335989Y1050378D03*
X1348941Y1072701D03*
X1347091Y1063134D03*
Y1069512D03*
X1348941Y1066323D03*
X1339689Y1063134D03*
X1335989D03*
X1341540Y1066323D03*
X1339689Y1069512D03*
X1335989D03*
X1341540Y1072701D03*
X1347091Y1075890D03*
X1348941Y1079079D03*
X1347091Y1082268D03*
Y1088646D03*
X1348941Y1085457D03*
X1339689Y1075890D03*
X1335989D03*
X1341540Y1079079D03*
X1339689Y1082268D03*
X1335989D03*
X1341540Y1085457D03*
X1335989Y1088646D03*
X1339689D03*
X1347091Y1101402D03*
X1348941Y1091835D03*
X1347091Y1095024D03*
X1348941Y1098213D03*
Y1104591D03*
X1335989Y1101402D03*
X1341540Y1104591D03*
X1339689Y1095024D03*
X1335989D03*
X1341540Y1098213D03*
X1339689Y1101402D03*
X1341540Y1091835D03*
X1348941Y1110969D03*
X1347091Y1114158D03*
X1348941Y1117347D03*
X1347091Y1107780D03*
X1339689Y1114158D03*
X1335989D03*
X1341540Y1117347D03*
X1335989Y1107780D03*
X1339689D03*
X1341540Y1110969D03*
X1347091Y1120536D03*
X1348941Y1130102D03*
X1347091Y1133292D03*
Y1126914D03*
X1348941Y1123725D03*
X1339689Y1120536D03*
X1335989D03*
X1341540Y1123725D03*
X1339689Y1133292D03*
X1335989D03*
Y1126914D03*
X1339689D03*
X1341540Y1130102D03*
X1348941Y1136480D03*
X1347091Y1139669D03*
X1348941Y1149236D03*
X1347091Y1146047D03*
X1348941Y1142858D03*
X1341540Y1136480D03*
X1339689Y1139669D03*
X1335989D03*
X1341540Y1142858D03*
X1335989Y1146047D03*
X1339689D03*
X1341540Y1149236D03*
X1347091Y1152425D03*
X1339689D03*
X1335989D03*
X1338263Y1549970D03*
X1342987D03*
X1347712D03*
X1335113Y1552698D03*
X1339838D03*
X1344562D03*
X1349287D03*
X1338263Y1563608D03*
X1342987D03*
X1347712D03*
X1335113Y1566336D03*
X1339838D03*
X1344562D03*
X1349287D03*
X1364414Y892379D03*
X1360713D03*
X1351461Y889190D03*
X1353311Y892379D03*
X1351461Y895568D03*
X1364414Y905134D03*
Y898757D03*
Y911512D03*
X1360713Y905134D03*
Y898757D03*
Y911512D03*
X1353311D03*
X1351461Y901946D03*
X1353311Y905134D03*
X1351461Y908324D03*
X1353311Y898757D03*
X1364414Y917890D03*
Y924268D03*
X1360713Y917890D03*
Y924268D03*
X1351461Y921079D03*
X1353311Y924268D03*
X1351461Y914701D03*
X1353311Y917890D03*
X1364414Y930646D03*
X1360713D03*
X1351461Y927457D03*
X1353311Y930646D03*
X1351461Y940213D03*
Y933835D03*
X1353311Y937024D03*
X1360713Y956158D03*
Y943402D03*
Y949780D03*
X1364414Y956158D03*
Y943402D03*
Y949780D03*
X1353311Y943402D03*
X1351461Y946591D03*
X1353311Y949780D03*
X1351461Y952969D03*
X1353311Y956158D03*
X1351461Y965725D03*
X1353311Y968914D03*
X1351461Y959347D03*
X1353311Y962536D03*
X1351461Y984859D03*
Y978481D03*
X1353311Y981670D03*
X1351461Y972103D03*
X1353311Y975292D03*
Y988048D03*
X1351461Y997615D03*
X1353311Y1000804D03*
Y994426D03*
X1351461Y1003993D03*
X1353311Y1007182D03*
X1354493Y1031244D03*
X1352642Y1034433D03*
X1354493Y1037622D03*
X1352642Y1040811D03*
X1354493Y1050378D03*
X1352642Y1047189D03*
X1354493Y1063134D03*
X1352642Y1066323D03*
X1354493Y1069512D03*
X1352642Y1072701D03*
X1361894Y1069512D03*
Y1063134D03*
X1354493Y1075890D03*
X1352642Y1079079D03*
X1354493Y1082268D03*
X1352642Y1085457D03*
X1354493Y1088646D03*
X1361894Y1075890D03*
Y1088646D03*
Y1082268D03*
X1352642Y1104591D03*
X1354493Y1095024D03*
X1352642Y1098213D03*
X1354493Y1101402D03*
X1352642Y1091835D03*
X1361894Y1095024D03*
X1354493Y1114158D03*
X1352642Y1117347D03*
X1354493Y1107780D03*
X1352642Y1110969D03*
X1361894Y1114158D03*
Y1107780D03*
X1354493Y1120536D03*
X1352642Y1123725D03*
X1354493Y1133292D03*
Y1126914D03*
X1352642Y1130102D03*
X1361894Y1120536D03*
Y1126914D03*
Y1133292D03*
X1352642Y1136480D03*
X1354493Y1139669D03*
X1352642Y1142858D03*
X1354493Y1146047D03*
X1352642Y1149236D03*
X1361894Y1139669D03*
Y1146047D03*
X1354493Y1152425D03*
X1352642Y1155614D03*
X1361894Y1158803D03*
X1358193D03*
X1361894Y1152425D03*
X1352436Y1549970D03*
X1357161D03*
X1361885D03*
X1354011Y1552698D03*
X1358735D03*
X1363460D03*
X1352436Y1563608D03*
X1357161D03*
X1361885D03*
X1354011Y1566336D03*
X1358735D03*
X1363460D03*
X1375516Y892379D03*
X1371815D03*
X1375516Y898757D03*
Y905134D03*
X1371815Y898757D03*
Y905134D03*
X1375516Y911512D03*
X1371815D03*
X1375516Y917890D03*
Y924268D03*
X1371815Y917890D03*
Y924268D03*
X1375516Y930646D03*
X1371815D03*
Y956158D03*
Y943402D03*
Y949780D03*
X1375516Y956158D03*
Y943402D03*
Y949780D03*
X1372997Y1069512D03*
Y1063134D03*
X1365595Y1069512D03*
Y1063134D03*
X1376697Y1069512D03*
Y1063134D03*
X1372997Y1075890D03*
X1365595D03*
X1376697D03*
X1372997Y1088646D03*
Y1082268D03*
X1365595Y1088646D03*
Y1082268D03*
X1376697Y1088646D03*
Y1082268D03*
X1372997Y1095024D03*
X1365595D03*
X1376697D03*
X1365595Y1114158D03*
Y1107780D03*
X1376697Y1114158D03*
Y1107780D03*
X1372997Y1114158D03*
Y1107780D03*
X1365595Y1120536D03*
X1376697D03*
Y1126914D03*
X1372997Y1120536D03*
Y1126914D03*
X1365595D03*
Y1133292D03*
X1376697D03*
X1372997D03*
X1365595Y1139669D03*
Y1146047D03*
X1376697Y1139669D03*
Y1146047D03*
X1372997Y1139669D03*
Y1146047D03*
Y1158803D03*
X1369296D03*
X1365595Y1152425D03*
X1376697D03*
X1372997D03*
X1371334Y1549970D03*
X1376058D03*
X1366609D03*
X1372909Y1552698D03*
X1377633D03*
X1368184D03*
X1371334Y1563608D03*
X1376058D03*
X1366609D03*
X1372909Y1566336D03*
X1377633D03*
X1368184D03*
X1386619Y892379D03*
X1394020D03*
X1382918D03*
X1386619Y905134D03*
Y898757D03*
X1394020Y905134D03*
Y898757D03*
X1382918Y905134D03*
Y898757D03*
X1386619Y911512D03*
X1394020D03*
X1382918D03*
X1386619Y924268D03*
Y917890D03*
X1394020Y924268D03*
Y917890D03*
X1382918Y924268D03*
Y917890D03*
X1394020Y937024D03*
Y956158D03*
Y943402D03*
Y949780D03*
X1382918Y956158D03*
Y943402D03*
Y949780D03*
X1386619Y956158D03*
Y943402D03*
Y949780D03*
X1384099Y1069512D03*
X1387800D03*
X1384099Y1075890D03*
X1387800D03*
X1384099Y1088646D03*
Y1082268D03*
X1387800Y1088646D03*
Y1082268D03*
X1384099Y1095024D03*
X1387800D03*
Y1114158D03*
X1384099D03*
X1387800Y1120536D03*
Y1126914D03*
X1384099Y1120536D03*
Y1126914D03*
X1387800Y1133292D03*
X1384099D03*
X1387800Y1139669D03*
Y1146047D03*
X1384099Y1139669D03*
Y1146047D03*
Y1158803D03*
X1380398D03*
X1391500D03*
X1387800Y1152425D03*
X1384099D03*
X1380783Y1549970D03*
X1385507D03*
X1390232D03*
X1382357Y1552698D03*
X1387082D03*
X1391806D03*
X1380783Y1563608D03*
X1385507D03*
X1390232D03*
X1382357Y1566336D03*
X1387082D03*
X1391806D03*
X1406973Y895568D03*
X1397721Y892379D03*
X1403272Y895568D03*
X1406973Y908324D03*
Y901946D03*
X1397721Y905134D03*
Y898757D03*
X1403272Y908324D03*
Y901946D03*
X1397721Y911512D03*
X1406973Y921079D03*
Y914701D03*
X1397721Y924268D03*
Y917890D03*
X1403272Y921079D03*
Y914701D03*
Y940213D03*
X1406973D03*
X1397721Y937024D03*
X1406973Y927457D03*
X1403272D03*
Y952969D03*
Y946591D03*
X1406973Y952969D03*
Y946591D03*
X1397721Y956158D03*
Y943402D03*
Y949780D03*
X1395201Y1082268D03*
X1404453Y1085457D03*
X1395201Y1088646D03*
X1398902Y1082268D03*
X1408154Y1085457D03*
X1398902Y1088646D03*
X1395201Y1095024D03*
Y1101402D03*
X1404453Y1098213D03*
Y1091835D03*
X1398902Y1095024D03*
Y1101402D03*
X1408154Y1098213D03*
Y1091835D03*
X1398902Y1114158D03*
X1408154Y1117347D03*
Y1110969D03*
X1395201Y1114158D03*
X1404453Y1117347D03*
Y1110969D03*
X1398902Y1120536D03*
Y1126914D03*
X1408154Y1123725D03*
X1395201Y1120536D03*
Y1126914D03*
X1404453Y1123725D03*
X1398902Y1133292D03*
X1408154Y1130102D03*
X1395201Y1133292D03*
X1404453Y1130102D03*
X1398902Y1139669D03*
Y1146047D03*
X1408154Y1142858D03*
Y1136480D03*
X1395201Y1139669D03*
Y1146047D03*
X1404453Y1142858D03*
Y1136480D03*
X1395201Y1158803D03*
X1398902Y1152425D03*
X1395201D03*
X1394956Y1549970D03*
X1396531Y1552698D03*
X1394956Y1563608D03*
X1396531Y1566336D03*
X1434704Y892379D03*
X1425452Y895568D03*
X1438405Y892379D03*
X1429153Y895568D03*
X1434704Y898757D03*
Y905134D03*
X1425452Y901946D03*
Y908324D03*
X1438405Y898757D03*
Y905134D03*
X1429153Y901946D03*
Y908324D03*
X1434704Y911512D03*
X1438405D03*
X1434704Y917890D03*
Y924268D03*
X1425452Y914701D03*
Y921079D03*
X1438405Y917890D03*
Y924268D03*
X1429153Y914701D03*
Y921079D03*
X1438405Y937024D03*
X1429153Y940213D03*
X1434704Y937024D03*
X1425452Y940213D03*
Y927457D03*
X1429153D03*
X1438405Y943402D03*
Y956158D03*
X1429153Y946591D03*
Y952969D03*
X1438405Y949780D03*
X1434704Y943402D03*
Y956158D03*
X1425452Y946591D03*
Y952969D03*
X1434704Y949780D03*
X1438405Y962536D03*
X1429153Y965725D03*
Y959347D03*
X1438405Y968914D03*
X1434704Y962536D03*
X1425452Y965725D03*
Y959347D03*
X1434704Y968914D03*
X1438405Y975292D03*
X1429153Y972103D03*
Y978481D03*
X1434704Y975292D03*
X1425452Y972103D03*
Y978481D03*
X1430334Y1059945D03*
X1426633D03*
X1430334Y1066323D03*
Y1072701D03*
X1426633Y1066323D03*
Y1072701D03*
X1435885Y1063134D03*
Y1069512D03*
X1430334Y1079079D03*
X1426633D03*
X1435885Y1075890D03*
Y1088646D03*
X1430334Y1085457D03*
X1426633D03*
X1435885Y1082268D03*
Y1101402D03*
Y1095024D03*
X1430334Y1091835D03*
Y1098213D03*
X1426633Y1091835D03*
Y1098213D03*
Y1110969D03*
Y1117347D03*
X1435885Y1114158D03*
X1430334Y1110969D03*
Y1117347D03*
Y1130102D03*
X1426633D03*
Y1123725D03*
X1435885Y1126914D03*
Y1120536D03*
X1430334Y1123725D03*
X1435885Y1133292D03*
Y1146047D03*
Y1139669D03*
X1426633Y1136480D03*
Y1142858D03*
X1430334Y1136480D03*
Y1142858D03*
X1445806Y892379D03*
X1449507D03*
X1445806Y898757D03*
Y905134D03*
X1449507Y898757D03*
Y905134D03*
X1445806Y911512D03*
X1449507D03*
X1445806Y917890D03*
Y924268D03*
X1449507Y917890D03*
Y924268D03*
Y949780D03*
Y943402D03*
Y956158D03*
X1445806Y949780D03*
Y943402D03*
Y956158D03*
X1449507Y968914D03*
Y962536D03*
X1445806Y968914D03*
Y962536D03*
X1449507Y975292D03*
X1445806D03*
X1439586Y1063134D03*
Y1069512D03*
X1450688Y1063134D03*
Y1069512D03*
X1446987Y1063134D03*
Y1069512D03*
X1439586Y1075890D03*
X1450688D03*
X1446987D03*
X1439586Y1088646D03*
X1450688Y1082268D03*
X1446987D03*
X1439586D03*
X1450688Y1088646D03*
X1446987D03*
X1439586Y1101402D03*
Y1095024D03*
X1450688D03*
X1446987D03*
Y1114158D03*
X1439586D03*
X1450688D03*
X1446987Y1126914D03*
Y1120536D03*
X1439586Y1126914D03*
Y1120536D03*
X1450688Y1126914D03*
Y1120536D03*
X1446987Y1133292D03*
X1450688D03*
X1439586D03*
X1446987Y1139669D03*
X1450688D03*
X1446987Y1146047D03*
X1439586D03*
Y1139669D03*
X1450688Y1146047D03*
X1468011Y892379D03*
X1456909D03*
X1460609D03*
X1468011Y911512D03*
Y898757D03*
Y905134D03*
X1456909Y898757D03*
Y905134D03*
X1460609Y898757D03*
Y905134D03*
X1456909Y911512D03*
X1460609D03*
X1468011Y924268D03*
Y917890D03*
X1456909Y924268D03*
Y917890D03*
X1460609Y924268D03*
Y917890D03*
X1468011Y930646D03*
X1456909D03*
X1460609D03*
Y949780D03*
Y943402D03*
Y956158D03*
X1468011Y949780D03*
Y943402D03*
Y956158D03*
X1456909Y949780D03*
Y943402D03*
Y956158D03*
X1460609Y968914D03*
Y962536D03*
X1468011Y968914D03*
Y962536D03*
X1456909Y968914D03*
Y962536D03*
X1460609Y975292D03*
X1468011D03*
X1456909D03*
X1461791Y1063134D03*
Y1069512D03*
X1458090Y1063134D03*
Y1069512D03*
X1461791Y1075890D03*
X1458090D03*
X1461791Y1082268D03*
Y1088646D03*
X1458090Y1082268D03*
Y1088646D03*
X1461791Y1095024D03*
X1458090D03*
Y1114158D03*
Y1107780D03*
X1461791Y1114158D03*
Y1107780D03*
X1458090Y1133292D03*
X1461791D03*
X1458090Y1126914D03*
Y1120536D03*
X1461791Y1126914D03*
Y1120536D03*
X1458090Y1146047D03*
Y1139669D03*
X1461791Y1146047D03*
Y1139669D03*
X1461777Y1552698D03*
X1460202Y1549970D03*
X1464926D03*
X1466501Y1552698D03*
X1460202Y1563608D03*
X1464926D03*
X1461777Y1566336D03*
X1466501D03*
X1471712Y892379D03*
X1480964Y889190D03*
X1479113Y892379D03*
X1480964Y895568D03*
X1471712Y911512D03*
Y898757D03*
Y905134D03*
X1479113Y911512D03*
X1480964Y901946D03*
X1479113Y905134D03*
X1480964Y908324D03*
X1479113Y898757D03*
X1480964Y921079D03*
X1479113Y924268D03*
X1480964Y914701D03*
X1479113Y917890D03*
X1471712Y924268D03*
Y917890D03*
X1480964Y927457D03*
X1479113Y930646D03*
X1480964Y940213D03*
Y933835D03*
X1479113Y937024D03*
X1471712Y930646D03*
Y949780D03*
Y943402D03*
Y956158D03*
X1479113Y943402D03*
X1480964Y946591D03*
X1479113Y949780D03*
X1480964Y952969D03*
X1479113Y956158D03*
X1480964Y965725D03*
X1479113Y968914D03*
X1480964Y959347D03*
X1479113Y962536D03*
X1471712Y968914D03*
Y962536D03*
X1480964Y984859D03*
Y978481D03*
X1479113Y981670D03*
X1480964Y972103D03*
X1479113Y975292D03*
X1471712D03*
X1479113Y988048D03*
X1480964Y997615D03*
X1479113Y1000804D03*
X1480964Y991237D03*
Y1003993D03*
X1479113Y1007182D03*
X1480295Y1031244D03*
X1482145Y1034433D03*
X1480295Y1037622D03*
X1482145Y1040811D03*
X1480295Y1044000D03*
Y1050378D03*
X1482145Y1047189D03*
X1480295Y1063134D03*
X1482145Y1066323D03*
X1480295Y1069512D03*
X1482145Y1072701D03*
X1472893Y1063134D03*
Y1069512D03*
X1469192Y1063134D03*
Y1069512D03*
X1480295Y1075890D03*
X1482145Y1079079D03*
X1480295Y1082268D03*
X1482145Y1085457D03*
X1480295Y1088646D03*
X1472893Y1075890D03*
X1469192D03*
X1472893Y1082268D03*
Y1088646D03*
X1469192Y1082268D03*
Y1088646D03*
X1482145Y1104591D03*
X1480295Y1095024D03*
X1482145Y1098213D03*
X1480295Y1101402D03*
X1482145Y1091835D03*
X1472893Y1095024D03*
X1469192D03*
X1480295Y1114158D03*
X1482145Y1117347D03*
X1480295Y1107780D03*
X1482145Y1110969D03*
X1469192Y1107780D03*
Y1114158D03*
X1472893Y1107780D03*
Y1114158D03*
X1480295Y1120536D03*
X1482145Y1123725D03*
X1480295Y1133292D03*
Y1126914D03*
X1482145Y1130102D03*
X1469192Y1120536D03*
X1472893D03*
X1469192Y1133292D03*
Y1126914D03*
X1472893Y1133292D03*
Y1126914D03*
X1482145Y1136480D03*
X1480295Y1139669D03*
X1482145Y1142858D03*
X1480295Y1146047D03*
X1482145Y1149236D03*
X1469192Y1146047D03*
Y1139669D03*
X1472893Y1146047D03*
Y1139669D03*
X1480295Y1152425D03*
X1482145Y1155614D03*
X1479099Y1549970D03*
X1483824D03*
X1480674Y1552698D03*
X1469651Y1549970D03*
X1474375D03*
X1471225Y1552698D03*
X1475950D03*
X1469651Y1563608D03*
X1474375D03*
X1479099D03*
X1483824D03*
X1471225Y1566336D03*
X1475950D03*
X1480674D03*
X1486515Y886001D03*
X1484665Y889190D03*
Y895568D03*
X1486515Y892379D03*
X1497617Y886001D03*
X1492066Y889190D03*
X1493917Y892379D03*
X1492066Y895568D03*
X1497617Y892379D03*
X1484665Y908324D03*
X1486515Y898757D03*
X1484665Y901946D03*
X1486515Y905134D03*
Y911512D03*
X1493917D03*
X1497617Y898757D03*
X1492066Y901946D03*
X1493917Y905134D03*
X1497617D03*
X1492066Y908324D03*
X1497617Y911512D03*
X1493917Y898757D03*
X1486515Y917890D03*
X1484665Y921079D03*
X1486515Y924268D03*
X1484665Y914701D03*
X1497617Y917890D03*
X1492066Y921079D03*
X1493917Y924268D03*
X1497617D03*
X1492066Y914701D03*
X1493917Y917890D03*
X1484665Y927457D03*
X1486515Y937024D03*
X1484665Y940213D03*
Y933835D03*
X1486515Y930646D03*
X1492066Y927457D03*
X1493917Y930646D03*
X1497617Y937024D03*
X1492066Y940213D03*
Y933835D03*
X1497617Y930646D03*
X1493917Y937024D03*
X1486515Y943402D03*
X1484665Y946591D03*
X1486515Y956158D03*
X1484665Y952969D03*
X1486515Y949780D03*
X1493917Y943402D03*
X1497617D03*
X1492066Y946591D03*
X1493917Y949780D03*
X1497617Y956158D03*
X1492066Y952969D03*
X1497617Y949780D03*
X1493917Y956158D03*
X1486515Y962536D03*
X1484665Y965725D03*
Y959347D03*
X1486515Y968914D03*
X1497617Y962536D03*
X1492066Y965725D03*
X1493917Y968914D03*
X1492066Y959347D03*
X1493917Y962536D03*
X1497617Y968914D03*
X1486515Y975292D03*
X1484665Y978481D03*
Y972103D03*
X1492066Y984859D03*
X1497617Y975292D03*
X1492066Y978481D03*
X1493917Y981670D03*
X1492066Y972103D03*
X1493917Y975292D03*
X1486515Y994426D03*
X1484665Y997615D03*
X1486515Y1000804D03*
Y988048D03*
X1493917D03*
X1497617Y994426D03*
X1492066Y997615D03*
X1493917Y1000804D03*
X1497617D03*
Y988048D03*
X1492066Y991237D03*
X1484665Y1010371D03*
X1486515Y1007182D03*
X1484665Y1003993D03*
X1497617Y1007182D03*
X1492066Y1003993D03*
X1493917Y1007182D03*
X1485846Y1034433D03*
X1487696Y1037622D03*
X1485846Y1040811D03*
X1495098Y1031244D03*
X1493247Y1034433D03*
X1498799Y1037622D03*
X1495098D03*
X1493247Y1040811D03*
X1495098Y1044000D03*
X1485846Y1059945D03*
X1487696Y1050378D03*
X1485846Y1053567D03*
X1495098Y1050378D03*
X1493247Y1047189D03*
X1498799Y1050378D03*
X1485846Y1072701D03*
X1487696Y1063134D03*
Y1069512D03*
X1485846Y1066323D03*
X1495098Y1063134D03*
X1498799D03*
X1493247Y1066323D03*
X1495098Y1069512D03*
X1498799D03*
X1493247Y1072701D03*
X1487696Y1075890D03*
X1485846Y1079079D03*
X1487696Y1082268D03*
Y1088646D03*
X1485846Y1085457D03*
X1495098Y1075890D03*
X1498799D03*
X1493247Y1079079D03*
X1495098Y1082268D03*
X1498799D03*
X1493247Y1085457D03*
X1498799Y1088646D03*
X1495098D03*
X1487696Y1101402D03*
X1485846Y1091835D03*
X1487696Y1095024D03*
X1485846Y1098213D03*
Y1104591D03*
X1498799Y1101402D03*
X1493247Y1104591D03*
X1495098Y1095024D03*
X1498799D03*
X1493247Y1098213D03*
X1495098Y1101402D03*
X1493247Y1091835D03*
X1485846Y1110969D03*
X1487696Y1114158D03*
X1485846Y1117347D03*
X1487696Y1107780D03*
X1495098Y1114158D03*
X1498799D03*
X1493247Y1117347D03*
X1498799Y1107780D03*
X1495098D03*
X1493247Y1110969D03*
X1487696Y1120536D03*
X1485846Y1130102D03*
X1487696Y1133292D03*
Y1126914D03*
X1485846Y1123725D03*
X1495098Y1120536D03*
X1498799D03*
X1493247Y1123725D03*
X1495098Y1133292D03*
X1498799D03*
Y1126914D03*
X1495098D03*
X1493247Y1130102D03*
X1485846Y1136480D03*
X1487696Y1139669D03*
X1485846Y1149236D03*
X1487696Y1146047D03*
X1485846Y1142858D03*
X1493247Y1136480D03*
X1495098Y1139669D03*
X1498799D03*
X1493247Y1142858D03*
X1498799Y1146047D03*
X1495098D03*
X1493247Y1149236D03*
X1487696Y1152425D03*
X1495098D03*
X1498799D03*
X1497997Y1549970D03*
X1488548D03*
X1493273D03*
X1485399Y1552698D03*
X1490123D03*
X1494847D03*
X1488548Y1563608D03*
X1493273D03*
X1497997D03*
X1485399Y1566336D03*
X1490123D03*
X1494847D03*
X1512421Y886001D03*
X1506869Y889190D03*
X1510570D03*
X1505019Y892379D03*
X1510570Y895568D03*
X1506869D03*
X1512421Y892379D03*
X1499468Y889190D03*
Y895568D03*
X1510570Y908324D03*
X1505019Y911512D03*
X1512421Y898757D03*
X1506869Y901946D03*
X1510570D03*
X1505019Y905134D03*
X1512421D03*
X1506869Y908324D03*
X1512421Y911512D03*
X1505019Y898757D03*
X1499468Y908324D03*
Y901946D03*
X1512421Y917890D03*
X1506869Y921079D03*
X1510570D03*
X1505019Y924268D03*
X1512421D03*
X1510570Y914701D03*
X1506869D03*
X1505019Y917890D03*
X1499468Y921079D03*
Y914701D03*
X1506869Y927457D03*
X1510570D03*
X1505019Y930646D03*
X1512421Y937024D03*
X1506869Y940213D03*
X1510570D03*
Y933835D03*
X1506869D03*
X1512421Y930646D03*
X1505019Y937024D03*
X1499468Y927457D03*
Y940213D03*
Y933835D03*
X1505019Y943402D03*
X1512421D03*
X1506869Y946591D03*
X1510570D03*
X1505019Y949780D03*
X1512421Y956158D03*
X1510570Y952969D03*
X1506869D03*
X1512421Y949780D03*
X1505019Y956158D03*
X1499468Y946591D03*
Y952969D03*
X1512421Y962536D03*
X1506869Y965725D03*
X1510570D03*
X1505019Y968914D03*
X1506869Y959347D03*
X1510570D03*
X1505019Y962536D03*
X1512421Y968914D03*
X1499468Y965725D03*
Y959347D03*
X1506869Y984859D03*
X1512421Y975292D03*
X1506869Y978481D03*
X1510570D03*
X1505019Y981670D03*
X1510570Y972103D03*
X1506869D03*
X1505019Y975292D03*
X1499468Y978481D03*
Y972103D03*
X1505019Y988048D03*
X1512421Y994426D03*
X1510570Y997615D03*
X1506869D03*
X1505019Y1000804D03*
X1512421D03*
Y988048D03*
X1506869Y991237D03*
X1499468Y997615D03*
X1510570Y1010371D03*
X1512421Y1007182D03*
X1510570Y1003993D03*
X1506869D03*
X1505019Y1007182D03*
X1499468Y1010371D03*
Y1003993D03*
X1506200Y1031244D03*
X1508050Y1034433D03*
X1511751D03*
X1513602Y1037622D03*
X1506200D03*
X1508050Y1040811D03*
X1511751D03*
X1506200Y1044000D03*
X1500649Y1034433D03*
Y1040811D03*
X1506200Y1050378D03*
X1511751Y1059945D03*
X1508050Y1047189D03*
X1513602Y1050378D03*
X1511751Y1053567D03*
X1500649Y1059945D03*
Y1053567D03*
X1511751Y1072701D03*
X1506200Y1063134D03*
X1513602D03*
X1508050Y1066323D03*
X1506200Y1069512D03*
X1513602D03*
X1508050Y1072701D03*
X1511751Y1066323D03*
X1500649Y1072701D03*
Y1066323D03*
X1506200Y1075890D03*
X1513602D03*
X1508050Y1079079D03*
X1511751D03*
X1506200Y1082268D03*
X1513602D03*
X1508050Y1085457D03*
X1513602Y1088646D03*
X1506200D03*
X1511751Y1085457D03*
X1500649Y1079079D03*
Y1085457D03*
X1513602Y1101402D03*
X1508050Y1104591D03*
X1511751Y1091835D03*
X1506200Y1095024D03*
X1513602D03*
X1508050Y1098213D03*
X1511751D03*
X1506200Y1101402D03*
X1511751Y1104591D03*
X1508050Y1091835D03*
X1500649D03*
Y1098213D03*
Y1104591D03*
X1511751Y1110969D03*
X1506200Y1114158D03*
X1513602D03*
X1508050Y1117347D03*
X1511751D03*
X1513602Y1107780D03*
X1506200D03*
X1508050Y1110969D03*
X1500649D03*
Y1117347D03*
X1506200Y1120536D03*
X1513602D03*
X1508050Y1123725D03*
X1511751Y1130102D03*
X1506200Y1133292D03*
X1513602D03*
Y1126914D03*
X1506200D03*
X1511751Y1123725D03*
X1508050Y1130102D03*
X1500649D03*
Y1123725D03*
X1508050Y1136480D03*
X1511751D03*
X1506200Y1139669D03*
X1513602D03*
X1508050Y1142858D03*
X1511751Y1149236D03*
X1513602Y1146047D03*
X1506200D03*
X1511751Y1142858D03*
X1508050Y1149236D03*
X1500649Y1136480D03*
Y1149236D03*
Y1142858D03*
X1506200Y1152425D03*
X1513602D03*
X1508050Y1155614D03*
X1500649D03*
X1507446Y1549970D03*
X1512170D03*
X1502721D03*
X1509021Y1552698D03*
X1513745D03*
X1499572D03*
X1504296D03*
X1507446Y1563608D03*
X1512170D03*
X1502721D03*
X1509021Y1566336D03*
X1513745D03*
X1499572D03*
X1504296D03*
X1523523Y886001D03*
X1517972Y889190D03*
X1525373D03*
X1519822Y892379D03*
X1525373Y895568D03*
X1517972D03*
X1523523Y892379D03*
X1525373Y908324D03*
X1519822Y911512D03*
X1523523Y898757D03*
X1517972Y901946D03*
X1525373D03*
X1519822Y905134D03*
X1523523D03*
X1517972Y908324D03*
X1523523Y911512D03*
X1519822Y898757D03*
X1523523Y917890D03*
X1517972Y921079D03*
X1525373D03*
X1519822Y924268D03*
X1523523D03*
X1525373Y914701D03*
X1517972D03*
X1519822Y917890D03*
X1517972Y927457D03*
X1525373D03*
X1519822Y930646D03*
X1523523Y937024D03*
X1517972Y940213D03*
X1525373D03*
Y933835D03*
X1517972D03*
X1523523Y930646D03*
X1519822Y937024D03*
Y943402D03*
X1523523D03*
X1517972Y946591D03*
X1525373D03*
X1519822Y949780D03*
X1523523Y956158D03*
X1525373Y952969D03*
X1517972D03*
X1523523Y949780D03*
X1519822Y956158D03*
X1523523Y962536D03*
X1517972Y965725D03*
X1525373D03*
X1519822Y968914D03*
X1517972Y959347D03*
X1525373D03*
X1519822Y962536D03*
X1523523Y968914D03*
X1517972Y984859D03*
X1523523Y975292D03*
X1517972Y978481D03*
X1525373D03*
X1519822Y981670D03*
X1525373Y972103D03*
X1517972D03*
X1519822Y975292D03*
Y988048D03*
X1523523Y994426D03*
X1525373Y997615D03*
X1517972D03*
X1519822Y1000804D03*
X1523523D03*
Y988048D03*
X1517972Y991237D03*
X1525373Y1010371D03*
X1523523Y1007182D03*
X1525373Y1003993D03*
X1517972D03*
X1519822Y1007182D03*
X1521003Y1031244D03*
X1519153Y1034433D03*
X1526554D03*
X1524704Y1037622D03*
X1521003D03*
X1519153Y1040811D03*
X1526554D03*
X1521003Y1044000D03*
Y1050378D03*
X1526554Y1059945D03*
X1519153Y1047189D03*
X1524704Y1050378D03*
X1526554Y1053567D03*
Y1072701D03*
X1521003Y1063134D03*
X1524704D03*
X1519153Y1066323D03*
X1521003Y1069512D03*
X1524704D03*
X1519153Y1072701D03*
X1526554Y1066323D03*
X1521003Y1075890D03*
X1524704D03*
X1519153Y1079079D03*
X1526554D03*
X1521003Y1082268D03*
X1524704D03*
X1519153Y1085457D03*
X1524704Y1088646D03*
X1521003D03*
X1526554Y1085457D03*
X1524704Y1101402D03*
X1519153Y1104591D03*
X1526554Y1091835D03*
X1521003Y1095024D03*
X1524704D03*
X1519153Y1098213D03*
X1526554D03*
X1521003Y1101402D03*
X1526554Y1104591D03*
X1519153Y1091835D03*
X1526554Y1110969D03*
X1521003Y1114158D03*
X1524704D03*
X1519153Y1117347D03*
X1526554D03*
X1524704Y1107780D03*
X1521003D03*
X1519153Y1110969D03*
X1521003Y1120536D03*
X1524704D03*
X1519153Y1123725D03*
X1526554Y1130102D03*
X1521003Y1133292D03*
X1524704D03*
Y1126914D03*
X1521003D03*
X1526554Y1123725D03*
X1519153Y1130102D03*
Y1136480D03*
X1526554D03*
X1521003Y1139669D03*
X1524704D03*
X1519153Y1142858D03*
X1526554Y1149236D03*
X1524704Y1146047D03*
X1521003D03*
X1526554Y1142858D03*
X1519153Y1149236D03*
X1521003Y1152425D03*
X1524704D03*
X1526554Y1155614D03*
X1516895Y1549970D03*
X1521619D03*
X1526344D03*
X1518469Y1552698D03*
X1523194D03*
X1527918D03*
X1516895Y1563608D03*
X1521619D03*
X1526344D03*
X1518469Y1566336D03*
X1523194D03*
X1527918D03*
X1538326Y886001D03*
X1532775Y889190D03*
X1536476D03*
X1530925Y892379D03*
X1536476Y895568D03*
X1532775D03*
X1538326Y892379D03*
X1536476Y908324D03*
X1530925Y911512D03*
X1538326Y898757D03*
X1532775Y901946D03*
X1536476D03*
X1530925Y905134D03*
X1538326D03*
X1532775Y908324D03*
X1538326Y911512D03*
X1530925Y898757D03*
X1538326Y917890D03*
X1532775Y921079D03*
X1536476D03*
X1530925Y924268D03*
X1538326D03*
X1536476Y914701D03*
X1532775D03*
X1530925Y917890D03*
X1532775Y927457D03*
X1536476D03*
X1530925Y930646D03*
X1538326Y937024D03*
X1532775Y940213D03*
X1536476D03*
Y933835D03*
X1532775D03*
X1538326Y930646D03*
X1530925Y937024D03*
Y943402D03*
X1538326D03*
X1532775Y946591D03*
X1536476D03*
X1530925Y949780D03*
X1538326Y956158D03*
X1536476Y952969D03*
X1532775D03*
X1538326Y949780D03*
X1530925Y956158D03*
X1538326Y962536D03*
X1532775Y965725D03*
X1536476D03*
X1530925Y968914D03*
X1532775Y959347D03*
X1536476D03*
X1530925Y962536D03*
X1538326Y968914D03*
X1532775Y984859D03*
X1538326Y975292D03*
X1532775Y978481D03*
X1536476D03*
X1530925Y981670D03*
X1536476Y972103D03*
X1532775D03*
X1530925Y975292D03*
Y988048D03*
X1538326Y994426D03*
X1536476Y997615D03*
X1532775D03*
X1530925Y1000804D03*
X1538326D03*
Y988048D03*
X1532775Y991237D03*
X1536476Y1010371D03*
X1538326Y1007182D03*
X1536476Y1003993D03*
X1532775D03*
X1530925Y1007182D03*
X1532106Y1031244D03*
X1533956Y1034433D03*
X1537657D03*
X1539507Y1037622D03*
X1532106D03*
X1533956Y1040811D03*
X1537657D03*
X1532106Y1044000D03*
Y1050378D03*
X1537657Y1059945D03*
X1533956Y1047189D03*
X1539507Y1050378D03*
X1537657Y1053567D03*
Y1072701D03*
X1532106Y1063134D03*
X1539507D03*
X1533956Y1066323D03*
X1532106Y1069512D03*
X1539507D03*
X1533956Y1072701D03*
X1537657Y1066323D03*
X1532106Y1075890D03*
X1539507D03*
X1533956Y1079079D03*
X1537657D03*
X1532106Y1082268D03*
X1539507D03*
X1533956Y1085457D03*
X1539507Y1088646D03*
X1532106D03*
X1537657Y1085457D03*
X1539507Y1101402D03*
X1533956Y1104591D03*
X1537657Y1091835D03*
X1532106Y1095024D03*
X1539507D03*
X1533956Y1098213D03*
X1537657D03*
X1532106Y1101402D03*
X1537657Y1104591D03*
X1533956Y1091835D03*
X1537657Y1110969D03*
X1532106Y1114158D03*
X1539507D03*
X1533956Y1117347D03*
X1537657D03*
X1539507Y1107780D03*
X1532106D03*
X1533956Y1110969D03*
X1532106Y1120536D03*
X1539507D03*
X1533956Y1123725D03*
X1537657Y1130102D03*
X1532106Y1133292D03*
X1539507D03*
Y1126914D03*
X1532106D03*
X1537657Y1123725D03*
X1533956Y1130102D03*
Y1136480D03*
X1537657D03*
X1532106Y1139669D03*
X1539507D03*
X1533956Y1142858D03*
X1537657Y1149236D03*
X1539507Y1146047D03*
X1532106D03*
X1537657Y1142858D03*
X1533956Y1149236D03*
X1532106Y1152425D03*
X1539507D03*
X1533956Y1155614D03*
X1531068Y1549970D03*
X1532643Y1552698D03*
X1531068Y1563608D03*
X1532643Y1566336D03*
X1588264Y1549970D03*
Y1563608D03*
X1592988Y1549970D03*
X1597713D03*
X1602437D03*
X1589839Y1552698D03*
X1594563D03*
X1599287D03*
X1592988Y1563608D03*
X1597713D03*
X1602437D03*
X1589839Y1566336D03*
X1594563D03*
X1599287D03*
X1607161Y1549970D03*
X1611886D03*
X1616610D03*
X1604012Y1552698D03*
X1608736D03*
X1613461D03*
X1607161Y1563608D03*
X1611886D03*
X1616610D03*
X1604012Y1566336D03*
X1608736D03*
X1613461D03*
X1621335Y1549970D03*
X1626059D03*
X1630783D03*
X1618185Y1552698D03*
X1622909D03*
X1627634D03*
X1632358D03*
X1621335Y1563608D03*
X1626059D03*
X1630783D03*
X1618185Y1566336D03*
X1622909D03*
X1627634D03*
X1632358D03*
X1635508Y1549970D03*
X1640232D03*
X1644957D03*
X1637083Y1552698D03*
X1641807D03*
X1646531D03*
X1635508Y1563608D03*
X1640232D03*
X1644957D03*
X1637083Y1566336D03*
X1641807D03*
X1646531D03*
X1649681Y1549970D03*
X1654406D03*
X1659130D03*
X1651256Y1552698D03*
X1655980D03*
X1660705D03*
X1649681Y1563608D03*
X1654406D03*
X1659130D03*
X1651256Y1566336D03*
X1655980D03*
X1660705D03*
G54D34*
X230905Y1649173D03*
Y1653897D03*
Y1663346D03*
Y1668070D03*
Y1677519D03*
Y1682244D03*
Y1691692D03*
Y1696417D03*
Y1705866D03*
Y1710590D03*
X238779Y1653110D03*
Y1657834D03*
X246653Y1663346D03*
Y1668070D03*
Y1677519D03*
Y1682244D03*
X238779Y1681456D03*
Y1686180D03*
X246653Y1691692D03*
Y1696417D03*
X238779Y1695629D03*
Y1700354D03*
X246653Y1705866D03*
Y1710590D03*
X238779Y1709803D03*
Y1714527D03*
X254527Y1667283D03*
Y1672007D03*
Y1681456D03*
Y1686180D03*
Y1695629D03*
Y1700354D03*
Y1709803D03*
Y1714527D03*
X270275Y1653110D03*
Y1657834D03*
Y1667283D03*
Y1672007D03*
X262401Y1677519D03*
X270275Y1681456D03*
X262401Y1682244D03*
X270275Y1686180D03*
X262401Y1691692D03*
X270275Y1695629D03*
X262401Y1696417D03*
X270275Y1700354D03*
X262401Y1705866D03*
X270275Y1709803D03*
X262401Y1710590D03*
X270275Y1714527D03*
X278149Y1649173D03*
X286023Y1653110D03*
X278149Y1653897D03*
X286023Y1657834D03*
X278149Y1663346D03*
X286023Y1667283D03*
X278149Y1668070D03*
X286023Y1672007D03*
X278149Y1677519D03*
X286023Y1681456D03*
X278149Y1682244D03*
X286023Y1686180D03*
X278149Y1691692D03*
X286023Y1695629D03*
X278149Y1696417D03*
X286023Y1700354D03*
X278149Y1705866D03*
X286023Y1709803D03*
X278149Y1710590D03*
X286023Y1714527D03*
X297835Y1677519D03*
X305709Y1681456D03*
X297835Y1682244D03*
X305709Y1686180D03*
X297835Y1691692D03*
X305709Y1695629D03*
X297835Y1696417D03*
X305709Y1700354D03*
X297835Y1705866D03*
X305709Y1709803D03*
X297835Y1710590D03*
X305709Y1714527D03*
X313583Y1677519D03*
X321457Y1681456D03*
X313583Y1682244D03*
X321457Y1686180D03*
X313583Y1691692D03*
X321457Y1695629D03*
X313583Y1696417D03*
X321457Y1700354D03*
X313583Y1705866D03*
X321457Y1709803D03*
X313583Y1710590D03*
X321457Y1714527D03*
X329331Y1677519D03*
Y1682244D03*
Y1691692D03*
Y1696417D03*
Y1705866D03*
Y1710590D03*
X345079Y1677519D03*
Y1682244D03*
X337205Y1681456D03*
Y1686180D03*
X345079Y1691692D03*
Y1696417D03*
X337205Y1695629D03*
Y1700354D03*
X345079Y1705866D03*
Y1710590D03*
X337205Y1709803D03*
Y1714527D03*
X352953Y1681456D03*
Y1686180D03*
Y1695629D03*
Y1700354D03*
Y1709803D03*
Y1714527D03*
X495078Y1677519D03*
Y1682244D03*
Y1691692D03*
Y1696417D03*
Y1705866D03*
Y1710590D03*
X510826Y1677519D03*
Y1682244D03*
X502952Y1681456D03*
Y1686180D03*
X510826Y1691692D03*
Y1696417D03*
X502952Y1695629D03*
Y1700354D03*
X510826Y1705866D03*
Y1710590D03*
X502952Y1709803D03*
Y1714527D03*
X518700Y1681456D03*
Y1686180D03*
X526574Y1677519D03*
Y1682244D03*
X518700Y1695629D03*
Y1700354D03*
X526574Y1691692D03*
Y1696417D03*
X518700Y1709803D03*
Y1714527D03*
X526574Y1705866D03*
Y1710590D03*
X542322Y1677519D03*
Y1682244D03*
X534448Y1681456D03*
Y1686180D03*
X542322Y1691692D03*
Y1696417D03*
X534448Y1695629D03*
Y1700354D03*
X542322Y1705866D03*
Y1710590D03*
X534448Y1709803D03*
Y1714527D03*
X550196Y1681456D03*
Y1686180D03*
Y1695629D03*
Y1700354D03*
Y1709803D03*
Y1714527D03*
X562008Y1677519D03*
X569882Y1681456D03*
X562008Y1682244D03*
X569882Y1686180D03*
X562008Y1691692D03*
X569882Y1695629D03*
X562008Y1696417D03*
X569882Y1700354D03*
X562008Y1705866D03*
X569882Y1709803D03*
X562008Y1710590D03*
X569882Y1714527D03*
X577756Y1677519D03*
X585630Y1681456D03*
X577756Y1682244D03*
X585630Y1686180D03*
X577756Y1691692D03*
X585630Y1695629D03*
X577756Y1696417D03*
X585630Y1700354D03*
X577756Y1705866D03*
X585630Y1709803D03*
X577756Y1710590D03*
X585630Y1714527D03*
X593504Y1677519D03*
X601378Y1681456D03*
X593504Y1682244D03*
X601378Y1686180D03*
X593504Y1691692D03*
X601378Y1695629D03*
X593504Y1696417D03*
X601378Y1700354D03*
X593504Y1705866D03*
X601378Y1709803D03*
X593504Y1710590D03*
X601378Y1714527D03*
X609252Y1677519D03*
X617126Y1681456D03*
X609252Y1682244D03*
X617126Y1686180D03*
X609252Y1691692D03*
X617126Y1695629D03*
X609252Y1696417D03*
X617126Y1700354D03*
X609252Y1705866D03*
X617126Y1709803D03*
X609252Y1710590D03*
X617126Y1714527D03*
X1238778Y1677519D03*
Y1682244D03*
Y1691692D03*
Y1696417D03*
Y1705866D03*
Y1710590D03*
X1254526Y1677519D03*
Y1682244D03*
X1246652Y1681456D03*
Y1686180D03*
X1254526Y1691692D03*
Y1696417D03*
X1246652Y1695629D03*
Y1700354D03*
X1254526Y1705866D03*
Y1710590D03*
X1246652Y1709803D03*
Y1714527D03*
X1262400Y1681456D03*
Y1686180D03*
X1270274Y1677519D03*
Y1682244D03*
X1262400Y1695629D03*
Y1700354D03*
X1270274Y1691692D03*
Y1696417D03*
X1262400Y1709803D03*
Y1714527D03*
X1270274Y1705866D03*
Y1710590D03*
X1286022Y1677519D03*
Y1682244D03*
X1278148Y1681456D03*
Y1686180D03*
X1286022Y1691692D03*
Y1696417D03*
X1278148Y1695629D03*
Y1700354D03*
X1286022Y1705866D03*
Y1710590D03*
X1278148Y1709803D03*
Y1714527D03*
X1293896Y1681456D03*
Y1686180D03*
Y1695629D03*
Y1700354D03*
Y1709803D03*
Y1714527D03*
X1305708Y1677519D03*
X1313582Y1681456D03*
X1305708Y1682244D03*
X1313582Y1686180D03*
X1305708Y1691692D03*
X1313582Y1695629D03*
X1305708Y1696417D03*
X1313582Y1700354D03*
X1305708Y1705866D03*
X1313582Y1709803D03*
X1305708Y1710590D03*
X1313582Y1714527D03*
X1321456Y1677519D03*
X1329330Y1681456D03*
X1321456Y1682244D03*
X1329330Y1686180D03*
X1321456Y1691692D03*
X1329330Y1695629D03*
X1321456Y1696417D03*
X1329330Y1700354D03*
X1321456Y1705866D03*
X1329330Y1709803D03*
X1321456Y1710590D03*
X1329330Y1714527D03*
X1337204Y1677519D03*
X1345078Y1681456D03*
X1337204Y1682244D03*
X1345078Y1686180D03*
X1337204Y1691692D03*
X1345078Y1695629D03*
X1337204Y1696417D03*
X1345078Y1700354D03*
X1337204Y1705866D03*
X1345078Y1709803D03*
X1337204Y1710590D03*
X1345078Y1714527D03*
X1352952Y1677519D03*
X1360826Y1681456D03*
X1352952Y1682244D03*
X1360826Y1686180D03*
X1352952Y1691692D03*
X1360826Y1695629D03*
X1352952Y1696417D03*
X1360826Y1700354D03*
X1352952Y1705866D03*
X1360826Y1709803D03*
X1352952Y1710590D03*
X1360826Y1714527D03*
X1502952Y1677519D03*
X1510826Y1681456D03*
X1502952Y1682244D03*
X1510826Y1686180D03*
X1502952Y1691692D03*
X1510826Y1695629D03*
X1502952Y1696417D03*
X1510826Y1700354D03*
X1502952Y1705866D03*
X1510826Y1709803D03*
X1502952Y1710590D03*
X1510826Y1714527D03*
X1518700Y1677519D03*
X1526574Y1681456D03*
X1518700Y1682244D03*
X1526574Y1686180D03*
X1518700Y1691692D03*
X1526574Y1695629D03*
X1518700Y1696417D03*
X1526574Y1700354D03*
X1518700Y1705866D03*
X1526574Y1709803D03*
X1518700Y1710590D03*
X1526574Y1714527D03*
X1534448Y1677519D03*
X1542322Y1681456D03*
X1534448Y1682244D03*
X1542322Y1686180D03*
X1534448Y1691692D03*
X1542322Y1695629D03*
X1534448Y1696417D03*
X1542322Y1700354D03*
X1534448Y1705866D03*
X1542322Y1709803D03*
X1534448Y1710590D03*
X1542322Y1714527D03*
X1550196Y1677519D03*
X1558070Y1681456D03*
X1550196Y1682244D03*
X1558070Y1686180D03*
X1550196Y1691692D03*
X1558070Y1695629D03*
X1550196Y1696417D03*
X1558070Y1700354D03*
X1550196Y1705866D03*
X1558070Y1709803D03*
X1550196Y1710590D03*
X1558070Y1714527D03*
X1569882Y1677519D03*
Y1682244D03*
Y1691692D03*
Y1696417D03*
Y1705866D03*
Y1710590D03*
X1585630Y1677519D03*
Y1682244D03*
X1577756Y1681456D03*
Y1686180D03*
X1585630Y1691692D03*
Y1696417D03*
X1577756Y1695629D03*
Y1700354D03*
X1585630Y1705866D03*
Y1710590D03*
X1577756Y1709803D03*
Y1714527D03*
X1593504Y1681456D03*
Y1686180D03*
X1601378Y1677519D03*
Y1682244D03*
X1593504Y1695629D03*
Y1700354D03*
X1601378Y1691692D03*
Y1696417D03*
X1593504Y1709803D03*
Y1714527D03*
X1601378Y1705866D03*
Y1710590D03*
X1617126Y1677519D03*
Y1682244D03*
X1609252Y1681456D03*
Y1686180D03*
X1617126Y1691692D03*
Y1696417D03*
X1609252Y1695629D03*
Y1700354D03*
X1617126Y1705866D03*
Y1710590D03*
X1609252Y1709803D03*
Y1714527D03*
X1625000Y1681456D03*
Y1686180D03*
Y1695629D03*
Y1700354D03*
Y1709803D03*
Y1714527D03*
G54D50*
X676509Y145866D03*
G54D35*
X230905Y1720039D03*
Y1724763D03*
Y1734212D03*
X238779Y1643661D03*
X246653Y1649173D03*
Y1653897D03*
X238779Y1667283D03*
Y1672007D03*
X246653Y1720039D03*
Y1724763D03*
X238779Y1723976D03*
Y1728700D03*
X246653Y1734212D03*
X254527Y1643661D03*
Y1653110D03*
Y1657834D03*
Y1723976D03*
Y1728700D03*
X270275Y1643661D03*
X262401Y1649173D03*
Y1653897D03*
Y1663346D03*
Y1668070D03*
Y1720039D03*
X270275Y1723976D03*
X262401Y1724763D03*
X270275Y1728700D03*
X262401Y1734212D03*
X286023Y1643661D03*
X278149Y1720039D03*
X286023Y1723976D03*
X278149Y1724763D03*
X286023Y1728700D03*
X278149Y1734212D03*
X305709Y1672007D03*
X297835Y1720039D03*
X305709Y1723976D03*
X297835Y1724763D03*
X305709Y1728700D03*
X297835Y1734212D03*
X321457Y1672007D03*
X313583Y1720039D03*
X321457Y1723976D03*
X313583Y1724763D03*
X321457Y1728700D03*
X313583Y1734212D03*
X329331Y1720039D03*
Y1724763D03*
Y1734212D03*
X337205Y1672007D03*
X345079Y1720039D03*
Y1724763D03*
X337205Y1723976D03*
Y1728700D03*
X345079Y1734212D03*
X352953Y1672007D03*
Y1723976D03*
Y1728700D03*
X495078Y1720039D03*
Y1724763D03*
Y1734212D03*
X502952Y1672007D03*
X510826Y1720039D03*
Y1724763D03*
X502952Y1723976D03*
Y1728700D03*
X510826Y1734212D03*
X518700Y1672007D03*
Y1723976D03*
Y1728700D03*
X526574Y1720039D03*
Y1724763D03*
Y1734212D03*
X534448Y1672007D03*
X542322Y1720039D03*
Y1724763D03*
X534448Y1723976D03*
Y1728700D03*
X542322Y1734212D03*
X550196Y1672007D03*
Y1723976D03*
Y1728700D03*
X569882Y1672007D03*
X562008Y1720039D03*
X569882Y1723976D03*
X562008Y1724763D03*
X569882Y1728700D03*
X562008Y1734212D03*
X585630Y1672007D03*
X577756Y1720039D03*
X585630Y1723976D03*
X577756Y1724763D03*
X585630Y1728700D03*
X577756Y1734212D03*
X601378Y1672007D03*
X593504Y1720039D03*
X601378Y1723976D03*
X593504Y1724763D03*
X601378Y1728700D03*
X593504Y1734212D03*
X617126Y1672007D03*
X609252Y1720039D03*
X617126Y1723976D03*
X609252Y1724763D03*
X617126Y1728700D03*
X609252Y1734212D03*
X1238778Y1720039D03*
Y1724763D03*
Y1734212D03*
X1246652Y1672007D03*
X1254526Y1720039D03*
Y1724763D03*
X1246652Y1723976D03*
Y1728700D03*
X1254526Y1734212D03*
X1262400Y1672007D03*
Y1723976D03*
Y1728700D03*
X1270274Y1720039D03*
Y1724763D03*
Y1734212D03*
X1278148Y1672007D03*
X1286022Y1720039D03*
Y1724763D03*
X1278148Y1723976D03*
Y1728700D03*
X1286022Y1734212D03*
X1293896Y1672007D03*
Y1723976D03*
Y1728700D03*
X1313582Y1672007D03*
X1305708Y1720039D03*
X1313582Y1723976D03*
X1305708Y1724763D03*
X1313582Y1728700D03*
X1305708Y1734212D03*
X1329330Y1672007D03*
X1321456Y1720039D03*
X1329330Y1723976D03*
X1321456Y1724763D03*
X1329330Y1728700D03*
X1321456Y1734212D03*
X1345078Y1672007D03*
X1337204Y1720039D03*
X1345078Y1723976D03*
X1337204Y1724763D03*
X1345078Y1728700D03*
X1337204Y1734212D03*
X1360826Y1672007D03*
X1352952Y1720039D03*
X1360826Y1723976D03*
X1352952Y1724763D03*
X1360826Y1728700D03*
X1352952Y1734212D03*
X1510826Y1672007D03*
X1502952Y1720039D03*
X1510826Y1723976D03*
X1502952Y1724763D03*
X1510826Y1728700D03*
X1502952Y1734212D03*
X1526574Y1672007D03*
X1518700Y1720039D03*
X1526574Y1723976D03*
X1518700Y1724763D03*
X1526574Y1728700D03*
X1518700Y1734212D03*
X1542322Y1672007D03*
X1534448Y1720039D03*
X1542322Y1723976D03*
X1534448Y1724763D03*
X1542322Y1728700D03*
X1534448Y1734212D03*
X1558070Y1672007D03*
X1550196Y1720039D03*
X1558070Y1723976D03*
X1550196Y1724763D03*
X1558070Y1728700D03*
X1550196Y1734212D03*
X1569882Y1720039D03*
Y1724763D03*
Y1734212D03*
X1577756Y1672007D03*
X1585630Y1720039D03*
Y1724763D03*
X1577756Y1723976D03*
Y1728700D03*
X1585630Y1734212D03*
X1593504Y1672007D03*
Y1723976D03*
Y1728700D03*
X1601378Y1720039D03*
Y1724763D03*
Y1734212D03*
X1609252Y1672007D03*
X1617126Y1720039D03*
Y1724763D03*
X1609252Y1723976D03*
Y1728700D03*
X1617126Y1734212D03*
X1625000Y1672007D03*
Y1723976D03*
Y1728700D03*
G54D74*
X1859986Y1403418D03*
X1859706Y1709011D03*
X1871790Y476573D03*
X1861790D03*
X1870648Y783729D03*
X1860648D03*
X1862295Y850767D03*
X1872295D03*
X1871790Y1158071D03*
X1861790D03*
X1869986Y1403418D03*
X1869706Y1709011D03*
X1881862Y107291D03*
X1882340Y410829D03*
X1882711Y476864D03*
X1882240Y783474D03*
X1883273Y850816D03*
X1882579Y1158348D03*
X1881223Y1404467D03*
X1881177Y1709323D03*
X1891862Y107291D03*
X1892340Y410829D03*
X1892711Y476864D03*
X1892240Y783474D03*
X1893273Y850816D03*
X1892579Y1158348D03*
X1891223Y1404467D03*
X1891177Y1709323D03*
X2082012Y108312D03*
X2072012D03*
X2071128Y410829D03*
X2081128D03*
G54D13*
X27559Y87795D03*
X40708Y631889D03*
Y1368908D03*
X51180Y1714961D03*
X373622Y87795D03*
X395671Y1714960D03*
X661024Y631890D03*
X707677Y1714960D03*
X800787Y87795D03*
X931693Y757874D03*
X931692Y1072835D03*
X931693Y1387795D03*
X1045866Y87795D03*
X1155709Y1714961D03*
X1271260Y631890D03*
X1461806Y1714961D03*
X1499606Y87795D03*
X1806298Y1714961D03*
X1829921Y87795D03*
X1816772Y631889D03*
Y1368897D03*
G54D37*
X277098Y185236D03*
X395208D03*
G54D65*
X1183858Y217205D03*
X1173858D03*
X1193858D03*
G54D47*
X443467Y594259D03*
X1425533Y601230D03*
G54D16*
X27048Y1533228D03*
X79590Y1369350D03*
X137284Y1533228D03*
X215418Y658055D03*
X276440Y1357539D03*
X420125Y656008D03*
X443764Y1339823D03*
X523173Y578174D03*
X681440Y1385138D03*
X791678D03*
X873622Y1145275D03*
X983858D03*
X1052960Y1369350D03*
X1249812Y1357539D03*
X1370284Y582303D03*
X1417134Y1339823D03*
X1533552Y682342D03*
X1629732Y1383523D03*
X1664890Y642972D03*
X1714330Y1570984D03*
X1739968Y1383527D03*
X1761575Y159134D03*
X1824566Y1570988D03*
X1838150Y201929D03*
G54D52*
X757184Y1702772D03*
X1072863Y1409176D03*
X1080970Y1640958D03*
G54D66*
X1225530Y60384D03*
G54D73*
X1835198Y1601502D03*
G54D77*
X1864986Y1390234D03*
X1886862Y94107D03*
X1887711Y463680D03*
X1888273Y837632D03*
G54D75*
X1866790Y463389D03*
X1867295Y837583D03*
X1886223Y1391283D03*
X2077012Y95128D03*
G54D39*
X303154Y879624D03*
Y886002D03*
X305004Y882813D03*
X303154Y892380D03*
Y898758D03*
X310555Y873246D03*
X317957Y879624D03*
X310555D03*
X319807Y876435D03*
X314256Y873246D03*
X310555Y886002D03*
X314256D03*
X316107Y882813D03*
Y889191D03*
X308705D03*
X319807Y882813D03*
X314256Y892380D03*
X308705Y895569D03*
Y882813D03*
X314256Y898758D03*
X316107Y901947D03*
X308705D03*
Y908325D03*
X314256Y911513D03*
X316107Y908325D03*
X314256Y917891D03*
X308705Y914702D03*
Y921080D03*
X316107D03*
Y940214D03*
X308705Y927458D03*
X316107D03*
X308705Y933836D03*
X314256Y930647D03*
Y937025D03*
X308705Y940214D03*
X314256Y949781D03*
X316107Y946592D03*
X308705D03*
Y952970D03*
X314256Y956159D03*
X316107Y959348D03*
X308705D03*
Y965726D03*
X316107D03*
X314256Y968915D03*
X317957Y981671D03*
X308705Y978482D03*
X316107D03*
X314256Y975293D03*
X308705Y972104D03*
X316107Y984860D03*
X308705D03*
X312406D03*
X319807D03*
X308705Y991238D03*
X310555Y988049D03*
X314256D03*
X316107Y997616D03*
X308705D03*
X314256Y994427D03*
X316107Y1003994D03*
X314256Y1007183D03*
X316107Y1010372D03*
X308705D03*
Y1003994D03*
X327209Y876435D03*
X332760Y879624D03*
X325358D03*
X334598Y872066D03*
X334610Y882813D03*
X321658Y886002D03*
X325358D03*
X330910Y882813D03*
X329059Y886002D03*
X334610Y889191D03*
X327209D03*
X334610Y895569D03*
X321658Y892380D03*
X327209Y895569D03*
X329059Y892380D03*
X334610Y901947D03*
X321658Y898758D03*
X327209Y901947D03*
X329059Y898758D03*
X321658Y905135D03*
Y911513D03*
X329059Y905135D03*
Y911513D03*
X327209Y908325D03*
X334610Y908324D03*
Y914702D03*
X321658Y917891D03*
X327209Y914702D03*
X329059Y917891D03*
X334610Y921080D03*
X321658Y924269D03*
X329059D03*
X327209Y921080D03*
X334610Y927458D03*
Y933836D03*
X321658Y930647D03*
X327209Y927458D03*
Y933836D03*
X329059Y930647D03*
X334610Y940214D03*
X321658Y937025D03*
X327209Y940214D03*
X329059Y937025D03*
Y956159D03*
X334610Y946592D03*
X321658Y943403D03*
Y949781D03*
X329059Y943403D03*
Y949781D03*
X327209Y946592D03*
X334610Y952970D03*
X321658Y956159D03*
X327209Y952970D03*
X334610Y959348D03*
Y965726D03*
X329059Y962537D03*
X327209Y965726D03*
X321658Y962537D03*
X327209Y959348D03*
X321658Y968915D03*
X329059D03*
X334610Y972104D03*
Y978482D03*
X321658Y975293D03*
Y981671D03*
X329059Y975293D03*
X327209Y972104D03*
X332760Y981671D03*
X329059D03*
X327209Y978482D03*
X334610Y984860D03*
X327209D03*
X330910D03*
X334610Y991238D03*
Y997616D03*
X321658Y988049D03*
Y994427D03*
X327209Y991238D03*
X329059Y988049D03*
Y994427D03*
X327209Y997616D03*
X321658Y1000805D03*
X329059D03*
X334610Y1003994D03*
Y1010372D03*
X321658Y1007183D03*
X327209Y1010372D03*
X329059Y1007183D03*
X327209Y1003994D03*
X343862Y879624D03*
X340162Y879568D03*
X345713Y882813D03*
X336461Y886002D03*
X340162D03*
X347563D03*
X342012Y882813D03*
X347563Y892380D03*
X342012Y889191D03*
X340162Y892380D03*
X347563Y898758D03*
Y905135D03*
Y911513D03*
X342012Y901947D03*
X340162Y898758D03*
Y911513D03*
X342012Y908325D03*
X347563Y917891D03*
Y924269D03*
X340162Y917891D03*
X342012Y921080D03*
X347563Y930647D03*
Y937025D03*
X342012Y927458D03*
X340162Y930647D03*
X342012Y940214D03*
X340162Y937025D03*
X347563Y943403D03*
Y949781D03*
Y956159D03*
X340162Y949781D03*
X342012Y946592D03*
X340162Y956159D03*
X347563Y962537D03*
Y968915D03*
X342012Y959348D03*
Y965726D03*
X340162Y968915D03*
X347563Y975293D03*
Y981671D03*
X345713Y984860D03*
X340162Y975293D03*
X343862Y981671D03*
X342012Y978482D03*
Y984860D03*
X347563Y988049D03*
Y994427D03*
Y1000805D03*
X340162Y988049D03*
X342012Y997616D03*
X340162Y994427D03*
X347563Y1007183D03*
X342012Y1010372D03*
X340162Y1007183D03*
X342012Y1003994D03*
X351265Y879568D03*
X360516Y876435D03*
X354965Y879624D03*
X356803Y872066D03*
X351264Y886002D03*
X362366D03*
X356815Y882813D03*
X360516D03*
X353114D03*
X354965Y886002D03*
Y892380D03*
X360516Y889191D03*
Y895569D03*
X353114Y889191D03*
Y895569D03*
X354965Y898758D03*
X360516Y901947D03*
X353114D03*
X354965Y911513D03*
Y905135D03*
X360516Y908325D03*
X353114Y908324D03*
X354965Y917891D03*
X360516Y914702D03*
X353114D03*
X354965Y924269D03*
X360516Y921080D03*
X353114D03*
X354965Y930647D03*
X360516Y927458D03*
Y933836D03*
X353114D03*
Y927458D03*
X354965Y937025D03*
X360516Y940214D03*
X353114D03*
X360516Y946592D03*
X353114D03*
X360516Y952970D03*
X353114D03*
X354965Y956159D03*
Y943403D03*
Y949781D03*
X360516Y959348D03*
Y965726D03*
X353114Y959348D03*
Y965726D03*
X354965Y962537D03*
Y968915D03*
Y975293D03*
Y981671D03*
X360516Y972104D03*
Y978482D03*
X358665Y981671D03*
X353114Y972104D03*
Y978482D03*
X360516Y984860D03*
X356815D03*
X353114D03*
X360516Y997616D03*
Y991238D03*
X353114D03*
Y997616D03*
X354965Y988049D03*
Y994427D03*
Y1000805D03*
Y1007183D03*
X360516Y1003994D03*
X353114D03*
X360516Y1010372D03*
X353114D03*
X369768Y879624D03*
X373469D03*
X375319Y876435D03*
X377169Y879624D03*
X366067Y886002D03*
Y892380D03*
X367917Y889191D03*
X373469Y892380D03*
X367917Y882813D03*
X373469Y886002D03*
X379020Y882813D03*
X377169Y886002D03*
X379020Y895569D03*
X366067Y898758D03*
Y911513D03*
X367917Y901947D03*
X373469Y898758D03*
X379020Y908325D03*
X373469Y911513D03*
Y905135D03*
X367917Y908324D03*
X366067Y917891D03*
X373469D03*
X367917Y921080D03*
X373469Y924269D03*
X379020Y921080D03*
X366067Y930647D03*
Y937025D03*
X367917Y927458D03*
X379020Y933836D03*
X373469Y930647D03*
X367917Y940214D03*
X373469Y937025D03*
X379020Y940214D03*
X366067Y949781D03*
Y956159D03*
X367917Y946592D03*
X373469Y943403D03*
Y949781D03*
Y956159D03*
X379020Y952970D03*
X366067Y968915D03*
X367917Y959348D03*
Y965726D03*
X373469Y962537D03*
Y968915D03*
X379020Y965726D03*
X366067Y975293D03*
X369768Y981671D03*
X367917Y978482D03*
X373469Y975293D03*
Y981671D03*
X367917Y984860D03*
X379020D03*
X371618D03*
X379020Y978482D03*
X366067Y994427D03*
Y988049D03*
X367917Y997616D03*
X379020Y991238D03*
X373469Y988049D03*
X379020Y997616D03*
X373469Y994427D03*
Y1000805D03*
X366067Y1007183D03*
X373469D03*
X367917Y1003994D03*
X379020D03*
X367917Y1010372D03*
X386421Y876435D03*
X388272Y879624D03*
X384571Y873246D03*
X382721Y882813D03*
Y889191D03*
X380870Y892380D03*
X384571Y886002D03*
X386421Y882813D03*
X393823D03*
X388272Y886002D03*
X390122Y882813D03*
X391973Y892380D03*
X390122Y895569D03*
X386421Y889191D03*
X393823D03*
X382721Y901947D03*
X380870Y898758D03*
Y911513D03*
Y905135D03*
X393823Y901947D03*
X391973Y898758D03*
X390122Y901947D03*
X386421D03*
X391973Y905135D03*
Y911513D03*
X390122Y908325D03*
X382721Y914702D03*
X380870Y917891D03*
Y924269D03*
X386421Y914702D03*
X391973Y917891D03*
X393823Y914702D03*
X390122D03*
Y921080D03*
X391973Y924269D03*
X382721Y927458D03*
Y933836D03*
X380870Y930647D03*
X386421Y927458D03*
Y933836D03*
X393823Y927458D03*
X390122D03*
X393823Y933836D03*
X391973Y930647D03*
X390122Y933836D03*
Y940214D03*
X382721Y946592D03*
X380870Y943403D03*
Y949781D03*
Y956159D03*
X386421Y946592D03*
X391973Y943403D03*
Y949781D03*
X393823Y946592D03*
X390122D03*
X391973Y956159D03*
X390122Y952970D03*
X382721Y959348D03*
X380870Y962537D03*
Y968915D03*
X393823Y959348D03*
X390122D03*
Y965726D03*
X386421Y959348D03*
X391973Y962537D03*
Y968915D03*
X386421Y984860D03*
X382721Y972104D03*
X380870Y975293D03*
X393823Y972104D03*
X390122D03*
Y978482D03*
X384571Y981671D03*
X391973D03*
Y975293D03*
X386421Y972104D03*
X393823Y984860D03*
X391973Y988049D03*
X384571Y994427D03*
Y988049D03*
X391973Y994427D03*
X393823Y991238D03*
X386421D03*
Y997616D03*
X391973Y1000805D03*
X384571D03*
X393823Y997616D03*
X386421Y1003994D03*
X382721Y1010372D03*
X390122D03*
X391973Y1007183D03*
X393823Y1003994D03*
X395673Y1007183D03*
X384571D03*
X410477Y873246D03*
X397524Y876435D03*
X399374Y873246D03*
Y879624D03*
X397524Y882813D03*
Y889191D03*
X401225Y882813D03*
X408626D03*
X404925D03*
X401225Y895569D03*
X408626Y889191D03*
X404925D03*
X403075Y892380D03*
X397524Y901947D03*
X401225D03*
X408626D03*
X404925D03*
X403075Y898758D03*
Y905135D03*
Y911513D03*
X401225Y908324D03*
X397524Y914702D03*
X401225D03*
X408626D03*
X403075Y917891D03*
X404925Y914702D03*
X401225Y921080D03*
X403075Y924269D03*
X401225Y933836D03*
X408626Y927458D03*
X404925D03*
X403075Y930647D03*
X401225Y940214D03*
X397524Y927458D03*
Y933836D03*
X401225Y927458D03*
X397524Y946592D03*
X401225D03*
X403075Y943403D03*
X408626Y946592D03*
X403075Y949781D03*
X404925Y946592D03*
X401225Y952970D03*
X403075Y956159D03*
X397524Y959348D03*
X401225Y965726D03*
Y959348D03*
X408626D03*
X404925D03*
X403075Y962537D03*
Y968915D03*
X397524Y972104D03*
X401225D03*
X408626D03*
X404925D03*
X399374Y981671D03*
X406776D03*
X401225Y978482D03*
X403075Y975293D03*
X401225Y984860D03*
X408626D03*
Y991238D03*
X399374Y988049D03*
Y994427D03*
X406776Y988049D03*
X401225Y991238D03*
Y997616D03*
X399374Y1000805D03*
X397524Y1010372D03*
X399374Y1007183D03*
X401225Y1003994D03*
X421579Y873246D03*
X412327Y882813D03*
Y895569D03*
X414177Y892380D03*
X419729Y882813D03*
X416028D03*
X423429Y895569D03*
X425280Y892380D03*
X416028Y889191D03*
X419729D03*
X412327Y901947D03*
X414177Y898758D03*
Y905135D03*
Y911513D03*
X412327Y908325D03*
X423429Y901947D03*
X425280Y898758D03*
X419729Y901947D03*
X416028D03*
X425280Y905135D03*
Y911513D03*
X423429Y908324D03*
X414177Y917891D03*
X412327Y914702D03*
X414177Y924269D03*
X412327Y921080D03*
X423429Y914702D03*
X419729D03*
X416028D03*
X425280Y917891D03*
Y924269D03*
X423429Y921080D03*
X412327Y927458D03*
Y933836D03*
X414177Y930647D03*
X412327Y940214D03*
X414177Y937025D03*
X423429Y927458D03*
X419729D03*
X423429Y933836D03*
X425280Y930647D03*
X419729Y933836D03*
X416028Y927458D03*
Y933836D03*
X425280Y937025D03*
X423429Y940214D03*
X414177Y949781D03*
X412327Y946592D03*
X414177Y943403D03*
X412327Y952970D03*
X414177Y956159D03*
X416028Y946592D03*
X425280Y943403D03*
Y949781D03*
X423429Y946592D03*
X419729D03*
X423429Y952970D03*
X425280Y956159D03*
X412327Y965726D03*
Y959348D03*
X414177Y962537D03*
Y968915D03*
X423429Y965726D03*
X416028Y959348D03*
X423429D03*
X419729D03*
X425280Y962537D03*
Y968915D03*
X416028Y972104D03*
X423429D03*
X419729D03*
X416028Y984860D03*
X423429D03*
X412327Y978482D03*
X414177Y981671D03*
Y975293D03*
X412327Y972104D03*
X423429Y978482D03*
X421579Y981671D03*
X425280Y975293D03*
X414177Y988049D03*
X421579D03*
X423429Y991238D03*
X416028D03*
X434532Y876435D03*
X432681Y879624D03*
X430831Y882813D03*
X427130D03*
X430831Y889191D03*
X427130D03*
X434532Y895569D03*
Y889191D03*
X428981Y905135D03*
X434532Y901947D03*
X432681Y905135D03*
X434532Y908325D03*
X428981Y917891D03*
X432681D03*
X434532Y914702D03*
Y921080D03*
X428981Y930647D03*
Y937025D03*
X432681Y930647D03*
X434532Y927458D03*
Y933836D03*
X432681Y937025D03*
X434532Y940214D03*
X428981Y949781D03*
X432681D03*
X434532Y946592D03*
Y952970D03*
X428981Y962537D03*
X432681D03*
X434532Y959348D03*
Y965726D03*
X428981Y981671D03*
Y975293D03*
X430831Y984860D03*
X434532Y972104D03*
X432681Y975293D03*
X434532Y978482D03*
X430831Y991238D03*
X428981Y988049D03*
X445609Y876435D03*
X447460Y879624D03*
X445609Y882813D03*
Y889191D03*
Y895569D03*
X453011Y882813D03*
X449310Y889191D03*
X453011D03*
X454861Y892380D03*
X445609Y901947D03*
Y908325D03*
X454861Y898758D03*
X451160Y905135D03*
X454861D03*
Y911513D03*
X447460Y905135D03*
X445609Y914702D03*
Y921080D03*
X447460Y917891D03*
X451160D03*
X454861D03*
Y924269D03*
Y930647D03*
X447460Y937025D03*
X451160D03*
X454861D03*
X445609Y927458D03*
Y933836D03*
Y940214D03*
X447460Y930647D03*
X451160D03*
X445609Y946592D03*
Y952970D03*
X447460Y949781D03*
X454861Y943403D03*
X451160Y949781D03*
X454861D03*
Y956159D03*
X445609Y959348D03*
Y965726D03*
X454861Y962537D03*
X451160D03*
X447460D03*
X454861Y968915D03*
X445609Y972104D03*
Y978482D03*
Y984860D03*
X447460Y981671D03*
X454861D03*
X451160Y975293D03*
X447460D03*
X454861D03*
X453011Y984860D03*
X445609Y991238D03*
X453011D03*
X454861Y988049D03*
X447460D03*
X460412Y876435D03*
X469664Y879624D03*
X460412Y889191D03*
X456712Y895569D03*
X467814Y882813D03*
X465964Y892380D03*
X467814Y895569D03*
X464113Y889191D03*
X456712Y908324D03*
X465964Y911513D03*
X456712Y901947D03*
X460412D03*
X465964Y898758D03*
X467814Y901947D03*
X464113D03*
X467814Y908325D03*
X465964Y905135D03*
X460412Y914702D03*
X456712D03*
Y921080D03*
X467814Y914702D03*
X464113D03*
X465964Y917891D03*
X467814Y921080D03*
X465964Y924269D03*
X460412Y927458D03*
X456712D03*
Y933836D03*
X460412D03*
X456712Y940214D03*
X467814Y927458D03*
Y933836D03*
X464113Y927458D03*
Y933836D03*
X467814Y940214D03*
X465964Y937025D03*
X460412Y946592D03*
X456712D03*
Y952970D03*
X467814Y946592D03*
X464113D03*
X465964Y943403D03*
Y949781D03*
X467814Y952970D03*
X465964Y956159D03*
X456712Y965726D03*
X460412Y959348D03*
X456712D03*
X467814Y965726D03*
Y959348D03*
X465964Y962537D03*
X464113Y959348D03*
X465964Y968915D03*
X456712Y972104D03*
Y978482D03*
X462263Y981671D03*
X460412Y972104D03*
Y984860D03*
X469664Y981671D03*
X467814Y978482D03*
Y972104D03*
X465964Y975293D03*
X464113Y972104D03*
X467814Y984860D03*
X460412Y991238D03*
X462263Y988049D03*
X469664D03*
X467814Y991238D03*
X471515Y876435D03*
X480767Y873246D03*
Y879624D03*
X482617Y876435D03*
X478916Y882813D03*
X475215D03*
X471515D03*
X478916Y895569D03*
X477066Y892380D03*
X475215Y889191D03*
X471515D03*
X482617Y882813D03*
Y889191D03*
X478916Y901947D03*
X471515D03*
X475215D03*
X477066Y898758D03*
X478916Y908325D03*
X477066Y905135D03*
Y911513D03*
X482617Y901947D03*
X478916Y914702D03*
X477066Y917891D03*
X475215Y914702D03*
X471515D03*
X478916Y921080D03*
X477066Y924269D03*
X482617Y914702D03*
X478916Y927458D03*
Y933836D03*
X475215Y927458D03*
X471515D03*
X477066Y930647D03*
X478916Y940214D03*
X482617Y927458D03*
Y933836D03*
X478916Y946592D03*
X477066Y943403D03*
X475215Y946592D03*
X471515D03*
X477066Y949781D03*
X478916Y952970D03*
X477066Y956159D03*
X482617Y946592D03*
X478916Y965726D03*
Y959348D03*
X475215D03*
X471515D03*
X477066Y962537D03*
Y968915D03*
X482617Y959348D03*
X478916Y978482D03*
Y972104D03*
X477066Y981671D03*
Y975293D03*
X475215Y972104D03*
X471515D03*
X475215Y984860D03*
X484467Y981671D03*
X482617Y972104D03*
Y984860D03*
X477066Y994427D03*
X475215Y991238D03*
X477066Y988049D03*
Y1000805D03*
X484467Y994427D03*
Y988049D03*
X482617Y991238D03*
Y997616D03*
X484467Y1000805D03*
X477066Y1007183D03*
X484467D03*
X482617Y1010372D03*
Y1003994D03*
X493719Y876435D03*
X491869Y879624D03*
X493719Y882813D03*
X490019D03*
X486318D03*
X493719Y889191D03*
X486318D03*
X490019Y895569D03*
X488168Y892380D03*
X497420Y889191D03*
X499271Y892380D03*
X493719Y901947D03*
X486318D03*
X490019D03*
X488168Y898758D03*
Y905135D03*
Y911513D03*
X497420Y901947D03*
X499271Y898758D03*
Y905135D03*
Y911513D03*
X490019Y908324D03*
X493719Y914702D03*
X488168Y917891D03*
X490019Y914702D03*
X486318D03*
X490019Y921080D03*
X488168Y924269D03*
X499271Y917891D03*
X497420Y914702D03*
X499271Y924269D03*
X493719Y927458D03*
X486318D03*
X490019D03*
X493719Y933836D03*
X490019D03*
X486318D03*
X488168Y930647D03*
X490019Y940214D03*
X497420Y927458D03*
Y933836D03*
X499271Y930647D03*
X488168Y943403D03*
X493719Y946592D03*
X490019D03*
X486318D03*
X488168Y949781D03*
X490019Y952970D03*
X488168Y956159D03*
X497420Y946592D03*
X499271Y943403D03*
Y949781D03*
Y956159D03*
X490019Y965726D03*
X493719Y959348D03*
X490019D03*
X486318D03*
X488168Y962537D03*
Y968915D03*
X499271Y962537D03*
X497420Y959348D03*
X499271Y968915D03*
X491869Y981671D03*
X490019Y978482D03*
X493719Y972104D03*
X488168Y975293D03*
X490019Y972104D03*
X486318D03*
X490019Y984860D03*
X497420Y972104D03*
X499271Y975293D03*
Y981671D03*
X497420Y984860D03*
X491869Y994427D03*
Y988049D03*
X490019Y997616D03*
Y991238D03*
X491869Y1000805D03*
X497420Y991238D03*
Y997616D03*
X499271Y988049D03*
Y994427D03*
Y1000805D03*
X491869Y1007183D03*
X490019Y1010372D03*
Y1003994D03*
X497420Y1010372D03*
Y1003994D03*
X499271Y1007183D03*
X502971Y879624D03*
X501133Y872118D03*
X508523Y882813D03*
X506672Y886002D03*
X502971D03*
X504822Y882813D03*
X506672Y892380D03*
X501121Y895569D03*
X512223Y882813D03*
X514074Y886002D03*
X512223Y889191D03*
X514074Y892380D03*
X506672Y898758D03*
Y905135D03*
Y911513D03*
X501121Y908325D03*
X512223Y901947D03*
X514074Y898758D03*
Y911513D03*
X512223Y908325D03*
X506672Y917891D03*
X501121Y921080D03*
X506672Y924269D03*
X514074Y917891D03*
X512223Y921080D03*
X506672Y930647D03*
X501121Y933836D03*
X506672Y937025D03*
X501121Y940214D03*
X512223Y927458D03*
X514074Y930647D03*
X512223Y940214D03*
X514074Y937025D03*
X506672Y943403D03*
Y949781D03*
X501121Y952970D03*
X506672Y956159D03*
X514074Y949781D03*
X512223Y946592D03*
X514074Y956159D03*
X506672Y962537D03*
X501121Y965726D03*
X506672Y968915D03*
X512223Y959348D03*
Y965726D03*
X514074Y968915D03*
X510373Y981671D03*
X506672Y975293D03*
Y981671D03*
X501121Y978482D03*
X508523Y984860D03*
X514074Y975293D03*
X512223Y978482D03*
Y984860D03*
X506672Y988049D03*
Y994427D03*
Y1000805D03*
X514074Y988049D03*
Y994427D03*
X512223Y997616D03*
X506672Y1007183D03*
X514074D03*
X512223Y1003994D03*
X525176Y879624D03*
X515924Y876435D03*
X525176Y873246D03*
Y886002D03*
X523326Y882813D03*
X517775Y886002D03*
X519625Y882813D03*
X527027Y895569D03*
Y889191D03*
X525176Y892380D03*
X519625Y889191D03*
Y895569D03*
X528877Y886002D03*
X527027Y901947D03*
X525176Y898758D03*
X519625Y901947D03*
X525176Y905135D03*
Y911513D03*
X519625Y908325D03*
X527027Y908324D03*
X525176Y917891D03*
X519625Y914702D03*
X527027D03*
Y921080D03*
X525176Y924269D03*
X519625Y921080D03*
X525176Y937025D03*
X527027Y927458D03*
Y933836D03*
X525176Y930647D03*
X519625Y927458D03*
Y933836D03*
X527027Y940214D03*
X519625D03*
X527027Y946592D03*
X519625D03*
X525176Y943403D03*
Y949781D03*
X527027Y952970D03*
X525176Y956159D03*
X519625Y952970D03*
X527027Y959348D03*
Y965726D03*
X525176Y962537D03*
X519625Y959348D03*
Y965726D03*
X525176Y968915D03*
X521475Y981671D03*
X519625Y978482D03*
X527027Y984860D03*
X523326D03*
X519625D03*
X527027Y972104D03*
Y978482D03*
X525176Y975293D03*
Y981671D03*
X519625Y972104D03*
X527027Y991238D03*
Y997616D03*
X525176Y988049D03*
Y994427D03*
X519625Y991238D03*
Y997616D03*
X525176Y1000805D03*
X527027Y1010372D03*
Y1003994D03*
X525176Y1007183D03*
X519625Y1010372D03*
Y1003994D03*
X534428Y876435D03*
X539979Y879624D03*
X532578D03*
X541830Y876435D03*
X543680Y879624D03*
X538129Y889191D03*
X539979Y892380D03*
X532578D03*
X543680Y886002D03*
X538129Y882813D03*
X532578Y886002D03*
X534428Y882813D03*
X538129Y901947D03*
X539979Y898758D03*
X532578D03*
X539979Y911513D03*
X538129Y908325D03*
X532578Y905135D03*
Y911513D03*
X539979Y917891D03*
X532578D03*
X538129Y921080D03*
X532578Y924269D03*
X538129Y927458D03*
X539979Y930647D03*
X532578D03*
X539979Y937025D03*
X538129Y940214D03*
X532578Y937025D03*
X539979Y949781D03*
X538129Y946592D03*
X532578Y943403D03*
Y949781D03*
X539979Y956159D03*
X532578D03*
X538129Y959348D03*
Y965726D03*
X532578Y962537D03*
X539979Y968915D03*
X532578D03*
X539979Y975293D03*
X532578D03*
X538129Y978482D03*
X536279Y981671D03*
X532578D03*
X538129Y984860D03*
X534428D03*
X532578Y994427D03*
X539979Y988049D03*
X532578D03*
X539979Y994427D03*
X538129Y997616D03*
X532578Y1000805D03*
X539978Y1007184D03*
X538129Y1003994D03*
X532578Y1007183D03*
X545531Y876435D03*
X552932D03*
X556633D03*
X551082Y879624D03*
X545543Y872085D03*
X554783Y886002D03*
X549231Y882813D03*
X558483Y892380D03*
X545531Y889191D03*
Y895569D03*
X552932Y889191D03*
X551082Y892380D03*
X552932Y895569D03*
X558483Y886002D03*
X545531Y882813D03*
X551082Y886002D03*
X558483Y898758D03*
X545531Y901947D03*
X552932D03*
X551082Y898758D03*
X558483Y905135D03*
Y911513D03*
X551082Y905135D03*
Y911513D03*
X552932Y908325D03*
X545531Y908324D03*
X558483Y917891D03*
X551082D03*
X552932Y914702D03*
X545531D03*
X558483Y924269D03*
X551082D03*
X552932Y921080D03*
X545531D03*
X558483Y930647D03*
X545531Y927458D03*
Y933836D03*
X552932Y927458D03*
Y933836D03*
X551082Y930647D03*
X558483Y937025D03*
X545531Y940214D03*
X551082Y937025D03*
X552932Y940214D03*
X558483Y943403D03*
Y949781D03*
X545531Y946592D03*
X551082Y943403D03*
Y949781D03*
X552932Y946592D03*
X558483Y956159D03*
X545531Y952970D03*
X552932D03*
X551082Y956159D03*
X558483Y962537D03*
X545531Y959348D03*
Y965726D03*
X552932Y959348D03*
X551082Y962537D03*
X552932Y965726D03*
X558483Y968915D03*
X551082D03*
X558483Y975293D03*
Y981671D03*
X545531Y972104D03*
Y978482D03*
X547381Y981671D03*
X551082Y975293D03*
X552932Y972104D03*
X551082Y981671D03*
X552932Y978482D03*
Y984860D03*
X549231D03*
X545531D03*
X558483Y988049D03*
Y994427D03*
X552932Y991238D03*
X551082Y994427D03*
X552932Y997616D03*
X545531Y991238D03*
Y997616D03*
X551082Y988049D03*
X558483Y1000805D03*
X551082D03*
X558483Y1007183D03*
X545531Y1010372D03*
Y1003994D03*
X552932Y1010372D03*
X551082Y1007183D03*
X552932Y1003994D03*
X562184Y879624D03*
X569586Y873246D03*
X560334Y882813D03*
X564034D03*
X569586Y886002D03*
X571436Y882813D03*
Y889191D03*
X564034D03*
X565885Y892380D03*
X571436Y895569D03*
X564034Y901947D03*
X571436D03*
X565885Y898758D03*
X564034Y908325D03*
X571436D03*
X565885Y911513D03*
Y917891D03*
X571436Y914702D03*
X564034Y921080D03*
X571436D03*
X564034Y927458D03*
X571436D03*
X565885Y930647D03*
X571436Y933836D03*
X565885Y937025D03*
X564034Y940214D03*
X571436D03*
X565885Y949781D03*
X564034Y946592D03*
X571436D03*
Y952970D03*
X565885Y956159D03*
X564034Y959348D03*
X571436D03*
X564034Y965726D03*
X571436D03*
X565885Y968915D03*
X562184Y981671D03*
X565885Y975293D03*
X571436Y972104D03*
X564034Y978482D03*
X571436D03*
X567735Y984860D03*
X560334D03*
X564034D03*
X571436D03*
X569586Y988049D03*
X571436Y991238D03*
X565885Y994427D03*
X564034Y997616D03*
X571436D03*
X565885Y988049D03*
X571436Y1010372D03*
X565885Y1007183D03*
X564034Y1003994D03*
X571436D03*
X576987Y879624D03*
X575137Y882813D03*
X576987Y886002D03*
Y892380D03*
Y898758D03*
X1286697Y873245D03*
Y879623D03*
X1279296D03*
X1284847Y895568D03*
Y882812D03*
X1286697Y886001D03*
X1281146Y882812D03*
X1279296Y886001D03*
X1284847Y889190D03*
X1279296Y892379D03*
X1284847Y901946D03*
X1279296Y898757D03*
X1284847Y908324D03*
Y914701D03*
Y921079D03*
Y927457D03*
Y933835D03*
Y940213D03*
Y946591D03*
Y952969D03*
Y959347D03*
Y965725D03*
Y972103D03*
Y978481D03*
Y984859D03*
X1288548D03*
X1284847Y991237D03*
X1286697Y988048D03*
X1284847Y997615D03*
Y1010371D03*
Y1003993D03*
X1290398Y873245D03*
X1301500Y879623D03*
X1303351Y876434D03*
X1294099Y879623D03*
X1295949Y876434D03*
X1303351Y895568D03*
X1290398Y886001D03*
Y892379D03*
X1292249Y882812D03*
X1297800Y886001D03*
X1301500D03*
X1295949Y882812D03*
X1292249Y889190D03*
X1303351D03*
X1297800Y892379D03*
X1290398Y898757D03*
Y911512D03*
X1292249Y901946D03*
X1297800Y898757D03*
X1303351Y901946D03*
X1292249Y908324D03*
X1297800Y905134D03*
Y911512D03*
X1303351Y908324D03*
X1290398Y917890D03*
X1297800D03*
X1303351Y914701D03*
Y921079D03*
X1297800Y924268D03*
X1292249Y921079D03*
X1297800Y930646D03*
X1303351Y927457D03*
Y933835D03*
X1292249Y927457D03*
X1303351Y940213D03*
X1297800Y937024D03*
X1292249Y940213D03*
X1290398Y930646D03*
Y937024D03*
Y949780D03*
Y956158D03*
X1297800Y949780D03*
X1303351Y946591D03*
X1292249D03*
X1297800Y943402D03*
X1303351Y952969D03*
X1297800Y956158D03*
X1290398Y968914D03*
X1297800Y962536D03*
X1303351Y959347D03*
Y965725D03*
X1292249Y959347D03*
Y965725D03*
X1297800Y968914D03*
X1290398Y975292D03*
X1297800Y981670D03*
Y975292D03*
X1303351Y972103D03*
Y978481D03*
X1294099Y981670D03*
X1292249Y978481D03*
X1303351Y984859D03*
X1295949D03*
X1292249D03*
X1290398Y988048D03*
Y994426D03*
X1297800D03*
Y988048D03*
X1303351Y991237D03*
Y997615D03*
X1292249D03*
X1297800Y1000804D03*
X1290398Y1007182D03*
X1292249Y1010371D03*
X1297800Y1007182D03*
X1303351Y1010371D03*
Y1003993D03*
X1292249D03*
X1314453Y876434D03*
X1308902Y873245D03*
Y879623D03*
X1310752Y895568D03*
X1307052Y882812D03*
X1305201Y886001D03*
Y892379D03*
X1310752Y882812D03*
X1312603Y886001D03*
X1316304D03*
X1318154Y882812D03*
X1310752Y889190D03*
X1318154D03*
X1316304Y892379D03*
X1305201Y898757D03*
Y905134D03*
Y911512D03*
X1310752Y901946D03*
X1318154D03*
X1316304Y898757D03*
Y911512D03*
X1318154Y908324D03*
X1310752Y908323D03*
X1305201Y917890D03*
Y924268D03*
X1310752Y914701D03*
X1316304Y917890D03*
X1318154Y921079D03*
X1310752D03*
X1305201Y930646D03*
Y937024D03*
X1310752Y927457D03*
Y933835D03*
X1318154Y927457D03*
X1316304Y930646D03*
Y937024D03*
X1310752Y940213D03*
X1318154D03*
X1305201Y943402D03*
Y949780D03*
Y956158D03*
X1310752Y946591D03*
X1316304Y949780D03*
X1318154Y946591D03*
X1310752Y952969D03*
X1316304Y956158D03*
X1318154Y959347D03*
Y965725D03*
X1316304Y968914D03*
X1305201Y962536D03*
Y968914D03*
X1310752Y959347D03*
Y965725D03*
X1305201Y975292D03*
Y981670D03*
X1307052Y984859D03*
X1310752Y972103D03*
Y978481D03*
X1316304Y975292D03*
X1318154Y978481D03*
X1308902Y981670D03*
X1310752Y984859D03*
X1318154D03*
X1305201Y988048D03*
Y994426D03*
Y1000804D03*
X1310752Y991237D03*
Y997615D03*
X1316304Y988048D03*
X1318154Y997615D03*
X1316304Y994426D03*
X1305201Y1007182D03*
X1310752Y1003993D03*
Y1010371D03*
X1318154D03*
X1316304Y1007182D03*
X1318154Y1003993D03*
X1320004Y879623D03*
X1331107Y873245D03*
X1325556Y876434D03*
X1331107Y879623D03*
X1321855Y882812D03*
X1323705Y886001D03*
X1329256Y882812D03*
X1332957D03*
X1331107Y886001D03*
X1327406D03*
X1323705Y892379D03*
X1329256Y889190D03*
X1331107Y892379D03*
X1329256Y895568D03*
X1323705Y898757D03*
X1331107D03*
X1329256Y901946D03*
X1331107Y911512D03*
X1323705D03*
Y905134D03*
X1331107D03*
X1329256Y908323D03*
Y914701D03*
X1323705Y917890D03*
X1331107D03*
X1323705Y924268D03*
X1329256Y921079D03*
X1331107Y924268D03*
Y930646D03*
X1329256Y933835D03*
X1323705Y930646D03*
X1329256Y927457D03*
X1331107Y937024D03*
X1329256Y940213D03*
X1323705Y937024D03*
X1331107Y943402D03*
X1329256Y946591D03*
X1331107Y949780D03*
X1323705Y943402D03*
Y949780D03*
X1329256Y952969D03*
X1331107Y956158D03*
X1323705D03*
X1329256Y959347D03*
X1331107Y962536D03*
X1329256Y965725D03*
X1323705Y962536D03*
X1331107Y968914D03*
X1323705D03*
X1320004Y981670D03*
X1321855Y984859D03*
X1323705Y975292D03*
Y981670D03*
X1329256Y972103D03*
X1331107Y975292D03*
X1329256Y978481D03*
X1331107Y981670D03*
X1334807D03*
X1329256Y984859D03*
X1332957D03*
X1323705Y1000804D03*
Y988048D03*
Y994426D03*
X1329256Y997615D03*
X1331107Y988048D03*
X1329256Y991237D03*
X1331107Y994426D03*
Y1000804D03*
X1323705Y1007182D03*
X1329256Y1003993D03*
X1331107Y1007182D03*
X1329256Y1010371D03*
X1336658Y876434D03*
X1345910Y879623D03*
X1349611D03*
X1338508Y886001D03*
X1336658Y882812D03*
Y889190D03*
Y895568D03*
X1342209Y886001D03*
X1349611D03*
X1344059Y882812D03*
Y889190D03*
X1342209Y892379D03*
X1349611D03*
X1336658Y901946D03*
Y908324D03*
X1342209Y898757D03*
X1349611D03*
X1344059Y901946D03*
X1349611Y905134D03*
X1342209Y911512D03*
X1349611D03*
X1344059Y908323D03*
X1336658Y914701D03*
Y921079D03*
X1342209Y917890D03*
X1349611D03*
X1344059Y921079D03*
X1349611Y924268D03*
X1336658Y933835D03*
Y927457D03*
Y940213D03*
X1344059Y927457D03*
X1342209Y930646D03*
X1349611D03*
X1344059Y940213D03*
X1342209Y937024D03*
X1349611D03*
Y943402D03*
X1344059Y946591D03*
X1349611Y949780D03*
X1342209D03*
X1349611Y956158D03*
X1342209D03*
X1336658Y946591D03*
Y952969D03*
Y965725D03*
Y959347D03*
X1344059D03*
X1349611Y962536D03*
X1344059Y965725D03*
X1349611Y968914D03*
X1342209D03*
X1336658Y972103D03*
Y978481D03*
Y984859D03*
X1349611Y975292D03*
X1342209D03*
X1344059Y978481D03*
X1349611Y981670D03*
X1345910D03*
X1344059Y984859D03*
X1347760D03*
X1336658Y997615D03*
Y991237D03*
X1349611Y988048D03*
Y994426D03*
X1342209D03*
X1344059Y997615D03*
X1342209Y988048D03*
X1349611Y1000804D03*
X1336658Y1010371D03*
X1344059D03*
X1336658Y1003993D03*
X1344059D03*
X1342209Y1007182D03*
X1349611D03*
X1351461Y876434D03*
X1353311Y879623D03*
X1364414D03*
X1360713Y873245D03*
X1362563Y876434D03*
X1353311Y886001D03*
X1362563Y882812D03*
X1358863D03*
X1364414Y886001D03*
X1360713D03*
X1355162Y882812D03*
X1357012Y892379D03*
X1355162Y895568D03*
X1362563Y889190D03*
X1358863D03*
X1357012Y898757D03*
X1362563Y901946D03*
X1358863D03*
X1357012Y905134D03*
Y911512D03*
X1355162Y908324D03*
X1358863Y914701D03*
X1362563D03*
X1357012Y917890D03*
X1355162Y921079D03*
X1357012Y924268D03*
X1362563Y933835D03*
X1358863D03*
X1355162D03*
X1362563Y927457D03*
X1358863D03*
X1357012Y930646D03*
X1355162Y940213D03*
X1357012Y943402D03*
X1358863Y946591D03*
X1362563D03*
X1357012Y949780D03*
Y956158D03*
X1355162Y952969D03*
X1358863Y959347D03*
X1362563D03*
X1357012Y962536D03*
X1355162Y965725D03*
X1357012Y968914D03*
X1358863Y972103D03*
X1362563D03*
X1357012Y975292D03*
X1360713Y981670D03*
X1355162Y978481D03*
X1362563Y984859D03*
X1355162D03*
Y991237D03*
Y997615D03*
X1362563Y991237D03*
Y997615D03*
X1360713Y994426D03*
Y988048D03*
Y1000804D03*
X1358863Y1010371D03*
X1360713Y1007182D03*
X1362563Y1003993D03*
X1355162D03*
X1373666Y876434D03*
X1375516Y873245D03*
Y879623D03*
X1369965Y882812D03*
X1366264D03*
X1369965Y889190D03*
X1368115Y892379D03*
X1366264Y895568D03*
X1373666Y882812D03*
X1377367D03*
X1379217Y892379D03*
X1377367Y895568D03*
X1373666Y889190D03*
X1368115Y898757D03*
X1369965Y901946D03*
X1366264D03*
X1368115Y905134D03*
Y911512D03*
X1366264Y908324D03*
X1379217Y898757D03*
X1377367Y901946D03*
X1373666D03*
X1379217Y905134D03*
X1377367Y908324D03*
X1379217Y911512D03*
X1369965Y914701D03*
X1368115Y917890D03*
X1366264Y914701D03*
X1368115Y924268D03*
X1366264Y921079D03*
X1377367Y914701D03*
X1373666D03*
X1379217Y917890D03*
X1377367Y921079D03*
X1379217Y924268D03*
X1366264Y933835D03*
X1369965Y927457D03*
X1368115Y930646D03*
X1369965Y933835D03*
X1366264Y927457D03*
Y940213D03*
X1377367Y927457D03*
X1373666D03*
X1379217Y930646D03*
X1377367Y933835D03*
X1373666D03*
X1377367Y940213D03*
X1368115Y943402D03*
X1369965Y946591D03*
X1368115Y949780D03*
X1366264Y946591D03*
X1368115Y956158D03*
X1366264Y952969D03*
X1379217Y943402D03*
X1373666Y946591D03*
X1377367D03*
X1379217Y949780D03*
X1377367Y952969D03*
X1379217Y956158D03*
X1366264Y959347D03*
X1369965D03*
X1368115Y962536D03*
X1366264Y965725D03*
X1368115Y968914D03*
X1373666Y959347D03*
X1377367Y965725D03*
Y959347D03*
X1379217Y962536D03*
Y968914D03*
X1369965Y972103D03*
X1368115Y975292D03*
Y981670D03*
X1366264Y972103D03*
Y978481D03*
X1369965Y984859D03*
X1373666Y972103D03*
X1377367D03*
X1379217Y975292D03*
X1375516Y981670D03*
X1377367Y978481D03*
Y984859D03*
X1369965Y991237D03*
Y997615D03*
X1368115Y994426D03*
Y988048D03*
Y1000804D03*
X1375516Y994426D03*
X1377367Y991237D03*
Y997615D03*
X1375516Y988048D03*
Y1000804D03*
X1369965Y1003993D03*
X1368115Y1007182D03*
X1366264Y1010371D03*
X1373666D03*
X1375516Y1007182D03*
X1371815D03*
X1377367Y1003993D03*
X1386619Y879623D03*
X1382918Y873245D03*
X1384768Y876434D03*
X1394020Y873245D03*
X1384768Y882812D03*
X1381067D03*
Y889190D03*
X1384768D03*
X1392170Y882812D03*
X1388469D03*
Y895568D03*
X1392170Y889190D03*
X1390319Y892379D03*
X1381067Y901946D03*
X1384768D03*
X1388469D03*
X1390319Y898757D03*
X1392170Y901946D03*
X1388469Y908324D03*
X1390319Y911512D03*
Y905134D03*
X1381067Y914701D03*
X1384768D03*
X1390319Y917890D03*
X1388469Y914701D03*
X1392170D03*
X1388469Y921079D03*
X1390319Y924268D03*
X1381067Y927457D03*
X1384768D03*
X1388469D03*
Y933835D03*
X1392170Y927457D03*
X1390319Y930646D03*
X1392170Y933835D03*
X1388469Y940213D03*
X1390319Y937024D03*
X1381067Y946591D03*
X1384768D03*
X1388469D03*
X1390319Y943402D03*
X1392170Y946591D03*
X1390319Y949780D03*
X1388469Y952969D03*
X1390319Y956158D03*
X1381067Y959347D03*
X1384768D03*
X1388469Y965725D03*
Y959347D03*
X1392170D03*
X1390319Y962536D03*
Y968914D03*
X1388469Y978481D03*
X1381067Y972103D03*
X1384768D03*
X1382918Y981670D03*
X1384768Y984859D03*
X1388469Y972103D03*
X1392170D03*
X1390319Y981670D03*
Y975292D03*
X1392170Y984859D03*
X1384768Y991237D03*
X1382918Y988048D03*
X1392170Y991237D03*
X1390319Y988048D03*
X1397721Y873245D03*
Y879623D03*
X1395871Y876434D03*
X1408823Y879623D03*
X1399571Y882812D03*
X1395871D03*
X1401422Y892379D03*
X1399571Y895568D03*
X1395871Y889190D03*
X1403272Y882812D03*
X1406973D03*
X1403272Y889190D03*
X1406973D03*
X1399571Y901946D03*
X1395871D03*
X1401422Y905134D03*
Y911512D03*
X1405123Y905134D03*
X1408823D03*
X1401422Y898757D03*
X1399571Y908323D03*
Y914701D03*
X1401422Y917890D03*
X1395871Y914701D03*
X1399571Y921079D03*
X1401422Y924268D03*
X1405123Y917890D03*
X1408823D03*
X1395871Y927457D03*
Y933835D03*
X1399571Y927457D03*
X1401422Y930646D03*
X1399571Y933835D03*
Y940213D03*
X1401422Y937024D03*
X1405123Y930646D03*
X1408823D03*
X1405123Y937024D03*
X1408823D03*
X1401422Y943402D03*
X1399571Y946591D03*
X1401422Y949780D03*
X1399571Y952969D03*
X1401422Y956158D03*
X1408823Y949780D03*
X1405123D03*
X1395871Y946591D03*
X1399571Y965725D03*
X1395871Y959347D03*
X1399571D03*
X1401422Y962536D03*
Y968914D03*
X1408823Y962536D03*
X1405123D03*
X1397721Y981670D03*
X1399571Y978481D03*
X1395871Y972103D03*
X1399571D03*
X1401422Y975292D03*
X1399571Y984859D03*
X1405123Y981670D03*
X1408823Y975292D03*
X1405123D03*
X1406973Y984859D03*
X1399571Y991237D03*
X1397721Y988048D03*
X1406973Y991237D03*
X1405123Y988048D03*
X1410674Y876434D03*
X1423602Y879623D03*
X1421751Y876434D03*
X1410674Y882812D03*
Y889190D03*
Y895568D03*
X1421751Y882812D03*
Y895568D03*
Y889190D03*
X1410674Y901946D03*
Y908324D03*
X1421751Y901946D03*
X1423602Y905134D03*
X1421751Y908324D03*
X1410674Y914701D03*
Y921079D03*
X1423602Y917890D03*
X1421751Y914701D03*
Y921079D03*
Y940213D03*
X1410674Y927457D03*
Y933835D03*
Y940213D03*
X1423602Y930646D03*
X1421751Y927457D03*
Y933835D03*
X1423602Y937024D03*
X1410674Y946591D03*
Y952969D03*
X1423602Y949780D03*
X1421751Y946591D03*
Y952969D03*
X1410674Y959347D03*
Y965725D03*
X1423602Y962536D03*
X1421751Y959347D03*
Y965725D03*
X1410674Y972103D03*
Y978481D03*
X1423602Y981670D03*
Y975292D03*
X1421751Y972103D03*
Y978481D03*
Y984859D03*
X1423602Y988048D03*
X1421751Y991237D03*
X1436554Y876434D03*
X1429153Y882812D03*
X1425452Y889190D03*
X1429153D03*
X1431003Y892379D03*
X1432854Y895568D03*
X1436554Y889190D03*
X1432854Y901946D03*
X1431003Y898757D03*
Y911512D03*
Y905134D03*
X1427302D03*
X1436554Y901946D03*
X1432854Y908323D03*
Y914701D03*
X1431003Y917890D03*
X1427302D03*
X1432854Y921079D03*
X1431003Y924268D03*
X1436554Y914701D03*
X1432854Y927457D03*
X1431003Y930646D03*
X1427302D03*
X1432854Y933835D03*
Y940213D03*
X1431003Y937024D03*
X1427302D03*
X1436554Y927457D03*
Y933835D03*
X1431003Y943402D03*
Y949780D03*
X1427302D03*
X1432854Y946591D03*
Y952969D03*
X1431003Y956158D03*
X1436554Y946591D03*
X1432854Y959347D03*
X1427302Y962536D03*
X1431003D03*
X1432854Y965725D03*
X1431003Y968914D03*
X1436554Y959347D03*
X1432854Y978481D03*
X1431003Y981670D03*
X1432854Y972103D03*
X1431003Y975292D03*
X1427302D03*
X1429153Y984859D03*
X1438405Y981670D03*
X1436554Y972103D03*
Y984859D03*
X1431003Y988048D03*
X1429153Y991237D03*
X1436554D03*
X1438405Y988048D03*
X1447657Y876434D03*
X1445806Y879623D03*
X1443956Y882812D03*
X1447657D03*
X1440255Y889190D03*
X1447657D03*
X1442106Y892379D03*
X1443956Y895568D03*
X1451357Y882812D03*
X1451358Y889190D03*
X1453208Y892379D03*
X1442106Y898757D03*
X1440255Y901946D03*
X1447657D03*
X1443956D03*
X1442106Y905134D03*
X1443956Y908324D03*
X1442106Y911512D03*
X1451358Y901946D03*
X1453208Y898757D03*
Y905134D03*
Y911512D03*
X1440255Y914701D03*
X1443956D03*
X1447657D03*
X1442106Y917890D03*
X1443956Y921079D03*
X1442106Y924268D03*
X1451357Y914701D03*
X1453208Y917890D03*
Y924268D03*
X1440255Y927457D03*
X1443956D03*
X1447657D03*
X1440255Y933835D03*
X1443956D03*
X1442106Y937024D03*
X1443956Y940213D03*
X1453208Y930646D03*
X1451357Y927457D03*
X1447657Y946591D03*
X1442106Y943402D03*
X1440255Y946591D03*
X1442106Y949780D03*
X1443956Y946591D03*
Y952969D03*
X1442106Y956158D03*
X1451357Y946591D03*
X1453208Y943402D03*
Y949780D03*
Y956158D03*
X1440255Y959347D03*
X1443956D03*
X1447657D03*
X1443956Y965725D03*
X1442106Y962536D03*
Y968914D03*
X1451357Y959347D03*
X1453208Y962536D03*
Y968914D03*
X1445806Y981670D03*
X1443956Y978481D03*
Y972103D03*
X1447657D03*
X1442106Y975292D03*
X1440255Y972103D03*
X1443956Y984859D03*
X1453208Y981670D03*
X1451357Y972103D03*
X1453208Y975292D03*
X1451357Y984859D03*
X1445806Y988048D03*
X1443956Y991237D03*
X1453208Y988048D03*
Y994426D03*
X1451357Y991237D03*
X1453208Y1000804D03*
Y1007182D03*
X1456909Y873245D03*
Y879623D03*
X1458759Y876434D03*
X1468011Y879623D03*
X1455058Y882812D03*
X1462460D03*
X1466161D03*
X1458759D03*
Y889190D03*
X1455058Y895568D03*
X1464310Y892379D03*
X1466161Y895568D03*
X1462460Y889190D03*
X1464310Y898757D03*
X1455058Y901946D03*
X1458759D03*
X1466161D03*
X1462460D03*
X1464310Y905134D03*
X1455058Y908324D03*
X1464310Y911512D03*
X1466161Y908323D03*
X1458759Y914701D03*
X1464310Y917890D03*
Y924268D03*
X1455058Y921079D03*
X1466161D03*
X1455058Y914701D03*
X1462460D03*
X1466161D03*
X1455058Y927457D03*
X1458759D03*
X1466161D03*
X1462460D03*
X1455058Y933835D03*
X1464310Y930646D03*
X1462460Y933835D03*
X1466161D03*
X1458759D03*
X1455058Y940213D03*
X1466161D03*
X1462460Y946591D03*
X1466161D03*
X1458759D03*
X1466161Y952969D03*
X1464310Y956158D03*
X1455058Y952969D03*
X1464310Y943402D03*
X1455058Y946591D03*
X1464310Y949780D03*
X1455058Y965725D03*
X1466161D03*
X1455058Y959347D03*
X1462460D03*
X1466161D03*
X1458759D03*
X1464310Y962536D03*
Y968914D03*
X1460609Y981670D03*
X1455058Y978481D03*
X1466161D03*
X1455058Y972103D03*
X1462460D03*
X1466161D03*
X1458759D03*
X1464310Y975292D03*
X1458759Y984859D03*
X1466161D03*
X1468011Y981670D03*
X1458759Y997615D03*
X1466161D03*
X1460609Y988048D03*
Y994426D03*
X1458759Y991237D03*
X1466161D03*
X1460609Y1000804D03*
X1468011Y988048D03*
Y994426D03*
Y1000804D03*
X1458759Y1003993D03*
X1466161D03*
Y1010371D03*
X1458759D03*
X1460609Y1007182D03*
X1468011D03*
X1479113Y873245D03*
X1469861Y876434D03*
X1479113Y879623D03*
X1482814Y886001D03*
X1480964Y882812D03*
X1469861D03*
X1479113Y886001D03*
X1482814Y892379D03*
X1469861Y889190D03*
X1473562D03*
X1475413Y892379D03*
X1477263Y895568D03*
X1482814Y898757D03*
X1469861Y901946D03*
X1475413Y898757D03*
X1473562Y901946D03*
X1482814Y905134D03*
Y911512D03*
X1477263Y908324D03*
X1475413Y911512D03*
Y905134D03*
X1482814Y917890D03*
X1469861Y914701D03*
X1473562D03*
X1475413Y917890D03*
Y924268D03*
X1482814D03*
X1477263Y921079D03*
X1469861Y933835D03*
X1473562D03*
X1482814Y930646D03*
X1475413D03*
X1477263Y933835D03*
X1473562Y927457D03*
X1469861D03*
X1482814Y937024D03*
X1477263Y940213D03*
X1482814Y943402D03*
Y949780D03*
X1475413Y943402D03*
X1469861Y946591D03*
X1473562D03*
X1475413Y949780D03*
X1482814Y956158D03*
X1477263Y952969D03*
X1475413Y956158D03*
X1482814Y962536D03*
X1469861Y959347D03*
X1473562D03*
X1475413Y962536D03*
X1477263Y965725D03*
X1482814Y968914D03*
X1475413D03*
X1482814Y975292D03*
Y981670D03*
X1469861Y972103D03*
X1473562D03*
X1475413Y975292D03*
X1477263Y978481D03*
X1475413Y981670D03*
X1473562Y984859D03*
X1475413Y1000804D03*
X1482814Y988048D03*
Y994426D03*
X1473562Y991237D03*
Y997615D03*
X1475413Y988048D03*
Y994426D03*
X1482814Y1000804D03*
Y1007182D03*
X1473562Y1003993D03*
Y1010371D03*
X1475413Y1007182D03*
X1492066Y876434D03*
X1490216Y886001D03*
X1484665Y882812D03*
X1488365D03*
X1495767D03*
X1493917Y886001D03*
X1488365Y889190D03*
X1495767D03*
X1490216Y892379D03*
X1495767Y895568D03*
X1490216Y898757D03*
X1488365Y901946D03*
X1495767D03*
X1488365Y908324D03*
X1490216Y911512D03*
X1495767Y908324D03*
Y914701D03*
X1490216Y917890D03*
X1488365Y921079D03*
X1495767D03*
X1490216Y930646D03*
X1495767Y933835D03*
X1488365Y927457D03*
X1495767D03*
X1488365Y940213D03*
X1495767D03*
X1490216Y937024D03*
X1488365Y946591D03*
X1490216Y949780D03*
X1495767Y946591D03*
Y952969D03*
X1490216Y956158D03*
X1488365Y965725D03*
X1495767Y959347D03*
Y965725D03*
X1488365Y959347D03*
X1490216Y968914D03*
X1495767Y972103D03*
X1490216Y975292D03*
X1486515Y981670D03*
X1488365Y978481D03*
X1495767D03*
X1497617Y981670D03*
X1484665Y984859D03*
X1488365D03*
X1495767D03*
X1490216Y988048D03*
X1488365Y997615D03*
X1490216Y994426D03*
X1495767Y991237D03*
Y997615D03*
X1488365Y1003993D03*
X1490216Y1007182D03*
X1495767Y1003993D03*
Y1010371D03*
X1501318Y873245D03*
Y879623D03*
X1510570Y876434D03*
X1508720Y879623D03*
X1501318Y886001D03*
X1510570Y882812D03*
X1508720Y886001D03*
X1503169Y889190D03*
Y895568D03*
X1501318Y892379D03*
X1508720D03*
X1499468Y882812D03*
X1505019Y886001D03*
X1501318Y898757D03*
X1508720D03*
X1503169Y901946D03*
X1501318Y905134D03*
X1508720D03*
X1501318Y911512D03*
X1508720D03*
X1503169Y908323D03*
Y914701D03*
X1501318Y917890D03*
X1508720D03*
X1503169Y921079D03*
X1501318Y924268D03*
X1508720D03*
X1503169Y927457D03*
X1501318Y930646D03*
X1503169Y933835D03*
X1508720Y930646D03*
Y937024D03*
X1503169Y940213D03*
X1501318Y937024D03*
Y943402D03*
X1508720D03*
X1503169Y946591D03*
X1501318Y949780D03*
X1508720D03*
X1503169Y952969D03*
X1501318Y956158D03*
X1508720D03*
X1503169Y959347D03*
Y965725D03*
X1501318Y962536D03*
X1508720D03*
X1501318Y968914D03*
X1508720D03*
X1510570Y984859D03*
X1512421Y981670D03*
X1503169Y972103D03*
X1501318Y975292D03*
X1503169Y978481D03*
X1501318Y981670D03*
X1508720Y975292D03*
Y981670D03*
X1499468Y984859D03*
X1503169D03*
Y991237D03*
X1501318Y988048D03*
X1503169Y997615D03*
X1501318Y994426D03*
X1508720Y988048D03*
Y994426D03*
X1501318Y1000804D03*
X1508720D03*
X1501318Y1007182D03*
X1503169Y1010371D03*
X1508720Y1007182D03*
X1503169Y1003993D03*
X1521673Y876434D03*
X1517972D03*
X1519822Y879623D03*
X1527224D03*
X1516121D03*
X1523523Y873245D03*
X1514271Y882812D03*
Y889190D03*
X1521673Y882812D03*
X1519822Y886001D03*
X1525373Y882812D03*
X1527224Y886001D03*
X1521673Y889190D03*
Y895568D03*
X1527224Y892379D03*
X1516121D03*
X1514271Y901946D03*
Y908324D03*
X1521673Y901946D03*
X1527224Y898757D03*
X1516121D03*
X1527224Y911512D03*
Y905134D03*
X1516121Y911512D03*
X1521673Y908323D03*
X1514271Y921079D03*
X1521673Y914701D03*
X1527224Y917890D03*
X1516121D03*
X1521673Y921079D03*
X1527224Y924268D03*
X1514271Y927457D03*
Y940213D03*
X1516121Y930646D03*
X1521673Y927457D03*
Y933835D03*
X1527224Y930646D03*
X1516121Y937024D03*
X1527224D03*
X1521673Y940213D03*
X1514271Y946591D03*
X1516121Y949780D03*
X1521673Y946591D03*
X1527224Y943402D03*
Y949780D03*
X1521673Y952969D03*
X1527224Y956158D03*
X1516121D03*
X1514271Y959347D03*
Y965725D03*
X1521673Y959347D03*
Y965725D03*
X1527224Y962536D03*
Y968914D03*
X1516121D03*
X1514271Y978481D03*
Y984859D03*
X1521673Y972103D03*
X1523523Y981670D03*
X1521673Y978481D03*
X1527224Y975292D03*
Y981670D03*
X1516121Y975292D03*
X1521673Y984859D03*
X1525373D03*
X1514271Y997615D03*
X1521673Y991237D03*
Y997615D03*
X1527224Y988048D03*
Y994426D03*
X1516121Y988048D03*
Y994426D03*
X1527224Y1000804D03*
X1514271Y1003993D03*
X1516121Y1007182D03*
X1521673Y1003993D03*
Y1010371D03*
X1527224Y1007182D03*
X1529074Y876434D03*
X1538326Y879623D03*
X1530925Y886001D03*
X1529074Y889190D03*
Y895568D03*
X1540176Y882812D03*
X1536476D03*
X1534625Y886001D03*
X1540176Y889190D03*
X1542027Y892379D03*
X1534625D03*
X1529074Y901946D03*
Y908324D03*
X1542027Y898757D03*
X1540176Y901946D03*
X1534625Y898757D03*
X1540176Y908324D03*
X1542027Y911512D03*
X1534625Y905134D03*
Y911512D03*
X1529074Y914701D03*
Y921079D03*
X1542027Y917890D03*
X1534625D03*
X1540176Y921079D03*
X1534625Y924268D03*
X1529074Y927457D03*
Y933835D03*
Y940213D03*
X1540176Y927457D03*
X1542027Y930646D03*
X1534625D03*
X1542027Y937024D03*
X1540176Y940213D03*
X1534625Y937024D03*
X1529074Y946591D03*
Y952969D03*
X1540176Y946591D03*
X1542027Y949780D03*
X1534625Y943402D03*
Y949780D03*
Y956158D03*
X1542027D03*
X1529074Y959347D03*
Y965725D03*
X1540176Y959347D03*
Y965725D03*
X1534625Y962536D03*
X1542027Y968914D03*
X1534625D03*
X1538326Y981670D03*
X1542027Y975292D03*
X1540176Y978481D03*
X1534625Y975292D03*
Y981670D03*
X1536476Y984859D03*
X1540176D03*
X1529074Y972103D03*
Y978481D03*
Y984859D03*
Y991237D03*
Y997615D03*
X1542027Y988048D03*
X1540176Y997615D03*
X1542027Y994426D03*
X1534625Y988048D03*
Y994426D03*
Y1000804D03*
X1542027Y1007182D03*
X1534625D03*
X1529074Y1003993D03*
Y1010371D03*
X1540176Y1003993D03*
X1545728Y873245D03*
X1553129Y879623D03*
X1545728Y886001D03*
X1547578Y882812D03*
X1553129Y886001D03*
X1551279Y882812D03*
X1547578Y889190D03*
Y895568D03*
X1553129Y892379D03*
X1547578Y901946D03*
X1553129Y898757D03*
X1547578Y908324D03*
Y914701D03*
Y921079D03*
Y927457D03*
Y933835D03*
Y940213D03*
Y946591D03*
Y952969D03*
Y959347D03*
Y965725D03*
X1543877Y984859D03*
X1547578Y972103D03*
Y978481D03*
Y984859D03*
X1545728Y988048D03*
X1547578Y991237D03*
Y997615D03*
Y1003993D03*
Y1010371D03*
G54D60*
X928740Y321654D03*
G54D36*
X250326Y185236D03*
X368437D03*
G54D61*
X916546Y309460D03*
X911495Y321654D03*
X916546Y333848D03*
X928740Y304409D03*
Y338899D03*
X940934Y309460D03*
X945985Y321654D03*
X940934Y333848D03*
G54D72*
X1766929Y1714960D03*
G54D11*
X19685Y-29134D03*
Y1803261D03*
X2081889Y-29134D03*
Y1803261D03*
G54D27*
X117933Y605376D03*
X763602Y605413D03*
X1094076Y605378D03*
X1739745Y605411D03*
G54D18*
X44000Y154200D03*
X31818Y1424257D03*
X441043Y1672205D03*
Y1718465D03*
X1416437Y1672205D03*
Y1718465D03*
X1800449Y126194D03*
X1804650Y1667292D03*
G54D53*
X791280Y1704890D03*
X1066280D03*
G54D33*
X230905Y1644448D03*
Y1658621D03*
Y1672795D03*
Y1686968D03*
Y1701141D03*
Y1715314D03*
Y1729488D03*
X246653Y1644448D03*
X238779Y1648385D03*
X246653Y1658621D03*
X238779Y1662558D03*
X246653Y1672795D03*
X238779Y1676732D03*
X246653Y1686968D03*
X238779Y1690905D03*
X246653Y1701141D03*
X238779Y1705078D03*
X246653Y1715314D03*
X238779Y1719251D03*
X246653Y1729488D03*
X238779Y1733425D03*
X254527Y1648385D03*
Y1662558D03*
Y1676732D03*
Y1690905D03*
Y1705078D03*
Y1719251D03*
Y1733425D03*
X262401Y1644448D03*
X270275Y1648385D03*
X262401Y1658621D03*
X270275Y1662558D03*
X262401Y1672795D03*
X270275Y1676732D03*
X262401Y1686968D03*
X270275Y1690905D03*
X262401Y1701141D03*
X270275Y1705078D03*
X262401Y1715314D03*
X270275Y1719251D03*
X262401Y1729488D03*
X270275Y1733425D03*
X278149Y1644448D03*
X286023Y1648385D03*
X278149Y1658621D03*
X286023Y1662558D03*
X278149Y1672795D03*
X286023Y1676732D03*
X278149Y1686968D03*
X286023Y1690905D03*
X278149Y1701141D03*
X286023Y1705078D03*
X278149Y1715314D03*
X286023Y1719251D03*
X278149Y1729488D03*
X286023Y1733425D03*
X297835Y1672795D03*
X305709Y1676732D03*
X297835Y1686968D03*
X305709Y1690905D03*
X297835Y1701141D03*
X305709Y1705078D03*
X297835Y1715314D03*
X305709Y1719251D03*
X297835Y1729488D03*
X305709Y1733425D03*
X313583Y1672795D03*
X321457Y1676732D03*
X313583Y1686968D03*
X321457Y1690905D03*
X313583Y1701141D03*
X321457Y1705078D03*
X313583Y1715314D03*
X321457Y1719251D03*
X313583Y1729488D03*
X321457Y1733425D03*
X329331Y1672795D03*
Y1686968D03*
Y1701141D03*
Y1715314D03*
Y1729488D03*
X345079Y1672795D03*
X337205Y1676732D03*
X345079Y1686968D03*
X337205Y1690905D03*
X345079Y1701141D03*
X337205Y1705078D03*
X345079Y1715314D03*
X337205Y1719251D03*
X345079Y1729488D03*
X337205Y1733425D03*
X352953Y1676732D03*
Y1690905D03*
Y1705078D03*
Y1719251D03*
Y1733425D03*
X495078Y1672795D03*
Y1686968D03*
Y1701141D03*
Y1715314D03*
Y1729488D03*
X510826Y1672795D03*
X502952Y1676732D03*
X510826Y1686968D03*
X502952Y1690905D03*
X510826Y1701141D03*
X502952Y1705078D03*
X510826Y1715314D03*
X502952Y1719251D03*
X510826Y1729488D03*
X502952Y1733425D03*
X526574Y1672795D03*
X518700Y1676732D03*
X526574Y1686968D03*
X518700Y1690905D03*
X526574Y1701141D03*
X518700Y1705078D03*
X526574Y1715314D03*
X518700Y1719251D03*
X526574Y1729488D03*
X518700Y1733425D03*
X542322Y1672795D03*
X534448Y1676732D03*
X542322Y1686968D03*
X534448Y1690905D03*
X542322Y1701141D03*
X534448Y1705078D03*
X542322Y1715314D03*
X534448Y1719251D03*
X542322Y1729488D03*
X534448Y1733425D03*
X550196Y1676732D03*
Y1690905D03*
Y1705078D03*
Y1719251D03*
Y1733425D03*
X562008Y1672795D03*
X569882Y1676732D03*
X562008Y1686968D03*
X569882Y1690905D03*
X562008Y1701141D03*
X569882Y1705078D03*
X562008Y1715314D03*
X569882Y1719251D03*
X562008Y1729488D03*
X569882Y1733425D03*
X577756Y1672795D03*
X585630Y1676732D03*
X577756Y1686968D03*
X585630Y1690905D03*
X577756Y1701141D03*
X585630Y1705078D03*
X577756Y1715314D03*
X585630Y1719251D03*
X577756Y1729488D03*
X585630Y1733425D03*
X593504Y1672795D03*
X601378Y1676732D03*
X593504Y1686968D03*
X601378Y1690905D03*
X593504Y1701141D03*
X601378Y1705078D03*
X593504Y1715314D03*
X601378Y1719251D03*
X593504Y1729488D03*
X601378Y1733425D03*
X609252Y1672795D03*
X617126Y1676732D03*
X609252Y1686968D03*
X617126Y1690905D03*
X609252Y1701141D03*
X617126Y1705078D03*
X609252Y1715314D03*
X617126Y1719251D03*
X609252Y1729488D03*
X617126Y1733425D03*
X1238778Y1672795D03*
Y1686968D03*
Y1701141D03*
Y1715314D03*
Y1729488D03*
X1254526Y1672795D03*
X1246652Y1676732D03*
X1254526Y1686968D03*
X1246652Y1690905D03*
X1254526Y1701141D03*
X1246652Y1705078D03*
X1254526Y1715314D03*
X1246652Y1719251D03*
X1254526Y1729488D03*
X1246652Y1733425D03*
X1270274Y1672795D03*
X1262400Y1676732D03*
X1270274Y1686968D03*
X1262400Y1690905D03*
X1270274Y1701141D03*
X1262400Y1705078D03*
X1270274Y1715314D03*
X1262400Y1719251D03*
X1270274Y1729488D03*
X1262400Y1733425D03*
X1286022Y1672795D03*
X1278148Y1676732D03*
X1286022Y1686968D03*
X1278148Y1690905D03*
X1286022Y1701141D03*
X1278148Y1705078D03*
X1286022Y1715314D03*
X1278148Y1719251D03*
X1286022Y1729488D03*
X1278148Y1733425D03*
X1305708Y1672795D03*
Y1686968D03*
X1293896Y1676732D03*
X1305708Y1701141D03*
X1293896Y1690905D03*
X1305708Y1715314D03*
X1293896Y1705078D03*
X1305708Y1729488D03*
X1293896Y1719251D03*
Y1733425D03*
X1313582Y1676732D03*
Y1690905D03*
Y1705078D03*
Y1719251D03*
Y1733425D03*
X1321456Y1672795D03*
X1329330Y1676732D03*
X1321456Y1686968D03*
X1329330Y1690905D03*
X1321456Y1701141D03*
X1329330Y1705078D03*
X1321456Y1715314D03*
X1329330Y1719251D03*
X1321456Y1729488D03*
X1329330Y1733425D03*
X1337204Y1672795D03*
X1345078Y1676732D03*
X1337204Y1686968D03*
X1345078Y1690905D03*
X1337204Y1701141D03*
X1345078Y1705078D03*
X1337204Y1715314D03*
X1345078Y1719251D03*
X1337204Y1729488D03*
X1345078Y1733425D03*
X1352952Y1672795D03*
X1360826Y1676732D03*
X1352952Y1686968D03*
X1360826Y1690905D03*
X1352952Y1701141D03*
X1360826Y1705078D03*
X1352952Y1715314D03*
X1360826Y1719251D03*
X1352952Y1729488D03*
X1360826Y1733425D03*
X1502952Y1672795D03*
X1510826Y1676732D03*
X1502952Y1686968D03*
X1510826Y1690905D03*
X1502952Y1701141D03*
X1510826Y1705078D03*
X1502952Y1715314D03*
X1510826Y1719251D03*
X1502952Y1729488D03*
X1510826Y1733425D03*
X1518700Y1672795D03*
X1526574Y1676732D03*
X1518700Y1686968D03*
X1526574Y1690905D03*
X1518700Y1701141D03*
X1526574Y1705078D03*
X1518700Y1715314D03*
X1526574Y1719251D03*
X1518700Y1729488D03*
X1526574Y1733425D03*
X1534448Y1672795D03*
X1542322Y1676732D03*
X1534448Y1686968D03*
X1542322Y1690905D03*
X1534448Y1701141D03*
X1542322Y1705078D03*
X1534448Y1715314D03*
X1542322Y1719251D03*
X1534448Y1729488D03*
X1542322Y1733425D03*
X1550196Y1672795D03*
X1558070Y1676732D03*
X1550196Y1686968D03*
X1558070Y1690905D03*
X1550196Y1701141D03*
X1558070Y1705078D03*
X1550196Y1715314D03*
X1558070Y1719251D03*
X1550196Y1729488D03*
X1558070Y1733425D03*
X1569882Y1672795D03*
Y1686968D03*
Y1701141D03*
Y1715314D03*
Y1729488D03*
X1585630Y1672795D03*
X1577756Y1676732D03*
X1585630Y1686968D03*
X1577756Y1690905D03*
X1585630Y1701141D03*
X1577756Y1705078D03*
X1585630Y1715314D03*
X1577756Y1719251D03*
X1585630Y1729488D03*
X1577756Y1733425D03*
X1601378Y1672795D03*
X1593504Y1676732D03*
X1601378Y1686968D03*
X1593504Y1690905D03*
X1601378Y1701141D03*
X1593504Y1705078D03*
X1601378Y1715314D03*
X1593504Y1719251D03*
X1601378Y1729488D03*
X1593504Y1733425D03*
X1617126Y1672795D03*
X1609252Y1676732D03*
X1617126Y1686968D03*
X1609252Y1690905D03*
X1617126Y1701141D03*
X1609252Y1705078D03*
X1617126Y1715314D03*
X1609252Y1719251D03*
X1617126Y1729488D03*
X1609252Y1733425D03*
X1625000Y1676732D03*
Y1690905D03*
Y1705078D03*
Y1719251D03*
Y1733425D03*
G54D46*
X441043Y1698268D03*
X1416437D03*
G54D55*
X805690Y204724D03*
X1057659D03*
G54D15*
X17292Y290137D03*
X35689Y301357D03*
X33822Y1462075D03*
Y1459075D03*
Y1456075D03*
X36822D03*
Y1459075D03*
Y1462075D03*
X33822Y1465075D03*
X36822D03*
X37671Y1515214D03*
X34704Y1515235D03*
X47892Y290137D03*
X49400Y384392D03*
X49250Y396332D03*
X47618Y412613D03*
X47619Y421655D03*
X42822Y1462075D03*
Y1459075D03*
Y1456075D03*
Y1465075D03*
X47138Y1513072D03*
X47089Y1510268D03*
X50642Y1557451D03*
X45633Y1592481D03*
X50133D03*
X38426Y1654079D03*
X41427Y1668587D03*
X38426Y1659059D03*
X44583Y1672433D03*
Y1677613D03*
X66289Y301357D03*
X61340Y384362D03*
X61250Y396142D03*
X56542Y589521D03*
X66822Y1462075D03*
Y1459075D03*
Y1456075D03*
X57822Y1462075D03*
Y1459075D03*
Y1456075D03*
X66822Y1465075D03*
X57822D03*
X63990Y1562177D03*
Y1567627D03*
Y1564727D03*
X63915Y1558805D03*
Y1556254D03*
X63990Y1570427D03*
X61225Y1570283D03*
X58564Y1570209D03*
X65767Y1609405D03*
X59767D03*
X53767D03*
X65767Y1615405D03*
X65943Y1621405D03*
X59767D03*
X53767Y1615405D03*
Y1621405D03*
X59427Y1644410D03*
X53648Y1653088D03*
X77790Y520108D03*
X77733Y526764D03*
X77790Y537808D03*
X77733Y544464D03*
X81822Y1462075D03*
Y1456075D03*
Y1465075D03*
X68427Y1644410D03*
X73427D03*
X80000Y1702450D03*
X79500Y1720450D03*
X88722Y1462075D03*
X85722D03*
X88722Y1456075D03*
X85722D03*
X88722Y1465075D03*
X85722D03*
X85621Y1551969D03*
X82974Y1552051D03*
X83340Y1654353D03*
X89466Y1663138D03*
Y1667127D03*
X83340Y1659333D03*
X85395Y1670331D03*
Y1675311D03*
X102096Y1555442D03*
X100439Y1667361D03*
X106573Y1660235D03*
X100915Y1679564D03*
X105069Y1685763D03*
X102243Y1682263D03*
Y1689263D03*
X120016Y300654D03*
Y320631D03*
X114973Y1660235D03*
X113469Y1685763D03*
X133120Y1454751D03*
X137120D03*
X141028Y1454705D03*
X140775Y1638035D03*
X146982Y526997D03*
X145028Y1454705D03*
X152449Y1623572D03*
Y1628528D03*
X151611Y1663933D03*
X159427Y1687843D03*
X151510Y1676811D03*
X163113Y1477590D03*
Y1499490D03*
X164730Y1521561D03*
X161239Y1636147D03*
Y1631191D03*
X162995Y1661377D03*
X160011Y1663933D03*
X163003Y1666462D03*
X159910Y1676811D03*
X162848Y1679357D03*
X162840Y1674272D03*
X187250Y129674D03*
X189410Y388180D03*
X200754Y595174D03*
Y603274D03*
X192951Y1560498D03*
X196081Y1639349D03*
X195504Y1645359D03*
X203754Y595174D03*
Y603274D03*
X207968Y1653130D03*
X203800Y1646832D03*
X272242Y523076D03*
X276085Y1509654D03*
X270720Y1531073D03*
X273220D03*
X275720D03*
X281147Y521803D03*
X280621Y1478082D03*
X291175Y1477590D03*
X283221Y1484772D03*
Y1479992D03*
X278021Y1484772D03*
Y1479992D03*
X283221Y1493392D03*
X280621Y1491482D03*
X278021Y1493392D03*
X291175Y1499490D03*
X283221Y1498172D03*
X278021D03*
X291619Y1536606D03*
X291593Y1529402D03*
Y1531902D03*
X284800Y1526750D03*
X277572Y1536763D03*
X280072D03*
X291619Y1539106D03*
X292792Y1521561D03*
X297323Y1651172D03*
X318660Y24989D03*
X307255Y1641150D03*
X339914Y165170D03*
X384668Y471926D03*
X410701Y99148D03*
X396977Y216685D03*
X399625Y479119D03*
X408683Y1478082D03*
Y1491482D03*
X406083Y1479992D03*
Y1484772D03*
Y1493392D03*
Y1498172D03*
X404147Y1509654D03*
X398782Y1531073D03*
X401282D03*
X403782D03*
X411800Y220200D03*
X413425Y479042D03*
X411283Y1479992D03*
Y1484772D03*
Y1493392D03*
Y1498172D03*
X412862Y1526750D03*
X436090Y120007D03*
X429997Y166400D03*
X441997D03*
X439299Y220046D03*
X427225Y478965D03*
X440159Y966741D03*
Y981741D03*
Y974241D03*
X427286Y1477590D03*
Y1499490D03*
X428746Y1521727D03*
X427730Y1536606D03*
X427704Y1531902D03*
Y1529402D03*
X427730Y1539106D03*
X428500Y1650000D03*
X465997Y166400D03*
X457997D03*
X466041Y1664913D03*
X483467Y209755D03*
X514418Y145171D03*
Y149171D03*
Y153171D03*
X513360Y169190D03*
X511771Y199576D03*
X506261Y865338D03*
X522418Y153171D03*
X516572Y865327D03*
X530418Y145171D03*
Y149171D03*
Y153171D03*
X531280Y210922D03*
X544794Y1478082D03*
Y1491482D03*
X542194Y1479992D03*
Y1484772D03*
Y1493392D03*
X537694Y1504872D03*
X542194Y1498172D03*
X543759Y1536882D03*
X540193Y1531073D03*
X537693D03*
X535193D03*
X541259Y1536882D03*
X555348Y1477590D03*
X547394Y1479992D03*
Y1484772D03*
Y1493392D03*
X555348Y1499490D03*
X547394Y1498172D03*
X556965Y1521561D03*
X556642Y1529389D03*
X554715Y1531564D03*
X550540Y1526910D03*
X556197Y1536687D03*
Y1539187D03*
X561248Y106985D03*
Y100399D03*
X562208Y387227D03*
Y376427D03*
Y401158D03*
X568433Y415846D03*
X581985Y379577D03*
Y390377D03*
Y404308D03*
X588723Y423949D03*
X593975Y164440D03*
X598208Y387227D03*
Y376427D03*
X599164Y432209D03*
X604718Y257562D03*
X617985Y379577D03*
Y398578D03*
Y390377D03*
X610935Y409996D03*
X615075Y443000D03*
X633882Y587488D03*
X646285Y297171D03*
X640317Y391085D03*
X634566Y407848D03*
X639482Y587488D03*
X645446Y587300D03*
X653821Y90326D03*
X653013Y443200D03*
X664170Y445711D03*
X651046Y587300D03*
X672856Y1478082D03*
Y1491482D03*
X675112Y1479602D03*
X675456Y1484772D03*
Y1493392D03*
X670256Y1479992D03*
Y1484772D03*
Y1493392D03*
X665756Y1504872D03*
X675456Y1498172D03*
X670256D03*
X680710Y1520284D03*
X683674Y1522287D03*
X695796Y418358D03*
X708395Y430957D03*
X702095Y421508D03*
X698946Y437256D03*
X702095Y449854D03*
X708395Y474971D03*
X698946Y468672D03*
X695796Y487570D03*
X706172Y1552082D03*
X698003Y1684692D03*
X711544Y421508D03*
X720993Y443555D03*
Y446705D03*
X717843D03*
Y440405D03*
X720993Y449854D03*
Y462373D03*
Y459223D03*
Y456074D03*
X717843Y459223D03*
Y465523D03*
X711544Y484420D03*
X722141Y1405912D03*
X721916Y1414339D03*
Y1416939D03*
X722141Y1408412D03*
X721916Y1428989D03*
Y1431589D03*
X733512Y427807D03*
X727292Y421508D03*
X736661Y443555D03*
X733512Y446705D03*
Y443555D03*
X727292Y446705D03*
Y443555D03*
X724143D03*
Y462373D03*
X727292D03*
X733512Y459223D03*
X727292D03*
X733512Y462373D03*
X736661D03*
X727292Y474971D03*
X736661Y484420D03*
X724143D03*
X752409Y421508D03*
X739811Y443555D03*
Y446705D03*
X742961Y440405D03*
X739811Y449854D03*
Y456074D03*
Y459223D03*
Y462373D03*
X742961Y465523D03*
X752409Y484420D03*
X746082Y1506931D03*
X751030Y1668583D03*
X765008Y418358D03*
X758709Y437256D03*
X755559Y456074D03*
X758709Y468672D03*
X765008Y487570D03*
X758179Y1482049D03*
X758163Y1526223D03*
X758179Y1534963D03*
X779014Y1343262D03*
Y1340062D03*
X782014D03*
Y1337062D03*
Y1343262D03*
X780000Y1353500D03*
X779014Y1346462D03*
Y1349862D03*
X782014Y1346462D03*
Y1349862D03*
X780000Y1357500D03*
Y1363500D03*
Y1360500D03*
X780111Y1405366D03*
X782758Y1405249D03*
X795421Y1331257D03*
X785014Y1350862D03*
X804099Y1333835D03*
X801171Y1343278D03*
X810986Y1361684D03*
X819115Y115223D03*
X824499Y145198D03*
X820405Y311830D03*
X831115Y115223D03*
X829115Y150273D03*
X838670Y1518558D03*
X841310Y1518608D03*
X838630Y1521538D03*
X841270Y1521588D03*
X854578Y99651D03*
X856397Y339751D03*
X847007Y1521458D03*
X844367Y1521408D03*
Y1518784D03*
X847007Y1518834D03*
X855853Y1521308D03*
X853213Y1521258D03*
X850146Y1521261D03*
Y1518637D03*
X853213Y1518634D03*
X855853Y1518684D03*
X860152Y328399D03*
X865132D03*
X861377Y339751D03*
X872986Y753451D03*
X858581Y1518568D03*
X858567Y1521416D03*
X876133Y73580D03*
Y95580D03*
Y117580D03*
X919272Y989932D03*
X921289Y1663187D03*
X942779Y277731D03*
X936693Y1462328D03*
X939507Y1462497D03*
X945195Y1459453D03*
X942056Y1459650D03*
X939416Y1459600D03*
Y1456976D03*
X942056Y1457026D03*
X945195Y1456829D03*
X951099Y632206D03*
X956693Y1459805D03*
X953630Y1456760D03*
X958383Y1462447D03*
X950902Y1459500D03*
X948262Y1459450D03*
X953616Y1459608D03*
X948262Y1456826D03*
X950902Y1456876D03*
X955350Y1532760D03*
X961350D03*
X958350D03*
X953520Y1567570D03*
X950520D03*
X959520D03*
X956520D03*
X953520Y1582570D03*
X950520D03*
Y1579570D03*
X953520D03*
Y1576570D03*
X950520D03*
X953520Y1573570D03*
X950520D03*
Y1570570D03*
X953520D03*
X959520Y1582570D03*
X956520D03*
Y1579570D03*
X959520D03*
Y1576570D03*
X956520D03*
X959520Y1573570D03*
X956520D03*
Y1570570D03*
X959520D03*
X953520Y1588570D03*
X950520D03*
Y1585570D03*
X953520D03*
X959520Y1588570D03*
X956520D03*
Y1585570D03*
X959520D03*
X977150Y1052684D03*
X966000Y1300000D03*
X968500D03*
X971000D03*
X967350Y1532760D03*
X964350D03*
X991280D03*
X988280D03*
X988160Y1567710D03*
X991160D03*
X985160D03*
X988160Y1582710D03*
X991160D03*
X985160D03*
Y1579710D03*
X991160D03*
X988160D03*
X991160Y1570710D03*
X988160D03*
Y1573710D03*
X991160D03*
X988160Y1576710D03*
X991160D03*
X985160Y1570710D03*
Y1573710D03*
Y1576710D03*
X988160Y1588710D03*
X991160D03*
X985160D03*
Y1585710D03*
X991160D03*
X988160D03*
X994280Y1532760D03*
X997280D03*
X1000280D03*
X1014206Y510304D03*
X1013306Y526146D03*
X1019440Y1532930D03*
X1016750Y1567710D03*
X1019750D03*
X1016750Y1576710D03*
Y1573710D03*
Y1570710D03*
X1019750Y1576710D03*
Y1573710D03*
Y1570710D03*
Y1579710D03*
X1016750D03*
Y1582710D03*
X1019750D03*
Y1585710D03*
X1016750D03*
Y1588710D03*
X1019750D03*
X1025440Y1532930D03*
X1022440D03*
X1031440D03*
X1028440D03*
X1022750Y1567710D03*
Y1576710D03*
Y1573710D03*
Y1570710D03*
Y1579710D03*
Y1582710D03*
Y1585710D03*
Y1588710D03*
X1045254Y521074D03*
X1037212Y510940D03*
X1051110Y1532850D03*
X1048219Y1567883D03*
X1051219D03*
X1048219Y1576883D03*
Y1573883D03*
Y1570883D03*
X1051219Y1576883D03*
Y1573883D03*
Y1570883D03*
Y1579883D03*
X1048219D03*
Y1582883D03*
X1051219D03*
Y1585883D03*
X1048219D03*
Y1588883D03*
X1051219D03*
X1055934Y385488D03*
X1057110Y1532850D03*
X1054110D03*
X1063110D03*
X1060110D03*
X1054219Y1567883D03*
Y1576883D03*
Y1573883D03*
Y1570883D03*
Y1579883D03*
Y1582883D03*
Y1585883D03*
Y1588883D03*
X1068143Y383688D03*
X1073204Y383417D03*
X1083819Y353094D03*
X1090300Y1532660D03*
X1087300D03*
X1096300D03*
X1093300D03*
X1119067Y1551457D03*
X1133765Y1572102D03*
X1170986Y1510590D03*
Y1532490D03*
X1183354Y77685D03*
X1176972Y86788D03*
X1200824Y1593498D03*
X1192612Y1680410D03*
X1207954Y1680419D03*
X1209879Y1700359D03*
X1230094Y314216D03*
X1226094Y305216D03*
X1216875Y1705826D03*
X1216738Y1720861D03*
X1277732Y236594D03*
Y246594D03*
Y241594D03*
Y251594D03*
X1288494Y1511082D03*
X1285894Y1512992D03*
Y1517772D03*
X1288494Y1524482D03*
X1285894Y1531172D03*
Y1526392D03*
X1283958Y1542654D03*
X1278593Y1564073D03*
X1281093D03*
X1283593D03*
X1287945Y1569763D03*
X1285445D03*
X1302365Y1418702D03*
X1292522Y1421596D03*
X1303943Y1430729D03*
X1299048Y1510590D03*
X1291094Y1512992D03*
Y1517772D03*
X1299048Y1532490D03*
X1291094Y1531172D03*
Y1526392D03*
X1299466Y1562402D03*
Y1564902D03*
X1292673Y1559750D03*
X1299492Y1572106D03*
Y1569606D03*
X1307766Y563013D03*
X1308700Y590300D03*
X1317266Y592522D03*
X1308700Y587800D03*
X1313109Y1195398D03*
Y1200898D03*
X1325366Y592522D03*
X1339488Y1202295D03*
X1340483Y1209006D03*
X1336861Y1222119D03*
X1350809Y1202323D03*
X1368137Y1222298D03*
Y1227798D03*
X1383800Y1685398D03*
X1406655Y1564073D03*
X1409155D03*
X1399940Y1637127D03*
X1414619Y244450D03*
X1416301Y966740D03*
Y981740D03*
Y974240D03*
X1416556Y1511082D03*
X1419156Y1512992D03*
Y1517772D03*
X1413956Y1512992D03*
Y1517772D03*
X1416556Y1524482D03*
X1419156Y1531172D03*
Y1526392D03*
X1413956Y1531172D03*
Y1526392D03*
X1412020Y1542654D03*
X1420735Y1559750D03*
X1411655Y1564073D03*
X1435160Y1510590D03*
Y1532490D03*
X1435578Y1564902D03*
Y1562402D03*
X1436940Y1554277D03*
X1435604Y1572106D03*
Y1569606D03*
X1445985Y116953D03*
X1441390Y163944D03*
X1442993Y176204D03*
X1462405Y61563D03*
X1461242Y128242D03*
X1463017Y136368D03*
X1465832Y535330D03*
X1542767Y1564073D03*
X1552668Y1511082D03*
X1555268Y1512992D03*
Y1517772D03*
X1550068Y1512992D03*
Y1517772D03*
X1552668Y1524482D03*
X1555268Y1531172D03*
Y1526392D03*
X1550068Y1531172D03*
Y1526392D03*
X1548132Y1542654D03*
X1556847Y1559750D03*
X1545267Y1564073D03*
X1547767D03*
X1552118Y1569763D03*
X1549618D03*
X1563222Y1510590D03*
Y1532490D03*
X1564581Y1562316D03*
X1562613Y1564816D03*
X1564128Y1572225D03*
X1562621Y1569761D03*
X1602270Y229530D03*
X1629597Y221842D03*
X1619909Y306746D03*
X1643283Y1425541D03*
X1648337Y1451313D03*
X1654419Y233062D03*
X1655383Y1425541D03*
X1656997Y1708609D03*
Y1723759D03*
X1665100Y156762D03*
Y166762D03*
X1673223Y220857D03*
X1673630Y1533092D03*
Y1537872D03*
X1684925Y118762D03*
Y149762D03*
Y161762D03*
Y153762D03*
X1684942Y234000D03*
X1683587Y1433425D03*
X1680430Y1511198D03*
X1682760Y1512169D03*
X1683330Y1517772D03*
X1678130Y1512992D03*
Y1517772D03*
X1680730Y1524482D03*
X1683330Y1531172D03*
Y1526392D03*
X1678130Y1531172D03*
Y1526392D03*
X1688584Y1553284D03*
X1691548Y1555287D03*
X1686857Y1683918D03*
X1684733Y1698952D03*
X1695102Y1698947D03*
X1691357Y1688418D03*
X1691997Y1708609D03*
X1733083Y654034D03*
X1737606Y1539807D03*
X1736579Y1587480D03*
X1723929Y1654456D03*
X1723963Y1658965D03*
Y1663465D03*
Y1667965D03*
X1731117Y1705115D03*
Y1720265D03*
X1741329Y1482405D03*
Y1485405D03*
Y1491405D03*
Y1488405D03*
X1740058Y1537419D03*
X1744866Y1539589D03*
X1742165Y1539620D03*
X1740979Y1577905D03*
X1743681Y1626750D03*
X1750681D03*
X1747181D03*
X1743481Y1616550D03*
X1750481D03*
X1746981D03*
X1747963Y1641965D03*
X1764029Y1485405D03*
Y1482405D03*
Y1491405D03*
Y1488405D03*
X1756329Y1485405D03*
Y1482405D03*
Y1491405D03*
Y1488405D03*
X1769054Y1585705D03*
X1753079Y1596650D03*
Y1606550D03*
Y1603050D03*
Y1600150D03*
X1761839Y1634223D03*
X1757763Y1643365D03*
X1761494Y1661947D03*
X1779029Y1482405D03*
Y1485405D03*
Y1491405D03*
Y1488405D03*
X1772904Y1585005D03*
X1773863Y1661465D03*
X1774940Y1669037D03*
X1773738Y1672965D03*
X1773963Y1680965D03*
X1793070Y25001D03*
X1788029Y1485405D03*
Y1482405D03*
Y1491405D03*
Y1488405D03*
X1789379Y1588478D03*
X1805525Y146716D03*
X1812029Y1485405D03*
Y1482405D03*
X1803029D03*
Y1485405D03*
X1812029Y1491405D03*
Y1488405D03*
X1803029Y1491405D03*
Y1488405D03*
X1801789Y1536742D03*
X1807408Y1539223D03*
X1810408D03*
X1812078Y1596725D03*
X1812003Y1607375D03*
Y1603875D03*
X1812078Y1600225D03*
X1809179Y1616550D03*
X1809254Y1613775D03*
X1812570Y159275D03*
X1827029Y1488405D03*
Y1491405D03*
Y1485405D03*
Y1482405D03*
X1815344Y1539373D03*
X1818344D03*
X1823112Y1538659D03*
X1812679Y1616550D03*
X1816179D03*
X1812754Y1613775D03*
X1816254D03*
X1837641Y159275D03*
X1840700Y326201D03*
Y348201D03*
Y370201D03*
Y392201D03*
Y414201D03*
Y436201D03*
Y458201D03*
Y480201D03*
Y502201D03*
Y524201D03*
Y546201D03*
Y568201D03*
Y590201D03*
Y656201D03*
Y678201D03*
Y700201D03*
Y722201D03*
Y744201D03*
Y766201D03*
Y788201D03*
Y810201D03*
Y832201D03*
Y854201D03*
Y876201D03*
Y898201D03*
Y920201D03*
Y942201D03*
Y964201D03*
Y986201D03*
Y1008201D03*
Y1030201D03*
Y1052201D03*
Y1074201D03*
Y1096201D03*
Y1118201D03*
Y1140201D03*
Y1162201D03*
Y1184201D03*
Y1206201D03*
Y1228201D03*
Y1250201D03*
Y1272201D03*
Y1294201D03*
Y1316201D03*
Y1338201D03*
Y1404201D03*
Y1448201D03*
Y1470201D03*
Y1492201D03*
Y1514201D03*
Y1536201D03*
Y1558201D03*
Y1580201D03*
X1828889Y1622578D03*
Y1644578D03*
Y1666578D03*
Y1688578D03*
X1854479Y66461D03*
Y110461D03*
Y132461D03*
Y154461D03*
X1847866Y159124D03*
X1854479Y176461D03*
Y198461D03*
Y220461D03*
Y242461D03*
Y264461D03*
Y286461D03*
G54D59*
X922441Y154311D03*
Y243799D03*
G54D12*
X21569Y49379D03*
X21345Y387760D03*
X21309Y395712D03*
X36500Y323500D03*
X33686Y383944D03*
X27309Y383926D03*
X29962Y401000D03*
X36524Y398013D03*
X26771Y398811D03*
X30680Y438142D03*
X35852Y664480D03*
Y686410D03*
Y683910D03*
X43569Y49379D03*
X45423Y197224D03*
Y212224D03*
Y202224D03*
Y207224D03*
X40000Y323500D03*
X55190Y360862D03*
X42809D03*
X46834D03*
X39410Y384582D03*
X39226Y395346D03*
X53825Y421746D03*
X49848Y524210D03*
X49889Y531149D03*
X50880Y1421963D03*
X52405Y1514835D03*
X49405D03*
X52405Y1511986D03*
X49405D03*
X52330Y1509137D03*
X49330D03*
X52796Y1526469D03*
X52905Y1523335D03*
X47760Y1529506D03*
X65347Y66847D03*
X60367D03*
X65347Y71839D03*
X60367D03*
X58457Y69340D03*
X67575Y287500D03*
X56620Y303500D03*
X64150Y434972D03*
X53800Y435451D03*
X54762Y444993D03*
X56800Y524220D03*
X56719Y531120D03*
X64923Y795316D03*
Y832127D03*
Y868938D03*
Y905750D03*
Y942561D03*
Y1089805D03*
Y1126616D03*
Y1163427D03*
Y1200238D03*
Y1237049D03*
X58349Y1412731D03*
X55755Y1511885D03*
X55905Y1514835D03*
X57281Y1523287D03*
X66081D03*
X59881D03*
X63481D03*
X55789Y1509224D03*
X57281Y1526394D03*
X66081D03*
X65281Y1529501D03*
X59881Y1526394D03*
X63481D03*
X62681Y1529501D03*
X64235Y1533150D03*
X61755D03*
X59275D03*
X67196Y1552869D03*
X64235Y1538750D03*
X61755D03*
X59275D03*
X63802Y1579997D03*
X58602D03*
X61302D03*
X75928Y3001D03*
X81159Y17045D03*
X72087Y25977D03*
X74087Y23981D03*
X79043D03*
X81043Y25977D03*
X79192Y19541D03*
X81159Y22037D03*
X73025Y37106D03*
X80111D03*
X73025Y48720D03*
X80111D03*
X69453Y75343D03*
X82367Y71839D03*
X80457Y69340D03*
X82367Y66847D03*
X76347Y72850D03*
X71367D03*
X76347Y77842D03*
X71367D03*
X71779Y157194D03*
Y161194D03*
X71772Y421746D03*
X68365Y443677D03*
X80915Y756766D03*
X73873D03*
Y760266D03*
X69323Y776911D03*
X80915Y763766D03*
X80015Y786950D03*
X69323Y783604D03*
X81065Y791970D03*
X80015Y796989D03*
X69323Y807029D03*
Y813722D03*
Y820415D03*
X80015Y823761D03*
Y833800D03*
X81065Y828781D03*
X69323Y843840D03*
Y850533D03*
X80015Y860572D03*
X81065Y865592D03*
X69323Y857226D03*
X80015Y870611D03*
X69323Y880651D03*
Y887344D03*
Y894037D03*
X80015Y907423D03*
Y897383D03*
X81065Y902403D03*
X69323Y924155D03*
Y917462D03*
X81065Y939214D03*
X80015Y934194D03*
X69323Y930848D03*
X80015Y944234D03*
X69323Y954273D03*
Y960966D03*
Y967659D03*
Y974352D03*
Y981045D03*
Y987737D03*
Y994430D03*
Y1004470D03*
Y1034588D03*
Y1041281D03*
Y1047974D03*
Y1054667D03*
Y1071399D03*
Y1061360D03*
X80015Y1081438D03*
X81065Y1086458D03*
X69323Y1078092D03*
X80015Y1091478D03*
X69323Y1101517D03*
X80015Y1118249D03*
X69323Y1114903D03*
Y1108210D03*
X80015Y1128289D03*
X81065Y1123269D03*
X69323Y1145021D03*
Y1138328D03*
X80015Y1165100D03*
X81065Y1160080D03*
X80015Y1155060D03*
X69323Y1151714D03*
Y1175139D03*
Y1181832D03*
X80015Y1191871D03*
X69323Y1188525D03*
X81065Y1196891D03*
X80015Y1201911D03*
X69323Y1211950D03*
Y1218643D03*
X80015Y1238722D03*
Y1228682D03*
X81065Y1233702D03*
X69323Y1225336D03*
Y1248761D03*
Y1255454D03*
X76378Y1406622D03*
X74325Y1523303D03*
X68870Y1523147D03*
X71359Y1523186D03*
X81868Y1511285D03*
X81405Y1516835D03*
X81905Y1513835D03*
X81405Y1519835D03*
Y1522835D03*
X78808Y1522839D03*
X81905Y1508698D03*
X74440Y1526385D03*
X74462Y1529665D03*
X82696Y1529095D03*
X76806Y1593265D03*
X80400Y1602225D03*
X86139Y17045D03*
X95333D03*
X88148Y19541D03*
X95216Y25977D03*
X86260D03*
X93216Y23981D03*
X88260D03*
X86139Y22037D03*
X95333D03*
X93365Y19541D03*
X94284Y37106D03*
X87198D03*
Y48720D03*
X94284D03*
X87347Y71839D03*
Y66847D03*
X91457Y75340D03*
X93367Y72847D03*
Y77839D03*
X89150Y154494D03*
X93717Y159053D03*
X87654Y376026D03*
X87520Y386502D03*
X85465Y773564D03*
Y780257D03*
Y803682D03*
X94624Y795316D03*
X85465Y810375D03*
Y817068D03*
X94624Y832127D03*
X85465Y840493D03*
Y847186D03*
Y853879D03*
Y877304D03*
X94624Y868938D03*
X85465Y890690D03*
Y883997D03*
X94624Y905750D03*
X85465Y920808D03*
Y914115D03*
Y927501D03*
Y950926D03*
X94624Y942561D03*
X85465Y957619D03*
Y971005D03*
Y964312D03*
Y984391D03*
Y977698D03*
Y991084D03*
Y997777D03*
Y1004470D03*
Y1044627D03*
Y1031241D03*
Y1037934D03*
Y1051320D03*
Y1058013D03*
Y1068052D03*
Y1074745D03*
X94624Y1089805D03*
X85465Y1098171D03*
Y1104863D03*
Y1111556D03*
X94624Y1126616D03*
X85465Y1134982D03*
Y1148367D03*
Y1141675D03*
X94624Y1163427D03*
X85465Y1178486D03*
Y1171793D03*
Y1185178D03*
Y1208604D03*
X94624Y1200238D03*
X85465Y1215297D03*
Y1221989D03*
X94624Y1237049D03*
X85465Y1252108D03*
Y1245415D03*
X90501Y1338952D03*
X92791Y1341302D03*
X96191Y1337721D03*
X92941Y1346172D03*
X91000Y1350300D03*
X88500D03*
X84000Y1408000D03*
Y1412500D03*
Y1417000D03*
X97530Y1410247D03*
X93000Y1430500D03*
X84000Y1421500D03*
Y1426000D03*
X93000Y1435500D03*
Y1440000D03*
X84500D03*
X95624Y1523287D03*
X85368Y1511285D03*
X85405Y1513835D03*
X88868Y1511285D03*
X88905Y1513835D03*
X93024Y1523287D03*
X85405Y1508698D03*
X88905D03*
X97498Y1533150D03*
X95624Y1526394D03*
X95018Y1533150D03*
X88696Y1526769D03*
X93024Y1526394D03*
X88696Y1523769D03*
X97498Y1538750D03*
X95018D03*
X93029Y1705225D03*
X97683Y1722477D03*
X97928Y3001D03*
X100313Y17045D03*
X109506D03*
X109389Y25977D03*
X100433D03*
X107389Y23981D03*
X102433D03*
X100313Y22037D03*
X102321Y19541D03*
X109506Y22037D03*
X107538Y19541D03*
X108458Y37106D03*
X101371D03*
Y48720D03*
X108458D03*
X98347Y72847D03*
X104367Y71839D03*
X109347D03*
X102457Y69340D03*
X104367Y66847D03*
X109347D03*
X98347Y77839D03*
X104829Y151191D03*
X107931Y158767D03*
X99754Y155807D03*
X110616Y756766D03*
X103574D03*
Y760266D03*
X99024Y776911D03*
X110616Y763766D03*
X103574Y767266D03*
X99024Y783604D03*
X109716Y786950D03*
X110766Y791970D03*
X99024Y807029D03*
X109716Y796989D03*
X99024Y813722D03*
Y820415D03*
X109716Y823761D03*
Y833800D03*
X110766Y828781D03*
X99024Y843840D03*
Y850533D03*
Y857226D03*
X109716Y860572D03*
X110766Y865592D03*
X99024Y880651D03*
X109716Y870611D03*
X99024Y887344D03*
Y894037D03*
X109716Y897383D03*
X110766Y902403D03*
X109716Y907423D03*
X99024Y924155D03*
Y917462D03*
Y930848D03*
X110766Y939214D03*
X109716Y934194D03*
X99024Y954273D03*
X109716Y944234D03*
X99024Y960966D03*
Y967659D03*
Y974352D03*
Y981045D03*
Y987737D03*
Y994430D03*
Y1004470D03*
Y1034588D03*
Y1041281D03*
Y1047974D03*
Y1054667D03*
Y1071399D03*
Y1061360D03*
Y1078092D03*
X109716Y1081438D03*
X110766Y1086458D03*
X99024Y1101517D03*
X109716Y1091478D03*
X99024Y1114903D03*
Y1108210D03*
X109716Y1118249D03*
Y1128289D03*
X110766Y1123269D03*
X99024Y1145021D03*
Y1138328D03*
Y1151714D03*
X109716Y1165100D03*
X110766Y1160080D03*
X109716Y1155060D03*
X99024Y1175139D03*
Y1181832D03*
Y1188525D03*
X109716Y1191871D03*
X110766Y1196891D03*
X109716Y1201911D03*
X99024Y1211950D03*
Y1218643D03*
Y1225336D03*
X109716Y1228682D03*
Y1238722D03*
X110766Y1233702D03*
X99024Y1248761D03*
Y1255454D03*
X99211Y1337771D03*
X112677Y1357409D03*
X110077D03*
X107477D03*
X104877D03*
X111581Y1372872D03*
X106721Y1367272D03*
Y1372872D03*
X109151D03*
X112677Y1363473D03*
X110077D03*
X112677Y1360516D03*
X110077D03*
X107477D03*
X104877D03*
X100347Y1361417D03*
X109151Y1367272D03*
X111581D03*
X111630Y1385287D03*
X101995Y1388247D03*
X98492Y1523287D03*
X100922D03*
X109635Y1523158D03*
X106713Y1523098D03*
X103513D03*
X99978Y1533150D03*
X98492Y1526394D03*
X98424Y1529501D03*
X100922Y1526394D03*
X101024Y1529501D03*
X108861Y1528840D03*
Y1526410D03*
X101396Y1552769D03*
X99978Y1538750D03*
X106448Y1696436D03*
X119928Y3001D03*
X114486Y17045D03*
X123683D03*
X123563Y25977D03*
X114607D03*
X116607Y23981D03*
X121563D03*
X114486Y22037D03*
X116494Y19541D03*
X121712D03*
X123683Y22037D03*
X122631Y37106D03*
X115544D03*
Y48720D03*
X122631D03*
X113457Y75340D03*
X115367Y72847D03*
X120347D03*
X126367Y71842D03*
X124457Y69343D03*
X126367Y66850D03*
X115367Y77839D03*
X120347D03*
X115166Y773564D03*
Y780257D03*
X124324Y795316D03*
X115166Y803682D03*
Y810375D03*
Y817068D03*
X124324Y832127D03*
X115166Y840493D03*
Y847186D03*
Y853879D03*
Y877304D03*
X124324Y868938D03*
X115166Y890690D03*
Y883997D03*
X124324Y905750D03*
X115166Y920808D03*
Y914115D03*
Y927501D03*
Y950926D03*
X124324Y942561D03*
X115166Y957619D03*
Y971005D03*
Y964312D03*
Y984391D03*
Y977698D03*
Y991084D03*
Y997777D03*
Y1004470D03*
Y1031241D03*
Y1037934D03*
Y1044627D03*
Y1051320D03*
Y1058013D03*
Y1068052D03*
Y1074745D03*
X124324Y1089805D03*
X115166Y1098171D03*
Y1104863D03*
Y1111556D03*
X124324Y1126616D03*
X115166Y1134982D03*
Y1148367D03*
Y1141675D03*
X124324Y1163427D03*
X115166Y1178486D03*
Y1171793D03*
Y1185178D03*
Y1208604D03*
X124324Y1200238D03*
X115166Y1215297D03*
Y1221989D03*
X124324Y1237049D03*
X115166Y1252108D03*
Y1245415D03*
X124071Y1337843D03*
X126671D03*
X115277Y1357409D03*
X126491Y1354871D03*
X125241Y1357371D03*
X126491Y1352271D03*
X123891Y1354871D03*
Y1352271D03*
X120221Y1357425D03*
X126491Y1349671D03*
X123891D03*
X117777Y1357409D03*
X121207Y1360686D03*
X114405Y1509335D03*
Y1516335D03*
Y1512835D03*
Y1519835D03*
Y1522835D03*
X116905D03*
Y1519835D03*
Y1512835D03*
Y1516335D03*
Y1509335D03*
Y1526335D03*
X120052Y1712450D03*
X141928Y3001D03*
X128663Y17045D03*
X130668Y19541D03*
X128663Y22037D03*
X129718Y37106D03*
Y48720D03*
X135457Y75340D03*
X137367Y72847D03*
X142347D03*
X131347Y71842D03*
Y66850D03*
X137367Y77839D03*
X142347D03*
X128367Y202241D03*
Y207241D03*
Y197241D03*
Y212241D03*
X139440Y439000D03*
X138090Y441900D03*
X140800Y441920D03*
X134812Y530955D03*
X131861Y664958D03*
X139869Y686582D03*
X140316Y756766D03*
X133124D03*
Y760266D03*
X128724Y776911D03*
X140316Y763766D03*
X133124Y767266D03*
X139416Y786950D03*
X128724Y783604D03*
X140466Y791970D03*
X128724Y807029D03*
X139416Y796989D03*
X128724Y813722D03*
Y820415D03*
X139416Y823761D03*
Y833800D03*
X140466Y828781D03*
X128724Y843840D03*
Y850533D03*
Y857226D03*
X139416Y860572D03*
X140466Y865592D03*
X128724Y880651D03*
X139416Y870611D03*
X128724Y887344D03*
Y894037D03*
X139416Y897383D03*
X140466Y902403D03*
X139416Y907423D03*
X128724Y924155D03*
Y917462D03*
X140466Y939214D03*
X139416Y934194D03*
X128724Y930848D03*
Y954273D03*
X139416Y944234D03*
X128724Y960966D03*
Y967659D03*
Y974352D03*
Y981045D03*
Y987737D03*
Y994430D03*
Y1004470D03*
Y1034588D03*
Y1041281D03*
Y1047974D03*
Y1054667D03*
Y1071399D03*
Y1061360D03*
X139416Y1081438D03*
X140466Y1086458D03*
X128724Y1078092D03*
Y1101517D03*
X139416Y1091478D03*
X128724Y1114903D03*
X139416Y1118249D03*
X128724Y1108210D03*
X139416Y1128289D03*
X140466Y1123269D03*
X128724Y1145021D03*
Y1138328D03*
X139416Y1165100D03*
X140466Y1160080D03*
X139416Y1155060D03*
X128724Y1151714D03*
Y1175139D03*
Y1181832D03*
X139416Y1191871D03*
X128724Y1188525D03*
X140466Y1196891D03*
X139416Y1201911D03*
X128724Y1211950D03*
Y1218643D03*
Y1225336D03*
X139416Y1228682D03*
X140466Y1233702D03*
X139416Y1238722D03*
X128724Y1248761D03*
Y1255454D03*
X137551Y1337771D03*
X131791Y1337811D03*
X140077Y1357409D03*
X137477D03*
X139321Y1367272D03*
Y1372872D03*
X141751D03*
X140077Y1360516D03*
X137477D03*
X132947Y1361417D03*
X141751Y1367272D03*
X130492Y1384789D03*
X132150Y1386740D03*
X132643Y1711846D03*
X150473Y25977D03*
X157429Y23981D03*
X152473D03*
X151410Y37106D03*
Y48720D03*
X153347Y71842D03*
X148367D03*
X153347Y66850D03*
X148367D03*
X146453Y69343D03*
X150318Y233536D03*
X142660Y438930D03*
X143720Y441960D03*
X145960Y438800D03*
X146930Y441870D03*
X149210Y438640D03*
X149830Y441920D03*
X149672Y665500D03*
X152705Y683218D03*
X144866Y773564D03*
Y780257D03*
X154025Y795316D03*
X144866Y803682D03*
Y810375D03*
Y817068D03*
X154025Y832127D03*
X144866Y840493D03*
Y847186D03*
Y853879D03*
Y877304D03*
X154025Y868938D03*
X144866Y890690D03*
Y883997D03*
X154025Y905750D03*
X144866Y920808D03*
Y914115D03*
Y927501D03*
X154025Y942561D03*
X144866Y950926D03*
Y957619D03*
Y971005D03*
Y964312D03*
Y984391D03*
Y977698D03*
Y991084D03*
Y997777D03*
Y1004470D03*
Y1031241D03*
Y1037934D03*
Y1044627D03*
Y1051320D03*
Y1058013D03*
Y1068052D03*
Y1074745D03*
X154025Y1089805D03*
X144866Y1098171D03*
Y1104863D03*
Y1111556D03*
X154025Y1126616D03*
X144866Y1134982D03*
Y1148367D03*
Y1141675D03*
X154025Y1163427D03*
X144866Y1178486D03*
Y1171793D03*
Y1185178D03*
Y1208604D03*
X154025Y1200238D03*
X144866Y1215297D03*
Y1221989D03*
X154025Y1237049D03*
X144866Y1252108D03*
Y1245415D03*
X156491Y1354871D03*
Y1352271D03*
X152821Y1357425D03*
X156491Y1349671D03*
X145277Y1357409D03*
X147877D03*
X142677D03*
X150377D03*
X144181Y1367272D03*
X153767Y1360456D03*
Y1363413D03*
X144181Y1372872D03*
X142677Y1360516D03*
X145277Y1363473D03*
X142677D03*
X145277Y1360516D03*
X144230Y1385287D03*
X150900Y1433500D03*
Y1429500D03*
X143478Y1440000D03*
X151082Y1436653D03*
X146978Y1440000D03*
X147277Y1712791D03*
X152815Y1705500D03*
X155740Y1729726D03*
X163928Y3001D03*
X164525Y17045D03*
X159545D03*
X159429Y25977D03*
X164646D03*
X171602Y23981D03*
X166646D03*
X157578Y19541D03*
X166534D03*
X171751D03*
X164525Y22037D03*
X159545D03*
X158497Y37106D03*
X165584D03*
X158497Y48720D03*
X165584D03*
X158661Y75340D03*
X160571Y72847D03*
X165551D03*
X171571Y71839D03*
X169661Y69340D03*
X171571Y66847D03*
X160571Y77839D03*
X165551D03*
X172120Y416600D03*
X168950Y412950D03*
X168910Y415930D03*
X170500Y441420D03*
X167580Y441380D03*
X164870Y441360D03*
X169440Y438390D03*
X166220Y438460D03*
X162975Y760266D03*
Y756766D03*
X170017D03*
X158425Y776911D03*
X170017Y763766D03*
X162975Y767266D03*
X158425Y783604D03*
X169117Y786950D03*
X170167Y791970D03*
X158425Y807029D03*
X169117Y796989D03*
X158425Y813722D03*
Y820415D03*
X169117Y823761D03*
Y833800D03*
X170167Y828781D03*
X158425Y843840D03*
Y850533D03*
Y857226D03*
X169117Y860572D03*
X170167Y865592D03*
X158425Y880651D03*
X169117Y870611D03*
X158425Y887344D03*
Y894037D03*
X169117Y897383D03*
X170167Y902403D03*
X169117Y907423D03*
X158425Y924155D03*
Y917462D03*
Y930848D03*
X170167Y939214D03*
X169117Y934194D03*
X158425Y954273D03*
X169117Y944234D03*
X158425Y960966D03*
Y967659D03*
Y974352D03*
Y981045D03*
Y987737D03*
Y994430D03*
Y1004470D03*
Y1034588D03*
Y1041281D03*
Y1047974D03*
Y1054667D03*
Y1071399D03*
Y1061360D03*
Y1078092D03*
X169117Y1081438D03*
X170167Y1086458D03*
X158425Y1101517D03*
X169117Y1091478D03*
X158425Y1114903D03*
Y1108210D03*
X169117Y1118249D03*
Y1128289D03*
X170167Y1123269D03*
X158425Y1145021D03*
Y1138328D03*
X169117Y1165100D03*
X170167Y1160080D03*
X169117Y1155060D03*
X158425Y1151714D03*
Y1175139D03*
Y1181832D03*
Y1188525D03*
X169117Y1191871D03*
X170167Y1196891D03*
X169117Y1201911D03*
X158425Y1211950D03*
Y1218643D03*
Y1225336D03*
X169117Y1238722D03*
Y1228682D03*
X170167Y1233702D03*
X158425Y1248761D03*
Y1255454D03*
X171481Y1337853D03*
X164481Y1337813D03*
X161881D03*
X170177Y1357409D03*
X159091Y1354871D03*
X157841Y1357371D03*
X159091Y1352271D03*
Y1349671D03*
X172021Y1367272D03*
Y1372872D03*
X170177Y1360516D03*
X165647Y1361417D03*
X163192Y1384789D03*
X164850Y1386740D03*
X168661Y1459995D03*
X166751Y1462595D03*
X168661Y1465195D03*
X164650Y1529350D03*
Y1540250D03*
X171925Y1708428D03*
X167500Y1712864D03*
X171925Y1727581D03*
X157860Y1718500D03*
X185928Y3001D03*
X173719Y17045D03*
X178699D03*
X173602Y25977D03*
X173719Y22037D03*
X178699D03*
X180707Y19541D03*
X172670Y37106D03*
X179757D03*
X172670Y48720D03*
X179757D03*
X176551Y71839D03*
Y66847D03*
X180657Y75343D03*
X182571Y72850D03*
Y77842D03*
X182548Y147260D03*
X176610Y441380D03*
X175990Y438100D03*
X173710Y441330D03*
X172740Y438260D03*
X173299Y664958D03*
X172802Y682036D03*
X174567Y773564D03*
Y780257D03*
Y803682D03*
X183726Y795316D03*
X174567Y810375D03*
Y817068D03*
X183726Y832127D03*
X174567Y840493D03*
Y847186D03*
Y853879D03*
Y877304D03*
X183726Y868938D03*
X174567Y890690D03*
Y883997D03*
X183726Y905750D03*
X174567Y920808D03*
Y914115D03*
Y927501D03*
Y950926D03*
X183726Y942561D03*
X174567Y957619D03*
Y971005D03*
Y964312D03*
Y984391D03*
Y977698D03*
Y991084D03*
Y997777D03*
Y1004470D03*
Y1031241D03*
Y1037934D03*
Y1044627D03*
Y1051320D03*
Y1058013D03*
Y1068052D03*
Y1074745D03*
X183726Y1089805D03*
X174567Y1098171D03*
Y1104863D03*
Y1111556D03*
Y1134982D03*
X183726Y1126616D03*
X174567Y1148367D03*
Y1141675D03*
X183726Y1163427D03*
X174567Y1178486D03*
Y1171793D03*
Y1185178D03*
Y1208604D03*
X183726Y1200238D03*
X174567Y1215297D03*
Y1221989D03*
X183726Y1237049D03*
X174567Y1252108D03*
Y1245415D03*
X185701Y1337853D03*
X183101D03*
X174081D03*
X172777Y1357409D03*
X183077D03*
X185521Y1357425D03*
X175377Y1357409D03*
X177977D03*
X180577D03*
X176881Y1367272D03*
X174451D03*
X186467Y1360456D03*
Y1363413D03*
X172777Y1360516D03*
X176881Y1372872D03*
X174451D03*
X177977Y1363473D03*
X175377D03*
Y1360516D03*
X177977D03*
X176930Y1385287D03*
X173441Y1459995D03*
X173451Y1452895D03*
X180141Y1450295D03*
X175361D03*
X180141Y1455495D03*
X175361D03*
X173441Y1465195D03*
X186851Y1472295D03*
X177322Y1498320D03*
X173980Y1528731D03*
X185254Y1686870D03*
X179444Y1708810D03*
X184340Y1718000D03*
X194607Y25977D03*
X196607Y23981D03*
X201563D03*
X201712Y19541D03*
X195544Y37106D03*
Y48720D03*
X193571Y71839D03*
X198551D03*
X191661Y69340D03*
X193571Y66847D03*
X198551D03*
X187656Y72850D03*
Y77842D03*
X195979Y109462D03*
X203061Y131158D03*
X195690Y415390D03*
X195730Y412410D03*
X200405Y622385D03*
Y632385D03*
X192676Y760266D03*
Y756766D03*
X199718D03*
X192676Y767266D03*
X199718Y763766D03*
X188126Y776911D03*
X199868Y791970D03*
X198818Y786950D03*
X188126Y783604D03*
X198818Y796989D03*
X188126Y807029D03*
Y813722D03*
Y820415D03*
X199868Y828781D03*
X198818Y823761D03*
Y833800D03*
X188126Y843840D03*
Y850533D03*
X199868Y865592D03*
X198818Y860572D03*
X188126Y857226D03*
X198818Y870611D03*
X188126Y880651D03*
Y887344D03*
Y894037D03*
X199868Y902403D03*
X198818Y897383D03*
Y907423D03*
X188126Y917462D03*
Y924155D03*
X199868Y939214D03*
X198818Y934194D03*
X188126Y930848D03*
X198818Y944234D03*
X188126Y954273D03*
Y960966D03*
Y967659D03*
Y974352D03*
Y981045D03*
Y987737D03*
Y994430D03*
Y1004470D03*
Y1034588D03*
Y1041281D03*
Y1047974D03*
Y1054667D03*
Y1061360D03*
Y1071399D03*
X199868Y1086458D03*
X198818Y1081438D03*
X188126Y1078092D03*
X198818Y1091478D03*
X188126Y1101517D03*
X198818Y1118249D03*
X188126Y1108210D03*
Y1114903D03*
X199868Y1123269D03*
X198818Y1128289D03*
X188126Y1138328D03*
Y1145021D03*
X199868Y1160080D03*
X198818Y1155060D03*
Y1165100D03*
X188126Y1151714D03*
Y1175139D03*
X198818Y1191871D03*
X188126Y1181832D03*
Y1188525D03*
X199868Y1196891D03*
X198818Y1201911D03*
X188126Y1211950D03*
Y1218643D03*
X199868Y1233702D03*
X198818Y1228682D03*
Y1238722D03*
X188126Y1225336D03*
Y1248761D03*
Y1255454D03*
X195771Y1337903D03*
X193171D03*
X190541Y1357371D03*
X189191Y1354871D03*
Y1352271D03*
X191791Y1354871D03*
Y1352271D03*
X189191Y1349671D03*
X191791D03*
X198547Y1361417D03*
X196092Y1384789D03*
X197750Y1386740D03*
X193551Y1462595D03*
X200241Y1459995D03*
X195461D03*
X202161Y1450295D03*
X200251Y1452895D03*
X202161Y1455495D03*
X193541Y1469695D03*
X188761D03*
X193541Y1474895D03*
X188761D03*
X200241Y1465195D03*
X195461D03*
X197703Y1550897D03*
X192978Y1550797D03*
X188254D03*
X187388Y1594876D03*
X192344D03*
X199448D03*
X187388Y1589884D03*
X199448D03*
X192344D03*
X193418Y1604876D03*
Y1599884D03*
X198374D03*
Y1604876D03*
Y1611796D03*
X193418D03*
X198374Y1616788D03*
X193418D03*
X192344Y1626788D03*
X199448D03*
X192344Y1621796D03*
X199448D03*
X187388D03*
Y1626788D03*
X200848Y1655656D03*
X190242Y1656635D03*
X201120Y1668603D03*
X199040Y1666925D03*
X196366Y1664821D03*
X190271Y1671753D03*
X195153Y1679774D03*
X190391Y1701988D03*
X195300Y1694898D03*
X194000Y1712362D03*
X201531Y1715000D03*
X192745Y1707106D03*
X199547Y1704605D03*
X195150Y1723000D03*
X207928Y3001D03*
X208659Y17045D03*
X203679D03*
X208780Y25977D03*
X203563D03*
X210780Y23981D03*
X215736D03*
X210668Y19541D03*
X215885D03*
X208659Y22037D03*
X203679D03*
X202631Y37106D03*
X216804D03*
X209718D03*
X202631Y48720D03*
X209718D03*
X216804D03*
X202795Y75340D03*
X204705Y72847D03*
X209685D03*
X213791Y69343D03*
X215705Y66850D03*
Y71842D03*
X204705Y77839D03*
X209685D03*
X214107Y113022D03*
X205489Y142790D03*
X206760Y148760D03*
X206805Y622385D03*
X203605D03*
X206805Y632385D03*
X203605D03*
X204268Y773564D03*
Y780257D03*
X213427Y795316D03*
X204268Y803682D03*
Y810375D03*
Y817068D03*
X213427Y832127D03*
X204268Y840493D03*
Y847186D03*
Y853879D03*
X213427Y868938D03*
X204268Y877304D03*
Y883997D03*
Y890690D03*
X213427Y905750D03*
X204268Y914115D03*
Y920808D03*
Y927501D03*
X213427Y942561D03*
X204268Y950926D03*
Y957619D03*
Y964312D03*
Y971005D03*
Y977698D03*
Y984391D03*
Y991084D03*
Y997777D03*
Y1004470D03*
Y1031241D03*
Y1037934D03*
Y1044627D03*
Y1051320D03*
Y1058013D03*
Y1068052D03*
Y1074745D03*
X213427Y1089805D03*
X204268Y1098171D03*
Y1104863D03*
Y1111556D03*
X213427Y1126616D03*
X204268Y1134982D03*
Y1141675D03*
Y1148367D03*
X213427Y1163427D03*
X204268Y1171793D03*
Y1178486D03*
Y1185178D03*
X213427Y1200238D03*
X204268Y1208604D03*
Y1215297D03*
Y1221989D03*
X213427Y1237049D03*
X204268Y1245415D03*
Y1252108D03*
X215977Y1357409D03*
X210877D03*
X208277D03*
X213477D03*
X205677D03*
X203077D03*
X207351Y1367272D03*
X209781Y1372872D03*
X204921Y1367272D03*
Y1372872D03*
X207351D03*
X210877Y1363473D03*
X208277D03*
Y1360516D03*
X210877D03*
X205677D03*
X203077D03*
X209781Y1367272D03*
X209830Y1385287D03*
X213648Y1416262D03*
X206941Y1450295D03*
Y1455495D03*
X213651Y1472295D03*
X215561Y1469695D03*
Y1474895D03*
X216601Y1550697D03*
X202427D03*
X211876Y1550897D03*
X207152D03*
X211508Y1594876D03*
X204404D03*
X216464D03*
X211508Y1589884D03*
X204404D03*
X216464D03*
X210434Y1604876D03*
X205478D03*
X210434Y1599884D03*
X205478D03*
Y1611796D03*
X210434D03*
Y1616788D03*
X205478D03*
X211508Y1626788D03*
X216464D03*
X211508Y1621796D03*
X216464D03*
X204404Y1626788D03*
Y1621796D03*
X203807Y1681173D03*
Y1696366D03*
X211103Y1708988D03*
X229928Y3001D03*
X217853Y17045D03*
X222833D03*
X217736Y25977D03*
X217853Y22037D03*
X222833D03*
X224841Y19541D03*
X223891Y37106D03*
X230977D03*
X223891Y48720D03*
X230977D03*
X224795Y75340D03*
X226705Y72847D03*
X231685D03*
X220685Y66850D03*
Y71842D03*
X231685Y77839D03*
X226705D03*
X233653Y162074D03*
X222000Y160000D03*
X220687Y522453D03*
X226687D03*
X233493Y676906D03*
X227493D03*
X224493D03*
X230493D03*
X221493D03*
X222377Y760266D03*
Y756766D03*
X229419D03*
X222377Y767266D03*
X229419Y763119D03*
X217827Y776911D03*
X229569Y791970D03*
X228519Y786950D03*
X217827Y783604D03*
X228519Y796989D03*
X217827Y807029D03*
Y813722D03*
Y820415D03*
X229569Y828781D03*
X228519Y823761D03*
Y833800D03*
X217827Y843840D03*
Y850533D03*
X229569Y865592D03*
X228519Y860572D03*
X217827Y857226D03*
X228519Y870611D03*
X217827Y880651D03*
Y887344D03*
Y894037D03*
X229569Y902403D03*
X228519Y897383D03*
Y907423D03*
X217827Y917462D03*
Y924155D03*
X229569Y939214D03*
X228519Y934194D03*
X217827Y930848D03*
X228519Y944234D03*
X217827Y954273D03*
Y960966D03*
Y967659D03*
Y974352D03*
Y981045D03*
Y987737D03*
Y994430D03*
Y1004470D03*
Y1034588D03*
Y1041281D03*
Y1047974D03*
Y1054667D03*
Y1061360D03*
Y1071399D03*
X229569Y1086458D03*
X228519Y1081438D03*
X217827Y1078092D03*
Y1101517D03*
X228519Y1091478D03*
Y1118249D03*
X217827Y1108210D03*
Y1114903D03*
X229569Y1123269D03*
X228519Y1128289D03*
X217827Y1138328D03*
Y1145021D03*
X229569Y1160080D03*
X228519Y1155060D03*
Y1165100D03*
X217827Y1151714D03*
Y1175139D03*
X228519Y1191871D03*
X217827Y1181832D03*
Y1188525D03*
X229569Y1196891D03*
X228519Y1201911D03*
X217827Y1211950D03*
Y1218643D03*
X229569Y1233702D03*
X228519Y1228682D03*
Y1238722D03*
X217827Y1225336D03*
Y1248761D03*
Y1255454D03*
X224481Y1326418D03*
X221881D03*
X224481Y1323918D03*
X221881Y1321418D03*
X224481D03*
X221881Y1323918D03*
X230171Y1323904D03*
Y1321404D03*
X227871Y1338124D03*
X223941Y1338068D03*
X221341D03*
X230661Y1338124D03*
X224691Y1354871D03*
Y1352271D03*
X223441Y1357371D03*
X222091Y1354871D03*
Y1352271D03*
X218421Y1357425D03*
X224691Y1349671D03*
X222091D03*
X219367Y1360456D03*
Y1363413D03*
X231347Y1361417D03*
X228892Y1384789D03*
X230550Y1386740D03*
X228693Y1408885D03*
X224881Y1410685D03*
X220803Y1412115D03*
X217097Y1413863D03*
X227051Y1452895D03*
X220351Y1462595D03*
X228961Y1450295D03*
Y1455495D03*
X227041Y1459995D03*
X222261D03*
X220341Y1469695D03*
Y1474895D03*
X227041Y1465195D03*
X222261D03*
X226050Y1550897D03*
X221325Y1550797D03*
X230774Y1550897D03*
X228524Y1594876D03*
X223568D03*
Y1589884D03*
X228524D03*
X222494Y1604876D03*
X217538D03*
X222494Y1599884D03*
X217538D03*
X229598Y1604876D03*
Y1599884D03*
Y1611796D03*
X217538D03*
X222494D03*
X229598Y1616788D03*
X217538D03*
X222494D03*
X223568Y1626788D03*
X228524D03*
X223568Y1621796D03*
X228524D03*
X243486Y23005D03*
X244296Y59765D03*
X242251Y162515D03*
X246250Y204360D03*
X233438Y593556D03*
X236638D03*
X233456Y601598D03*
X236656D03*
X236674Y609640D03*
X233474D03*
X233969Y773564D03*
Y780257D03*
Y803682D03*
Y810375D03*
Y817068D03*
Y840493D03*
Y847186D03*
Y853879D03*
Y877304D03*
Y883997D03*
Y890690D03*
Y914115D03*
Y920808D03*
Y927501D03*
Y950926D03*
Y957619D03*
Y964312D03*
Y971005D03*
Y977698D03*
Y984391D03*
Y991084D03*
Y997777D03*
Y1004470D03*
Y1031241D03*
Y1037934D03*
Y1044627D03*
Y1051320D03*
Y1058013D03*
Y1068052D03*
Y1074745D03*
Y1098171D03*
Y1104863D03*
Y1111556D03*
Y1134982D03*
Y1141675D03*
Y1148367D03*
Y1171793D03*
Y1178486D03*
Y1185178D03*
Y1208604D03*
Y1215297D03*
Y1221989D03*
Y1245415D03*
Y1252108D03*
X232961Y1323904D03*
Y1321404D03*
X239561Y1338124D03*
X243677Y1357409D03*
X241077D03*
X238477D03*
X235877D03*
X246277D03*
X242581Y1367272D03*
X240151D03*
X243677Y1363473D03*
X241077D03*
Y1360516D03*
X243677D03*
X242581Y1372872D03*
X240151D03*
X237721D03*
Y1367272D03*
X238477Y1360516D03*
X235877D03*
X242630Y1385287D03*
X233194Y1407349D03*
X233741Y1450295D03*
Y1455495D03*
X240451Y1472295D03*
X242361Y1469695D03*
Y1474895D03*
X235499Y1550897D03*
X240223D03*
X244947Y1550697D03*
X240584Y1594876D03*
X235628D03*
Y1589884D03*
X240584D03*
X246614Y1604876D03*
Y1599884D03*
X234554Y1604876D03*
Y1599884D03*
X241658Y1604876D03*
Y1599884D03*
X246614Y1611796D03*
X241658D03*
X234554D03*
X246614Y1616788D03*
X241658D03*
X234554D03*
X235628Y1626788D03*
X240584D03*
X235628Y1621796D03*
X240584D03*
X251928Y3001D03*
X247716Y75865D03*
Y71865D03*
X251793Y100846D03*
X261383Y133786D03*
X258253D03*
X249735Y152694D03*
X254095Y209235D03*
X254671Y642138D03*
X258470Y775410D03*
X260671Y1338124D03*
X258071D03*
X247725Y1338141D03*
X257491Y1352271D03*
X256241Y1357371D03*
X257491Y1354871D03*
X254891Y1352271D03*
Y1354871D03*
X251221Y1357425D03*
X248777Y1357409D03*
X257491Y1349671D03*
X254891D03*
X252167Y1363413D03*
Y1360456D03*
X253851Y1452895D03*
X247151Y1462595D03*
X260541Y1450295D03*
X255761D03*
X260541Y1455495D03*
X255761D03*
X253841Y1459995D03*
X249061D03*
X253841Y1465195D03*
X249061D03*
X247141Y1469695D03*
Y1474895D03*
X259120Y1550797D03*
X254396Y1550897D03*
X249671D03*
X259748Y1594876D03*
X247688D03*
X252644D03*
X247688Y1589884D03*
X259748D03*
X252644D03*
X253718Y1604876D03*
X258674D03*
X253718Y1599884D03*
X258674D03*
Y1611796D03*
X253718D03*
X258674Y1616788D03*
X253718D03*
X252644Y1626788D03*
X259748D03*
X252644Y1621796D03*
X259748D03*
X247688Y1626788D03*
Y1621796D03*
X273928Y3001D03*
X272596Y27185D03*
X263276Y34625D03*
X271596Y40165D03*
X270364Y118415D03*
X272361Y120243D03*
X264574Y159206D03*
Y155206D03*
X267500Y220441D03*
X265100Y595078D03*
X270905Y608485D03*
X273905D03*
Y611485D03*
X272603Y692910D03*
Y695510D03*
X271491Y1291740D03*
X274091D03*
X272077Y1314370D03*
X269477D03*
X274677D03*
X272077Y1311263D03*
X269477D03*
X274677D03*
X271321Y1326726D03*
Y1321126D03*
X276181Y1326726D03*
X273751D03*
X274677Y1317327D03*
X264947Y1315271D03*
X276181Y1321126D03*
X273751D03*
X276230Y1339141D03*
X264085Y1339175D03*
X267251Y1452895D03*
X273941Y1450295D03*
X269161D03*
X273941Y1455495D03*
X269161D03*
X276637Y1523953D03*
X270139Y1548563D03*
X271808Y1594876D03*
X264704D03*
X271808Y1589884D03*
X264704D03*
X265778Y1604876D03*
X270734D03*
X265778Y1599790D03*
X270734D03*
Y1611796D03*
X265778D03*
X270734Y1616788D03*
X265778D03*
X271808Y1626788D03*
Y1621796D03*
X264704Y1626788D03*
Y1621796D03*
X291000Y14820D03*
X285896Y23965D03*
X291156Y21395D03*
X286716Y40020D03*
X285499Y53191D03*
X278989Y48720D03*
X286076D03*
X283949Y152506D03*
X288516Y157065D03*
X285260Y234000D03*
X279500Y234075D03*
X290865Y609470D03*
X277105Y608485D03*
X280305D03*
X277105Y611485D03*
X280305D03*
X286665Y609470D03*
X283705Y608485D03*
X284705Y605485D03*
X283705Y611485D03*
X287832Y674150D03*
X283921Y1291740D03*
X281321D03*
X284821Y1311279D03*
X282377Y1311263D03*
X279877D03*
X277277Y1314370D03*
Y1311263D03*
X288491Y1306125D03*
Y1308725D03*
X291091Y1306125D03*
Y1308725D03*
X288491Y1303525D03*
X291091D03*
X289841Y1311225D03*
X285767Y1314310D03*
Y1317267D03*
X277277Y1317327D03*
X283946Y1530595D03*
X286446D03*
X288824Y1594876D03*
X276764D03*
X283868D03*
Y1589884D03*
X276764D03*
X288824D03*
X277838Y1604876D03*
X282794D03*
X277838Y1599884D03*
X282794D03*
X289898Y1604876D03*
Y1599884D03*
Y1611796D03*
X282794D03*
X277838D03*
X289898Y1616788D03*
X282794D03*
X277838D03*
X283868Y1626788D03*
X288824D03*
X283868Y1621796D03*
X288824D03*
X276764Y1626788D03*
Y1621796D03*
X295928Y3001D03*
X296272Y69128D03*
X293443Y78576D03*
X293448Y82486D03*
Y85986D03*
X303043Y79376D03*
X299943Y79276D03*
X299653Y92506D03*
X299628Y149203D03*
X299624Y158706D03*
X294553Y153819D03*
X293000Y216500D03*
X294165Y609570D03*
X297838Y609585D03*
X300965Y609570D03*
X304449D03*
X305121Y726348D03*
X298991D03*
X294541Y1291378D03*
X291941D03*
X302373Y1314342D03*
X304973D03*
X302373Y1311235D03*
X304973D03*
X304217Y1326698D03*
Y1321098D03*
X297843Y1315243D03*
X295388Y1338615D03*
X297046Y1340566D03*
X305199Y1398269D03*
Y1400769D03*
X295116Y1398132D03*
Y1400632D03*
X292516D03*
Y1398132D03*
X301513Y1452895D03*
X294813Y1462595D03*
X303423Y1450295D03*
Y1455495D03*
X301503Y1459995D03*
X296723D03*
X301503Y1465195D03*
X296723D03*
X299950Y1499500D03*
X301550Y1518040D03*
Y1514420D03*
Y1510800D03*
X302042Y1528731D03*
X300884Y1594876D03*
X295928D03*
Y1589884D03*
X300884D03*
X294854Y1604876D03*
Y1599884D03*
X301958Y1604876D03*
Y1599884D03*
Y1611796D03*
X294854D03*
X301958Y1616788D03*
X294854D03*
X295928Y1626788D03*
X300884D03*
X295928Y1621796D03*
X300884D03*
X317928Y3001D03*
X306716Y39985D03*
X320053Y85806D03*
Y88806D03*
X310425Y243925D03*
X317240Y252970D03*
X308925Y260075D03*
X307865Y609570D03*
X311349Y609632D03*
X313961Y607088D03*
Y604588D03*
X319657Y696415D03*
X319621Y1291740D03*
X321387Y1306097D03*
Y1308697D03*
Y1303497D03*
X317717Y1311251D03*
X315273Y1311235D03*
X312773D03*
X307573Y1314342D03*
Y1311235D03*
X310173Y1314342D03*
Y1311235D03*
X318663Y1314282D03*
X309077Y1321098D03*
X306647D03*
X318663Y1317239D03*
X309077Y1326698D03*
X306647D03*
X307573Y1317299D03*
X310173D03*
X309126Y1339113D03*
X307799Y1400769D03*
Y1398269D03*
X318199Y1400549D03*
X314199D03*
X310399D03*
X308203Y1450295D03*
Y1455495D03*
X314913Y1472295D03*
X316823Y1469695D03*
Y1474895D03*
X321040Y1550797D03*
X316316D03*
X320048Y1594876D03*
X307988D03*
X312944D03*
X307988Y1589884D03*
X320048D03*
X312944D03*
X306914Y1604876D03*
Y1599884D03*
X314018Y1604876D03*
X318974D03*
X314018Y1599884D03*
X318974D03*
Y1611796D03*
X314018D03*
X306914D03*
X318974Y1616788D03*
X314018D03*
X306914D03*
X320048Y1626788D03*
X312944D03*
X320048Y1621796D03*
X312944D03*
X307988Y1626788D03*
Y1621796D03*
X329535Y49379D03*
X331000Y270260D03*
X328966Y543012D03*
X334744Y566086D03*
X333500Y582500D03*
Y578500D03*
X333988Y590633D03*
X329471Y1291778D03*
X322221Y1291740D03*
X326761Y1291778D03*
X335277Y1314285D03*
Y1311178D03*
X323987Y1303497D03*
Y1306097D03*
Y1308697D03*
X322737Y1311197D03*
X330747Y1315186D03*
X328292Y1338558D03*
X329950Y1340509D03*
X333830Y1396299D03*
Y1398899D03*
Y1401499D03*
Y1393799D03*
X324309Y1396599D03*
Y1399199D03*
Y1401799D03*
Y1394099D03*
X321999Y1400549D03*
X321613Y1462595D03*
X323523Y1459995D03*
X328303D03*
X328313Y1452895D03*
X335003Y1450295D03*
X330223D03*
X335003Y1455495D03*
X330223D03*
X328313Y1472295D03*
X323523Y1465195D03*
X328303D03*
X321603Y1469695D03*
Y1474895D03*
X325765Y1550897D03*
X330489Y1550697D03*
X335214Y1550897D03*
X332108Y1594876D03*
X325004D03*
X332108Y1589884D03*
X325004D03*
X326078Y1604876D03*
X331034D03*
X326078Y1599884D03*
X331034D03*
Y1611796D03*
X326078D03*
X331034Y1616788D03*
X326078D03*
X332108Y1626788D03*
X325004D03*
X332108Y1621796D03*
X325004D03*
X343036Y122525D03*
X342075Y287925D03*
X351157Y562415D03*
X345500Y574415D03*
X351157D03*
X338664Y699660D03*
X337030Y697750D03*
X340477Y1314285D03*
X337877D03*
Y1311178D03*
X340477D03*
X350621Y1311194D03*
X348177Y1311178D03*
X343077Y1314285D03*
X345677Y1311178D03*
X343077D03*
X341981Y1321041D03*
X339551D03*
X341981Y1326641D03*
X337121Y1321041D03*
X339551Y1326641D03*
X337121D03*
X340477Y1317242D03*
X343077D03*
X342030Y1339056D03*
X347110Y1398312D03*
X351110D03*
X341760Y1401449D03*
X337760D03*
X349760D03*
X345760D03*
X348413Y1462595D03*
X350323Y1459995D03*
X341713Y1472295D03*
X350323Y1465195D03*
X348403Y1469695D03*
X343623D03*
X348403Y1474895D03*
X343623D03*
X339938Y1550897D03*
X349387Y1550797D03*
X344663Y1550697D03*
X349124Y1594876D03*
X337064D03*
X344168D03*
Y1589884D03*
X337064D03*
X349124D03*
X338138Y1604876D03*
X343094D03*
X338138Y1599884D03*
X343094D03*
X350198Y1604876D03*
Y1599884D03*
Y1611796D03*
X343094D03*
X338138D03*
X350198Y1616788D03*
X343094D03*
X338138D03*
X344168Y1626788D03*
X349124D03*
X344168Y1621796D03*
X349124D03*
X337064Y1626788D03*
Y1621796D03*
X351535Y49379D03*
X366874Y135157D03*
X366771Y127665D03*
X359734Y288768D03*
X360433Y294030D03*
X355832Y297855D03*
X353700Y547893D03*
X356850D03*
X365593Y621622D03*
X364788Y1193918D03*
X364457Y1188109D03*
X359541Y1291918D03*
X362311Y1291968D03*
X356551Y1291880D03*
X353951D03*
X356891Y1306040D03*
Y1308640D03*
Y1303440D03*
X354291Y1306040D03*
Y1308640D03*
Y1303440D03*
X355641Y1311140D03*
X351567Y1314225D03*
Y1317182D03*
X363547Y1315386D03*
X361092Y1338758D03*
X362750Y1340709D03*
X355110Y1398312D03*
X359110D03*
X363110D03*
X357760Y1401449D03*
X353760D03*
X355113Y1452895D03*
X361803Y1450295D03*
X357023D03*
X361803Y1455495D03*
X357023D03*
X355103Y1459995D03*
Y1465195D03*
X354112Y1550897D03*
X358836D03*
X363561D03*
X361184Y1594876D03*
X356228D03*
Y1589884D03*
X361184D03*
X355154Y1604876D03*
Y1599884D03*
X362258Y1604876D03*
Y1599790D03*
Y1611796D03*
X355154D03*
X362258Y1616788D03*
X355154D03*
X356228Y1626788D03*
X361184D03*
X356228Y1621796D03*
X361184D03*
X373535Y49379D03*
X375920Y146577D03*
X380012Y243615D03*
X379200Y298772D03*
X367902Y303760D03*
X380771Y524903D03*
X375943D03*
X371724Y699450D03*
X370090Y697482D03*
X372000Y816862D03*
Y826362D03*
Y828862D03*
Y837862D03*
Y840362D03*
Y849362D03*
X378083Y1184949D03*
X367782Y1199648D03*
X380977Y1311378D03*
X375877Y1314485D03*
X378477Y1311378D03*
X375877D03*
X370677Y1314485D03*
X368077D03*
X373277D03*
X368077Y1311378D03*
X370677D03*
X373277D03*
X375877Y1317442D03*
X372351Y1326841D03*
X369921D03*
Y1321241D03*
X374781Y1326841D03*
X373277Y1317442D03*
X374781Y1321241D03*
X372351D03*
X374830Y1339256D03*
X379610Y1391781D03*
X375056Y1393741D03*
X375213Y1462595D03*
X377123Y1459995D03*
X368513Y1472295D03*
X377123Y1465195D03*
X375203Y1469695D03*
X370423D03*
X375203Y1474895D03*
X370423D03*
X368285Y1550897D03*
X373009Y1550697D03*
X377733Y1550897D03*
X368288Y1594876D03*
X373244D03*
X368288Y1589884D03*
X373244D03*
X367214Y1604876D03*
Y1599790D03*
X374318Y1604876D03*
X379274D03*
X374318Y1599884D03*
X379274D03*
Y1611796D03*
X374318D03*
X367214D03*
X379274Y1616788D03*
X374318D03*
X367214D03*
X373244Y1626788D03*
Y1621796D03*
X368288Y1626788D03*
Y1621796D03*
X372313Y1641759D03*
X379895Y1670046D03*
X372350Y1683284D03*
X385024Y-17575D03*
X381771Y-17589D03*
X388049Y-18895D03*
X381756Y-20104D03*
X385009Y-20090D03*
X381725Y-14717D03*
X385008Y-9673D03*
X385023Y-7158D03*
X381755Y-9687D03*
X388048Y-8478D03*
X381770Y-7172D03*
X381740Y-12202D03*
X395535Y49379D03*
X391600Y121178D03*
X387712Y147441D03*
X384600Y221800D03*
X386563Y280370D03*
X387184Y470495D03*
X387440Y525154D03*
X395657Y546894D03*
X391657Y546816D03*
X387657Y546876D03*
X384500Y810862D03*
X384499Y819862D03*
X388361Y1293713D03*
X385701Y1291828D03*
X392176Y1309859D03*
X394951Y1311259D03*
X389691Y1306240D03*
Y1308840D03*
X387091Y1306240D03*
Y1308840D03*
X389691Y1303640D03*
X387091D03*
X383421Y1311394D03*
X388441Y1311340D03*
X384367Y1314425D03*
Y1317382D03*
X392950Y1315280D03*
X392910Y1317880D03*
X395267Y1358621D03*
X393321Y1385630D03*
X388718Y1387386D03*
X384270Y1389875D03*
X395313Y1452895D03*
X381913D03*
X383823Y1450295D03*
X388603D03*
X383823Y1455495D03*
X388603D03*
X381903Y1459995D03*
Y1465195D03*
X382458Y1550897D03*
X387182Y1550797D03*
X393322Y1573347D03*
X394915Y1590018D03*
X387805Y1607802D03*
Y1604802D03*
Y1610802D03*
X387325Y1627212D03*
X385502Y1667154D03*
X394824Y1667120D03*
X389824D03*
X403734Y110326D03*
Y118976D03*
X397426Y112815D03*
Y116215D03*
X402606Y129465D03*
Y126065D03*
X403141Y144300D03*
X396237Y315507D03*
X399657Y546915D03*
X401880Y696220D03*
X404771Y698670D03*
X396129Y1334717D03*
X408459Y1330709D03*
X405859D03*
X400659D03*
X403259D03*
X408459Y1333816D03*
X405859D03*
X403259D03*
X400659D03*
X408459Y1336773D03*
X405859D03*
X402503Y1340572D03*
X407363D03*
X404933D03*
X407412Y1358587D03*
X407363Y1346172D03*
X404933D03*
X402503D03*
X410002Y1375093D03*
X405978Y1377794D03*
X401953Y1380494D03*
X397187Y1383354D03*
X397223Y1450295D03*
X402003D03*
X397223Y1455495D03*
X402003D03*
X401583Y1504872D03*
X404699Y1523953D03*
X398201Y1548563D03*
X410672Y1561170D03*
X400905Y1596091D03*
X403417Y1606224D03*
X403848Y1615354D03*
X400623Y1629772D03*
X406075Y1641000D03*
X399824Y1667120D03*
X409000Y1667025D03*
X405000Y1683500D03*
X401666Y1677925D03*
X417535Y49379D03*
X413949Y69270D03*
X414486Y127579D03*
Y124179D03*
X423521Y1311969D03*
X421091Y1311219D03*
X419673Y1325571D03*
Y1322971D03*
Y1328171D03*
X422273Y1322971D03*
Y1325571D03*
Y1328171D03*
X416949Y1336713D03*
Y1333756D03*
X424333Y1331447D03*
X411059Y1330709D03*
X416003Y1330725D03*
X413559Y1330709D03*
X421023Y1330671D03*
X414132Y1372234D03*
X415862Y1503715D03*
X422557Y1530595D03*
X420057D03*
X421059Y1569168D03*
X416163Y1594450D03*
X422007Y1592330D03*
X413100Y1607600D03*
X418293Y1607495D03*
X423379Y1607675D03*
X413200Y1612700D03*
X423439Y1612407D03*
X411515Y1599649D03*
X413100Y1617900D03*
X418500Y1618000D03*
X423349Y1617857D03*
X416962Y1634123D03*
X415437Y1636382D03*
X417365Y1630495D03*
X420765D03*
X421347Y1636668D03*
X411500Y1653500D03*
X417441Y1643946D03*
X420000Y1668075D03*
X417000Y1683500D03*
X439535Y49379D03*
X430564Y56348D03*
X430500Y72900D03*
X436090Y128007D03*
X440090Y132007D03*
X433124Y222253D03*
Y225205D03*
X439500Y484000D03*
X439284Y1038766D03*
Y1042766D03*
X431830Y1311240D03*
X438561Y1321622D03*
X432561D03*
X435561D03*
X437624Y1452895D03*
X430924Y1462595D03*
X439534Y1450295D03*
Y1455495D03*
X437614Y1459995D03*
X432834D03*
X437614Y1465195D03*
X432834D03*
X436140Y1499320D03*
X437661Y1518040D03*
Y1514420D03*
Y1510800D03*
X438153Y1528731D03*
X430239Y1581726D03*
X426688Y1598003D03*
X439283Y1608704D03*
X432559Y1627500D03*
X439404Y1615146D03*
X428000Y1640500D03*
X450102Y87011D03*
X450414Y92384D03*
X443014D03*
X452090Y116007D03*
Y124007D03*
Y132007D03*
Y128007D03*
X445997Y170701D03*
X453783Y217646D03*
X441320Y304170D03*
Y310170D03*
X449760Y497240D03*
X448688Y1305947D03*
X449440Y1308386D03*
X450220Y1310834D03*
X451083Y1313347D03*
X441561Y1321622D03*
X444561D03*
X452089Y1316074D03*
X452936Y1318775D03*
X453823Y1321436D03*
X454603Y1324033D03*
X454909Y1326721D03*
X444314Y1450295D03*
Y1455495D03*
X451024Y1472295D03*
X452934Y1469695D03*
Y1474895D03*
X452427Y1550797D03*
X440846Y1576526D03*
X451561Y1589884D03*
Y1594876D03*
X444128Y1604200D03*
Y1600200D03*
X451561Y1621796D03*
Y1626788D03*
X448776Y1622266D03*
Y1617166D03*
Y1619766D03*
X452500Y1637559D03*
X447387Y1641441D03*
X454099Y1649575D03*
X461535Y49379D03*
X457502Y87011D03*
X464456Y93101D03*
X457056D03*
X464051Y224799D03*
X460624Y244103D03*
X465925Y489925D03*
X457724Y1462595D03*
X459634Y1459995D03*
X464414D03*
X466334Y1450295D03*
X464424Y1452895D03*
X466334Y1455495D03*
X459634Y1465195D03*
X464414D03*
X457714Y1469695D03*
Y1474895D03*
X461876Y1550897D03*
X457151Y1550797D03*
X466600Y1550697D03*
X468577Y1589884D03*
Y1594876D03*
X456517Y1589884D03*
X463621D03*
Y1594876D03*
X456517D03*
X457591Y1599884D03*
X462547D03*
Y1604876D03*
X457591D03*
X462547Y1611796D03*
X457591D03*
X469651D03*
Y1599884D03*
Y1604876D03*
X462547Y1616788D03*
X457591D03*
X469651D03*
X468577Y1621796D03*
Y1626788D03*
X463621Y1621796D03*
Y1626788D03*
X456517Y1621796D03*
Y1626788D03*
X457240Y1629500D03*
X462500Y1655500D03*
X468350Y1645351D03*
X461000Y1650000D03*
X470309Y1689000D03*
X470500Y1674075D03*
X462500Y1701000D03*
X468500Y1708500D03*
X467416Y1724808D03*
X469975D03*
X464734Y1730518D03*
X483535Y49379D03*
X478949Y60029D03*
Y55135D03*
Y64975D03*
X470895Y128020D03*
X478295D03*
X482255Y127322D03*
Y135722D03*
X479630Y141942D03*
X471371Y231764D03*
X477203Y1015474D03*
X484784D03*
X477203Y1019017D03*
X484784D03*
X477203Y1022560D03*
X484784D03*
X484524Y1462595D03*
X471114Y1450295D03*
Y1455495D03*
X477824Y1472295D03*
X484514Y1469695D03*
X479734D03*
X484514Y1474895D03*
X479734D03*
X480774Y1550697D03*
X476049Y1550897D03*
X471325D03*
X480637Y1589884D03*
Y1594876D03*
X475681D03*
Y1589884D03*
X481711Y1611796D03*
Y1599884D03*
Y1604876D03*
X474607Y1611796D03*
Y1599884D03*
Y1604876D03*
X481711Y1616788D03*
X474607D03*
X475681Y1621796D03*
X480637D03*
X475681Y1626788D03*
X480637D03*
X478500Y1655500D03*
X476000Y1680000D03*
X478500Y1701000D03*
Y1714500D03*
X487590Y105969D03*
X494810D03*
X492300Y121389D03*
X487880Y131442D03*
X496280D03*
X492300Y124389D03*
X488580Y141942D03*
X494200Y158800D03*
X488260Y418980D03*
X488405Y578572D03*
X492284Y1015474D03*
Y1019017D03*
Y1022560D03*
X491224Y1452895D03*
X497914Y1450295D03*
X493134D03*
X497914Y1455495D03*
X493134D03*
X486434Y1459995D03*
X491214D03*
X486434Y1465195D03*
X491214D03*
X485498Y1550797D03*
X490223Y1550897D03*
X494947D03*
X499672D03*
X499801Y1594876D03*
X492697Y1589884D03*
X487741Y1594876D03*
X492697D03*
X499801Y1589884D03*
X487741D03*
X498727Y1611796D03*
Y1599884D03*
Y1604876D03*
X486667Y1611796D03*
X493771D03*
Y1599884D03*
Y1604876D03*
X486667Y1599884D03*
Y1604876D03*
X498727Y1616788D03*
X499801Y1621796D03*
Y1626788D03*
X486667Y1616788D03*
X493771D03*
X492697Y1621796D03*
X487741D03*
X492697Y1626788D03*
X487741D03*
X510815Y69562D03*
X502815Y106984D03*
X512654Y94967D03*
X500836Y119092D03*
X511140Y109829D03*
X511170Y224930D03*
Y227882D03*
X501500Y433000D03*
X511324Y1462595D03*
X513234Y1459995D03*
X504624Y1472295D03*
X513234Y1465195D03*
X511314Y1469695D03*
X506534D03*
X511314Y1474895D03*
X506534D03*
X513844Y1550897D03*
X509120Y1550697D03*
X504396Y1550897D03*
X511861Y1594876D03*
X504757Y1589884D03*
Y1594876D03*
X511861Y1589884D03*
X505831Y1611796D03*
X510787D03*
X505831Y1599884D03*
Y1604876D03*
X510787Y1599884D03*
Y1604876D03*
X511861Y1621796D03*
Y1626788D03*
X505831Y1616788D03*
X510787D03*
X504757Y1621796D03*
Y1626788D03*
X518843Y23788D03*
X517907Y69507D03*
X524993D03*
X516020Y102870D03*
X519240Y94967D03*
X521420Y109829D03*
X516020Y111770D03*
X518418Y137171D03*
X522831Y443712D03*
X518024Y1452895D03*
X519934Y1450295D03*
X524714D03*
X519934Y1455495D03*
X524714D03*
X518014Y1459995D03*
Y1465195D03*
X523293Y1550797D03*
X518569Y1550897D03*
X528940Y1548260D03*
X528877Y1589884D03*
Y1594876D03*
X516817Y1589884D03*
Y1594876D03*
X523921D03*
Y1589884D03*
X529951Y1611796D03*
Y1599790D03*
Y1604876D03*
X517891Y1611796D03*
X522847D03*
Y1599884D03*
X517891D03*
X522847Y1604876D03*
X517891D03*
X529951Y1616788D03*
X528877Y1621796D03*
Y1626788D03*
X517891Y1616788D03*
X522847D03*
X523921Y1621796D03*
X516817D03*
X523921Y1626788D03*
X516817D03*
X540843Y23788D03*
X542723Y39562D03*
X532080Y69507D03*
X539166D03*
X535170Y108730D03*
Y117630D03*
X533097Y246780D03*
X532000Y426500D03*
X544844Y439701D03*
X543500Y463500D03*
X540106Y657325D03*
X531424Y1452895D03*
X533334Y1450295D03*
X538114D03*
X533334Y1455495D03*
X538114D03*
X544814Y1459995D03*
X540810Y1523953D03*
X540937Y1589884D03*
Y1594876D03*
X535981D03*
Y1589884D03*
X542011Y1611796D03*
Y1599884D03*
Y1604876D03*
X534907Y1611796D03*
Y1599790D03*
Y1604876D03*
X542011Y1616788D03*
X540937Y1621796D03*
Y1626788D03*
X534907Y1616788D03*
X535981Y1621796D03*
Y1626788D03*
X548610Y57990D03*
X546253Y69507D03*
X553340D03*
X545935Y77516D03*
X553821D03*
X546400Y120700D03*
X553780Y118740D03*
Y127140D03*
X547196Y195256D03*
X546800Y262800D03*
X548856Y440452D03*
X556993Y616406D03*
X550993D03*
X553993D03*
X547993D03*
X558986Y1462595D03*
X545931Y1451344D03*
X559090Y1452185D03*
X548119Y1530595D03*
X550619D03*
X552997Y1589884D03*
X548041Y1594876D03*
X552997D03*
X548041Y1589884D03*
X559027Y1611796D03*
Y1599884D03*
Y1604876D03*
X546967Y1611796D03*
X554071D03*
Y1599884D03*
Y1604876D03*
X546967Y1599884D03*
Y1604876D03*
X559027Y1616788D03*
X546967D03*
X554071D03*
X552997Y1621796D03*
Y1626788D03*
X548041D03*
Y1621796D03*
X562843Y23788D03*
X560426Y69507D03*
X570860Y118310D03*
X565210Y125819D03*
X570860Y127510D03*
X564603Y197778D03*
Y200304D03*
X573911Y212196D03*
X569004Y228571D03*
X563230Y426508D03*
X563575Y448425D03*
X569464Y462140D03*
X559993Y616406D03*
X561580Y1242740D03*
X565686Y1452895D03*
X567596Y1450295D03*
X572376D03*
X567596Y1455495D03*
X572376D03*
X565676Y1459995D03*
X560896D03*
X565676Y1465195D03*
X560896D03*
X562860Y1499360D03*
X565723Y1510800D03*
Y1514420D03*
Y1518040D03*
X566215Y1528731D03*
X572161Y1594876D03*
X565057Y1589884D03*
X560101Y1594876D03*
X565057D03*
X572161Y1589884D03*
X560101D03*
X571087Y1611796D03*
Y1599884D03*
Y1604876D03*
X566131Y1611796D03*
Y1599884D03*
Y1604876D03*
X571087Y1616788D03*
X572161Y1621796D03*
Y1626788D03*
X566131Y1616788D03*
X565057Y1621796D03*
X560101D03*
X565057Y1626788D03*
X560101D03*
X584843Y23788D03*
X580098Y96439D03*
X576510Y125819D03*
X588554Y221277D03*
X577859Y212196D03*
X588554Y229277D03*
X575917Y421390D03*
X583505Y457925D03*
X587812Y474353D03*
X577801Y466000D03*
X578830Y1238075D03*
X578071Y1244425D03*
X588630Y1255075D03*
X583630D03*
X585786Y1462595D03*
X587696Y1459995D03*
X579086Y1472295D03*
X587696Y1465195D03*
X580996Y1469695D03*
X585776D03*
X580996Y1474895D03*
X585776D03*
X585213Y1550797D03*
X580489D03*
X589177Y1589884D03*
Y1594876D03*
X577117Y1589884D03*
Y1594876D03*
X584221D03*
Y1589884D03*
X578191Y1611796D03*
X583147D03*
Y1599884D03*
X578191D03*
X583147Y1604876D03*
X578191D03*
X589177Y1621796D03*
Y1626788D03*
X578191Y1616788D03*
X583147D03*
X584221Y1621796D03*
X577117D03*
X584221Y1626788D03*
X577117D03*
X603379Y70512D03*
X594430Y463600D03*
X592612Y805986D03*
X594330Y1238075D03*
X595671Y1245688D03*
X595598Y1251075D03*
X599659Y1241734D03*
X603947Y1258575D03*
X595947D03*
X592476Y1459995D03*
X594396Y1450295D03*
X599176D03*
X592486Y1452895D03*
X594396Y1455495D03*
X599176D03*
X592476Y1465195D03*
X599387Y1550897D03*
X604111D03*
X589938D03*
X594662Y1550697D03*
X601237Y1589884D03*
Y1594876D03*
X596281D03*
Y1589884D03*
X602311Y1611796D03*
Y1599884D03*
Y1604876D03*
X590251Y1611796D03*
X595207D03*
Y1599884D03*
X590251D03*
X595207Y1604876D03*
X590251D03*
X602311Y1616788D03*
X601237Y1621796D03*
Y1626788D03*
X590251Y1616788D03*
X595207D03*
X596281Y1621796D03*
Y1626788D03*
X606843Y23788D03*
X615190Y70533D03*
X607834Y222611D03*
X612414Y227041D03*
X605796Y425585D03*
X612969Y447260D03*
X616171Y780364D03*
X606559Y796116D03*
X612871Y1248488D03*
X612947Y1252075D03*
X609159Y1240234D03*
X612447Y1258575D03*
X616527Y1390732D03*
X619286Y1452895D03*
X612586Y1462595D03*
X614496Y1459995D03*
X619276D03*
X605886Y1472295D03*
X614496Y1465195D03*
X619276D03*
X612576Y1469695D03*
X607796D03*
X612576Y1474895D03*
X607796D03*
X613560Y1550797D03*
X618285Y1550897D03*
X608836Y1550697D03*
X613297Y1589884D03*
X608341Y1594876D03*
X613297D03*
X608341Y1589884D03*
X619327Y1611796D03*
Y1599884D03*
Y1604876D03*
X607267Y1611796D03*
X614371D03*
Y1599884D03*
Y1604876D03*
X607267Y1599884D03*
Y1604876D03*
X619327Y1616788D03*
X607267D03*
X614371D03*
X613297Y1621796D03*
X608341D03*
X613297Y1626788D03*
X608341D03*
X628843Y23788D03*
X625574Y150177D03*
X623605Y219277D03*
Y228777D03*
X624760Y424569D03*
X621916Y465088D03*
X632996Y478309D03*
X621309Y483346D03*
X634288Y766646D03*
X625976Y1450295D03*
X621196D03*
X625976Y1455495D03*
X621196D03*
X632686Y1472295D03*
X632458Y1550897D03*
X623009D03*
X627734D03*
X632461Y1594876D03*
X625357Y1589884D03*
X620401Y1594876D03*
X625357D03*
X632461Y1589884D03*
X620401D03*
X631387Y1611796D03*
Y1599790D03*
Y1604876D03*
X626431Y1611796D03*
Y1599790D03*
Y1604876D03*
X631387Y1616788D03*
X632461Y1626788D03*
Y1621796D03*
X626431Y1616788D03*
X620401Y1621796D03*
X625357D03*
X620401Y1626788D03*
X625357D03*
X627958Y1654114D03*
X645151Y69507D03*
X642394Y131172D03*
X642481Y184862D03*
X643012Y201913D03*
Y199313D03*
X635200Y415425D03*
X644673Y425816D03*
X637504Y454352D03*
X636614Y512597D03*
X647354Y776911D03*
Y783604D03*
Y807029D03*
Y813722D03*
Y820415D03*
Y843840D03*
Y850533D03*
Y857226D03*
Y880651D03*
Y887344D03*
Y894037D03*
Y917462D03*
Y924155D03*
Y930848D03*
Y954273D03*
Y960966D03*
Y967659D03*
Y974352D03*
Y981045D03*
Y987737D03*
Y994430D03*
Y1004470D03*
Y1034588D03*
Y1041281D03*
Y1047974D03*
Y1054667D03*
Y1061360D03*
Y1071399D03*
Y1078092D03*
Y1101517D03*
Y1108210D03*
Y1114903D03*
Y1138328D03*
Y1145021D03*
Y1151714D03*
Y1175139D03*
Y1181832D03*
Y1188525D03*
Y1211950D03*
Y1218643D03*
Y1225336D03*
Y1248761D03*
Y1255454D03*
X642436Y1350877D03*
X646236D03*
X638436D03*
X643563Y1392581D03*
X647445Y1392605D03*
X646086Y1452895D03*
X639386Y1462595D03*
X647996Y1450295D03*
Y1455495D03*
X641296Y1459995D03*
X646076D03*
X641296Y1465195D03*
X646076D03*
X639376Y1469695D03*
X634596D03*
X639376Y1474895D03*
X634596D03*
X646631Y1550897D03*
X637182Y1550697D03*
X641906Y1550897D03*
X637417Y1589884D03*
Y1594876D03*
X643447Y1599884D03*
X638491D03*
X643447Y1604876D03*
X638491D03*
X643447Y1611796D03*
X638491D03*
X643447Y1616788D03*
X637417Y1626788D03*
X638491Y1616788D03*
X637417Y1621796D03*
X640520Y1635483D03*
X649266Y1650126D03*
X642151Y1649961D03*
X639284Y1683049D03*
X647500Y1682850D03*
X635210Y1721545D03*
X650843Y23788D03*
X649585Y29298D03*
X663703Y32574D03*
X653570Y58363D03*
X660775Y78330D03*
X649441Y177003D03*
X662740Y375240D03*
X649500Y382500D03*
X660885Y412588D03*
X650268Y479141D03*
X649771Y505736D03*
X659398Y516260D03*
X658946Y756766D03*
X651904D03*
Y760266D03*
X663496Y773564D03*
X658946Y763766D03*
X651904Y767266D03*
X658046Y786950D03*
X663496Y780257D03*
X651754Y795316D03*
X658046Y796989D03*
X663496Y803682D03*
Y810375D03*
Y817068D03*
X651754Y832127D03*
X658046Y833800D03*
Y823761D03*
X663496Y840493D03*
Y847186D03*
X658046Y860572D03*
X663496Y853879D03*
X651754Y868938D03*
X658046Y870611D03*
X663496Y877304D03*
Y883997D03*
Y890690D03*
X651754Y905750D03*
X658046Y897383D03*
Y907423D03*
X663496Y914115D03*
Y920808D03*
X658046Y934194D03*
X663496Y927501D03*
X651754Y942561D03*
X658046Y944234D03*
X663496Y950926D03*
Y957619D03*
Y964312D03*
Y971005D03*
Y977698D03*
Y984391D03*
Y991084D03*
Y997777D03*
Y1004470D03*
Y1031241D03*
Y1037934D03*
Y1044627D03*
Y1051320D03*
Y1058013D03*
Y1068052D03*
Y1074745D03*
X651754Y1089805D03*
X658046Y1081438D03*
Y1091478D03*
X663496Y1098171D03*
Y1104863D03*
X658046Y1118249D03*
X663496Y1111556D03*
X651754Y1126616D03*
X658046Y1128289D03*
X663496Y1134982D03*
Y1141675D03*
Y1148367D03*
X651754Y1163427D03*
X658046Y1155060D03*
Y1165100D03*
X663496Y1171793D03*
Y1178486D03*
X658046Y1191871D03*
X663496Y1185178D03*
X651754Y1200238D03*
X658046Y1201911D03*
X663496Y1208604D03*
Y1215297D03*
Y1221989D03*
X651754Y1237049D03*
X658046Y1238722D03*
Y1228682D03*
X663496Y1245415D03*
Y1252108D03*
X657836Y1350877D03*
X653836D03*
X650036D03*
X661713Y1373981D03*
X655702Y1391107D03*
X659559Y1391027D03*
X655873Y1428844D03*
X652189Y1421276D03*
X659486Y1452895D03*
X661396Y1450295D03*
X652776D03*
X661396Y1455495D03*
X652776D03*
X662374Y1548563D03*
X651355Y1550797D03*
X651840Y1567752D03*
X660542Y1638169D03*
X657392Y1628137D03*
X652274Y1630366D03*
X650895Y1648115D03*
X655914Y1668744D03*
X659436Y1694697D03*
X649526Y1709274D03*
X663997Y1703111D03*
X659673Y1722174D03*
X661845Y1717340D03*
X654508Y1728000D03*
X654527Y1718229D03*
X659673Y1732836D03*
X672843Y23788D03*
X668739Y45262D03*
X677594Y36205D03*
X675887Y45262D03*
X666411Y69507D03*
X678664Y88080D03*
X673751Y78092D03*
X673691Y200672D03*
X673301Y211332D03*
X671753Y397936D03*
X670000Y457844D03*
X669955Y495468D03*
X671500Y529500D03*
X677055Y776911D03*
X667896Y791970D03*
X677055Y783604D03*
Y807029D03*
Y813722D03*
Y820415D03*
X667896Y828781D03*
X677055Y843840D03*
Y850533D03*
X667896Y865592D03*
X677055Y857226D03*
Y880651D03*
Y887344D03*
Y894037D03*
X667896Y902403D03*
X677055Y917462D03*
Y924155D03*
X667896Y939214D03*
X677055Y930848D03*
Y954273D03*
Y960966D03*
Y967659D03*
Y974352D03*
Y981045D03*
Y987737D03*
Y994430D03*
Y1004470D03*
Y1034588D03*
Y1041281D03*
Y1047974D03*
Y1054667D03*
Y1061360D03*
Y1071399D03*
X667896Y1086458D03*
X677055Y1078092D03*
Y1101517D03*
Y1108210D03*
Y1114903D03*
X667896Y1123269D03*
X677055Y1138328D03*
Y1145021D03*
X667896Y1160080D03*
X677055Y1151714D03*
Y1175139D03*
Y1181832D03*
Y1188525D03*
X667896Y1196891D03*
X677055Y1211950D03*
Y1218643D03*
X667896Y1233702D03*
X677055Y1225336D03*
Y1248761D03*
Y1255454D03*
X674552Y1351988D03*
Y1349488D03*
X666176Y1450295D03*
Y1455495D03*
X666050Y1501670D03*
X672684Y1522690D03*
X674687Y1519726D03*
X665800Y1530575D03*
X674620Y1535271D03*
Y1542125D03*
X672617Y1545089D03*
Y1538235D03*
X674894Y1629042D03*
X673982Y1639289D03*
X665802Y1652337D03*
X674486Y1647842D03*
X673480Y1662668D03*
X671631Y1690786D03*
X693672Y32684D03*
X686855Y43701D03*
X679719Y59066D03*
X682946Y69982D03*
X682891Y72642D03*
X688552Y79166D03*
X681895Y82212D03*
X685783Y78768D03*
X684954Y104968D03*
X691058Y131408D03*
X684521Y152482D03*
X688521D03*
X692521D03*
X682264Y224116D03*
X691547Y386834D03*
X688249Y405628D03*
X679862Y409320D03*
X679500Y526834D03*
X691496Y575081D03*
X688078Y675493D03*
X681605Y756766D03*
X681671Y760178D03*
X688647Y756766D03*
X693197Y773564D03*
X688647Y763766D03*
X681605Y767266D03*
X687747Y786950D03*
X693197Y780257D03*
X681455Y795316D03*
X687747Y796989D03*
X693197Y803682D03*
Y810375D03*
Y817068D03*
X681455Y832127D03*
X687747Y833800D03*
Y823761D03*
X693197Y840493D03*
Y847186D03*
X687747Y860572D03*
X693197Y853879D03*
X681455Y868938D03*
X687747Y870611D03*
X693197Y877304D03*
Y883997D03*
Y890690D03*
X681455Y905750D03*
X687747Y897383D03*
Y907423D03*
X693197Y914115D03*
Y920808D03*
X687747Y934194D03*
X693197Y927501D03*
X681455Y942561D03*
X687747Y944234D03*
X693197Y950926D03*
Y957619D03*
Y964312D03*
Y971005D03*
Y977698D03*
Y984391D03*
Y991084D03*
Y997777D03*
Y1004470D03*
Y1031241D03*
Y1037934D03*
Y1044627D03*
Y1051320D03*
Y1058013D03*
Y1068052D03*
Y1074745D03*
X681455Y1089805D03*
X687747Y1081438D03*
Y1091478D03*
X693197Y1098171D03*
Y1104863D03*
X687747Y1118249D03*
X693197Y1111556D03*
X681455Y1126616D03*
X687747Y1128289D03*
X693197Y1134982D03*
Y1141675D03*
Y1148367D03*
X681455Y1163427D03*
X687747Y1155060D03*
Y1165100D03*
X693197Y1171793D03*
Y1178486D03*
X687747Y1191871D03*
X693197Y1185178D03*
X681455Y1200238D03*
X687747Y1201911D03*
X693197Y1208604D03*
Y1215297D03*
Y1221989D03*
X681455Y1237049D03*
X687747Y1238722D03*
Y1228682D03*
X693197Y1245415D03*
Y1252108D03*
X688076Y1297506D03*
Y1305206D03*
Y1300006D03*
Y1302606D03*
X683052Y1352048D03*
Y1349548D03*
X685187Y1368700D03*
Y1363500D03*
Y1366100D03*
X687577Y1425054D03*
X688120Y1519601D03*
X683352Y1530526D03*
Y1526526D03*
X682016Y1539067D03*
X688308Y1631636D03*
X693150Y1640773D03*
X682925Y1657116D03*
X686825Y1647430D03*
X685485Y1682259D03*
X694843Y23788D03*
X701839Y45112D03*
X707608Y69718D03*
X705570Y133760D03*
X704144Y122602D03*
X707243Y123946D03*
X701927Y166535D03*
Y172441D03*
Y178346D03*
Y184252D03*
Y196063D03*
Y190157D03*
Y201968D03*
Y207874D03*
Y213779D03*
Y219685D03*
X696105Y364149D03*
X696500Y529862D03*
X700500Y545862D03*
X704500Y555862D03*
X701496Y580556D03*
X697392Y601686D03*
X697642Y733401D03*
X706756Y776911D03*
X697597Y791970D03*
X706756Y783604D03*
Y807029D03*
Y813722D03*
Y820415D03*
X697597Y828781D03*
X706756Y843840D03*
Y850533D03*
X697597Y865592D03*
X706756Y857226D03*
Y880651D03*
Y887344D03*
Y894037D03*
X697597Y902403D03*
X706756Y924155D03*
Y917462D03*
X697597Y939214D03*
X706756Y930848D03*
Y954273D03*
Y960966D03*
Y967659D03*
Y974352D03*
Y981045D03*
Y987737D03*
Y994430D03*
Y1004470D03*
Y1041281D03*
Y1034588D03*
Y1047974D03*
Y1054667D03*
Y1071399D03*
Y1061360D03*
Y1078092D03*
X697597Y1086458D03*
X706756Y1101517D03*
Y1114903D03*
Y1108210D03*
X697597Y1123269D03*
X706756Y1145021D03*
Y1138328D03*
Y1151714D03*
X697597Y1160080D03*
X706756Y1175139D03*
Y1181832D03*
Y1188525D03*
X697597Y1196891D03*
X706756Y1211950D03*
Y1218643D03*
Y1225336D03*
X697597Y1233702D03*
X706756Y1248761D03*
Y1255454D03*
X697483Y1297506D03*
Y1305206D03*
Y1300006D03*
Y1302606D03*
X701771Y1351988D03*
Y1349488D03*
X699467Y1368710D03*
Y1363510D03*
Y1366110D03*
X703568Y1379476D03*
X699610Y1580523D03*
X706681Y1627361D03*
X705833Y1633568D03*
X706089Y1643411D03*
X705815Y1654918D03*
X703473Y1663001D03*
X695400Y1685887D03*
X705366Y1684064D03*
X723479Y-28508D03*
X716843Y23788D03*
X717342Y57098D03*
X720328Y344824D03*
X711500Y360862D03*
X719500D03*
X711556Y575081D03*
X714583Y587642D03*
X715037Y603278D03*
X713280Y636897D03*
X712319Y654954D03*
X711306Y756766D03*
Y760178D03*
X718348Y756766D03*
X722898Y773564D03*
X718348Y763766D03*
X711306Y767266D03*
X722898Y780257D03*
X717448Y786950D03*
X722898Y803682D03*
X711156Y795316D03*
X717448Y796989D03*
X722898Y810375D03*
Y817068D03*
X717448Y823761D03*
Y833800D03*
X711156Y832127D03*
X722898Y847186D03*
Y840493D03*
Y853879D03*
X717448Y860572D03*
X722898Y877304D03*
X717448Y870611D03*
X711156Y868938D03*
X722898Y883997D03*
Y890690D03*
X717448Y897383D03*
Y907423D03*
X711156Y905750D03*
X722898Y920808D03*
Y914115D03*
Y927501D03*
X717448Y934194D03*
X722898Y950926D03*
X717448Y944234D03*
X711156Y942561D03*
X722898Y957619D03*
Y971005D03*
Y964312D03*
Y984391D03*
Y977698D03*
Y991084D03*
Y997777D03*
Y1004470D03*
Y1031241D03*
Y1037934D03*
Y1044627D03*
Y1051320D03*
Y1058013D03*
Y1068052D03*
Y1074745D03*
X717448Y1081438D03*
X711156Y1089805D03*
X717448Y1091478D03*
X722898Y1098171D03*
Y1104863D03*
Y1111556D03*
X717448Y1118249D03*
Y1128289D03*
X711156Y1126616D03*
X722898Y1134982D03*
Y1148367D03*
Y1141675D03*
X717448Y1165100D03*
X711156Y1163427D03*
X717448Y1155060D03*
X722898Y1178486D03*
Y1171793D03*
Y1185178D03*
X717448Y1191871D03*
X722898Y1208604D03*
X711156Y1200238D03*
X717448Y1201911D03*
X722898Y1215297D03*
Y1221989D03*
X717448Y1228682D03*
Y1238722D03*
X711156Y1237049D03*
X722898Y1252108D03*
Y1245415D03*
X721361Y1297546D03*
X711954D03*
X721361Y1305246D03*
Y1302646D03*
Y1300046D03*
X711954Y1305246D03*
Y1302646D03*
Y1300046D03*
X710221Y1351988D03*
Y1349488D03*
X716707Y1385281D03*
X719137D03*
X720233Y1378525D03*
Y1381482D03*
Y1375418D03*
X722833D03*
X714277Y1385281D03*
X715033Y1378525D03*
X717633D03*
X712433D03*
X717633Y1381482D03*
X715033Y1375418D03*
X717633D03*
X712433D03*
X719186Y1403296D03*
X719137Y1390881D03*
X714277D03*
X716707D03*
X709551Y1406578D03*
X716770Y1531459D03*
X715122Y1533378D03*
X716989Y1537249D03*
X713357Y1535212D03*
X715224Y1539083D03*
X713459Y1540917D03*
X722876Y1611343D03*
X717749Y1654921D03*
X709771Y1654927D03*
X712354Y1682279D03*
X738843Y23788D03*
X728981Y39872D03*
X736791Y39832D03*
X730131Y60757D03*
X736524Y58069D03*
X730958Y71014D03*
X738044Y71526D03*
X727944Y88972D03*
X727986Y101979D03*
X729900Y98090D03*
X727986Y105477D03*
X737624Y98858D03*
X734524Y98758D03*
X735734Y111988D03*
X726720Y574910D03*
X724001Y636790D03*
X726952Y648667D03*
X736457Y776911D03*
Y783604D03*
X727298Y791970D03*
X736457Y807029D03*
Y813722D03*
Y820415D03*
X727298Y828781D03*
X736457Y843840D03*
Y850533D03*
X727298Y865592D03*
X736457Y857226D03*
Y880651D03*
Y887344D03*
Y894037D03*
X727298Y902403D03*
X736457Y924155D03*
Y917462D03*
X727298Y939214D03*
X736457Y930848D03*
Y954273D03*
Y960966D03*
Y967659D03*
Y974352D03*
Y981045D03*
Y987737D03*
Y994430D03*
Y1004470D03*
Y1034588D03*
Y1041281D03*
Y1047974D03*
Y1054667D03*
Y1071399D03*
Y1061360D03*
X727298Y1086458D03*
X736457Y1078092D03*
Y1101517D03*
Y1114903D03*
Y1108210D03*
X727298Y1123269D03*
X736457Y1145021D03*
Y1138328D03*
X727298Y1160080D03*
X736457Y1151714D03*
Y1175139D03*
Y1181832D03*
Y1188525D03*
X727298Y1196891D03*
X736457Y1211950D03*
Y1218643D03*
X727298Y1233702D03*
X736457Y1225336D03*
Y1248761D03*
Y1255454D03*
X735954Y1297546D03*
Y1305246D03*
Y1302646D03*
Y1300046D03*
X727098Y1351977D03*
X730900Y1352131D03*
X727098Y1349077D03*
X730900Y1349231D03*
X734047Y1372880D03*
X731447D03*
X734047Y1370280D03*
Y1367680D03*
X731447D03*
Y1370280D03*
X728348Y1380832D03*
Y1377875D03*
X736280Y1379580D03*
X732797Y1375380D03*
X725333Y1375418D03*
X727777Y1375434D03*
X738230Y1402898D03*
X734925Y1657826D03*
X730302Y1658050D03*
X726302Y1658022D03*
X738370Y1677909D03*
X736001Y1695509D03*
X728454Y1690491D03*
X732434Y1690660D03*
X738550Y1693215D03*
X742841Y39832D03*
X744477Y58373D03*
X744988Y49062D03*
X747488D03*
X752261Y59782D03*
X745131Y69507D03*
X750090Y72820D03*
X745712Y212760D03*
X746705Y315647D03*
X742278Y566667D03*
X753500Y675800D03*
X748049Y756766D03*
X741007D03*
Y760266D03*
X752599Y773564D03*
X741007Y767266D03*
X748049Y763766D03*
X752599Y780257D03*
X747149Y786950D03*
X752599Y803682D03*
X747149Y796989D03*
X740857Y795316D03*
X752599Y810375D03*
Y817068D03*
X747149Y823761D03*
Y833800D03*
X740857Y832127D03*
X752599Y840493D03*
Y847186D03*
Y853879D03*
X747149Y860572D03*
X752599Y877304D03*
X747149Y870611D03*
X740857Y868938D03*
X752599Y890690D03*
Y883997D03*
X747149Y897383D03*
Y907423D03*
X740857Y905750D03*
X752599Y920808D03*
Y914115D03*
X747149Y934194D03*
X752599Y927501D03*
Y950926D03*
X747149Y944234D03*
X740857Y942561D03*
X752599Y957619D03*
Y971005D03*
Y964312D03*
Y984391D03*
Y977698D03*
Y991084D03*
Y997777D03*
Y1004470D03*
Y1031241D03*
Y1037934D03*
Y1044627D03*
Y1051320D03*
Y1058013D03*
Y1068052D03*
Y1074745D03*
X747149Y1081438D03*
X740857Y1089805D03*
X752599Y1098171D03*
Y1104863D03*
X747149Y1091478D03*
X752599Y1111556D03*
X747149Y1118249D03*
Y1128289D03*
X740857Y1126616D03*
X752599Y1134982D03*
Y1148367D03*
Y1141675D03*
X740857Y1163427D03*
X747149Y1165100D03*
Y1155060D03*
X752599Y1178486D03*
Y1171793D03*
Y1185178D03*
X747149Y1191871D03*
X752599Y1208604D03*
X740857Y1200238D03*
X747149Y1201911D03*
X752599Y1215297D03*
Y1221989D03*
X747149Y1228682D03*
Y1238722D03*
X740857Y1237049D03*
X752599Y1252108D03*
Y1245415D03*
X745475Y1297246D03*
Y1304946D03*
Y1302346D03*
Y1299746D03*
X739500Y1352031D03*
Y1349131D03*
X753015Y1381582D03*
Y1378625D03*
Y1375518D03*
X747059Y1385381D03*
X745215Y1378625D03*
X747815D03*
Y1375518D03*
X745215D03*
X750415Y1381582D03*
Y1378625D03*
Y1375518D03*
X749489Y1385381D03*
X751919D03*
X751968Y1403396D03*
X751919Y1390981D03*
X747059D03*
X749489D03*
X739888Y1404849D03*
X743740Y1657327D03*
X743039Y1643326D03*
X760843Y23788D03*
X754621Y74562D03*
X754634Y105288D03*
Y108288D03*
X762173Y123898D03*
X770073Y143438D03*
X756083Y220240D03*
X757464Y284087D03*
X754556Y283976D03*
X755335Y295589D03*
X758959Y319596D03*
X753959Y343790D03*
X766158Y776911D03*
Y783604D03*
X756999Y791970D03*
X766158Y807029D03*
Y813722D03*
Y820415D03*
X756999Y828781D03*
X766158Y843840D03*
Y850533D03*
Y857226D03*
X756999Y865592D03*
X766158Y880651D03*
Y887344D03*
Y894037D03*
X756999Y902403D03*
X766158Y924155D03*
Y917462D03*
X756999Y939214D03*
X766158Y930848D03*
Y954273D03*
Y960966D03*
Y967659D03*
Y974352D03*
Y981045D03*
Y987737D03*
Y994430D03*
Y1004470D03*
Y1041281D03*
Y1034588D03*
Y1047974D03*
Y1054667D03*
Y1071399D03*
Y1061360D03*
X756999Y1086458D03*
X766158Y1078092D03*
Y1101517D03*
Y1114903D03*
Y1108210D03*
X756999Y1123269D03*
X766158Y1145021D03*
Y1138328D03*
X756999Y1160080D03*
X766158Y1151714D03*
Y1175139D03*
Y1181832D03*
Y1188525D03*
X756999Y1196891D03*
X766158Y1211950D03*
Y1218643D03*
Y1225336D03*
X756999Y1233702D03*
X766158Y1248761D03*
Y1255454D03*
X759854Y1297246D03*
Y1304946D03*
Y1302346D03*
Y1299746D03*
X761800Y1352031D03*
Y1349131D03*
X764229Y1372880D03*
X766829D03*
Y1370380D03*
Y1367780D03*
X764229D03*
Y1370380D03*
X761130Y1380932D03*
Y1377975D03*
X755615Y1375518D03*
X758115D03*
X760559Y1375534D03*
X765579Y1375480D03*
X767381Y1676594D03*
X769475Y75360D03*
X771356Y167518D03*
X773221Y296262D03*
X780618Y296345D03*
X779121Y306155D03*
X773944Y312588D03*
X780808Y419865D03*
X777900Y756766D03*
X770708D03*
Y760266D03*
X782300Y773564D03*
X770708Y767266D03*
X777900Y763766D03*
X776850Y786950D03*
X782300Y780257D03*
X776850Y796989D03*
X770558Y795316D03*
X782300Y803682D03*
Y810375D03*
Y817068D03*
X770558Y832127D03*
X776850Y823761D03*
Y833800D03*
X782300Y847186D03*
Y840493D03*
X776850Y860572D03*
X782300Y853879D03*
Y877304D03*
X776850Y870611D03*
X770558Y868938D03*
X782300Y890690D03*
Y883997D03*
X776850Y897383D03*
Y907423D03*
X770558Y905750D03*
X782300Y920808D03*
Y914115D03*
X776850Y934194D03*
X782300Y927501D03*
X776850Y944234D03*
X770558Y942561D03*
X782300Y950926D03*
Y957619D03*
Y971005D03*
Y964312D03*
Y984391D03*
Y977698D03*
Y991084D03*
Y997777D03*
Y1004470D03*
Y1031241D03*
Y1037934D03*
Y1044627D03*
Y1051320D03*
Y1058013D03*
Y1068052D03*
Y1074745D03*
X776850Y1081438D03*
X770558Y1089805D03*
X782300Y1098171D03*
Y1104863D03*
X776850Y1091478D03*
Y1118249D03*
X782300Y1111556D03*
X776850Y1128289D03*
X770558Y1126616D03*
X782300Y1134982D03*
Y1148367D03*
Y1141675D03*
X776850Y1165100D03*
X770558Y1163427D03*
X776850Y1155060D03*
X782300Y1178486D03*
Y1171793D03*
Y1185178D03*
X776850Y1191871D03*
X782300Y1208604D03*
X770558Y1200238D03*
X776850Y1201911D03*
X782300Y1215297D03*
Y1221989D03*
X776850Y1228682D03*
Y1238722D03*
X770558Y1237049D03*
X782300Y1252108D03*
Y1245415D03*
X769521Y1297199D03*
Y1304899D03*
Y1299699D03*
Y1302299D03*
X770990Y1349091D03*
Y1351991D03*
X773069Y1375500D03*
X770469D03*
X776010Y1380750D03*
X787456Y49379D03*
X797594Y282233D03*
X797444Y271469D03*
X795668Y298801D03*
X792488Y377452D03*
X797252Y459344D03*
Y471344D03*
X794425Y541425D03*
X794059Y553559D03*
X791500Y560000D03*
X785000Y563500D03*
X795858Y776911D03*
Y783604D03*
X786700Y791970D03*
X795858Y807029D03*
Y820415D03*
Y813722D03*
X786700Y828781D03*
X795858Y843840D03*
Y850533D03*
X786700Y865592D03*
X795858Y857226D03*
Y880651D03*
Y894037D03*
Y887344D03*
X786700Y902403D03*
X795858Y924155D03*
Y917462D03*
X786700Y939214D03*
X795858Y930848D03*
Y954273D03*
Y960966D03*
Y967659D03*
Y981045D03*
Y974352D03*
Y994430D03*
Y987737D03*
Y1004470D03*
Y1041281D03*
Y1034588D03*
Y1054667D03*
Y1047974D03*
Y1071399D03*
Y1061360D03*
X786700Y1086458D03*
X795858Y1078092D03*
Y1101517D03*
Y1114903D03*
Y1108210D03*
X786700Y1123269D03*
X795858Y1145021D03*
Y1138328D03*
X786700Y1160080D03*
X795858Y1151714D03*
Y1175139D03*
Y1181832D03*
Y1188525D03*
X786700Y1196891D03*
X795858Y1218643D03*
Y1211950D03*
X786700Y1233702D03*
X795858Y1225336D03*
Y1248761D03*
Y1255454D03*
X809456Y49379D03*
X806984Y265653D03*
X798621Y312773D03*
X803264Y330102D03*
X808401Y341670D03*
X811569Y387674D03*
X813175Y422687D03*
X810360Y442079D03*
X802752Y455344D03*
X812500Y504000D03*
X807450Y756766D03*
X800408D03*
Y760266D03*
X812000Y773564D03*
X800408Y767266D03*
X812000Y780257D03*
X806550Y786950D03*
X812000Y803682D03*
X806550Y796989D03*
X800258Y795316D03*
X812000Y817068D03*
Y810375D03*
X800258Y832127D03*
X806550Y833800D03*
Y823761D03*
X812000Y847186D03*
Y840493D03*
X806550Y860572D03*
X812000Y853879D03*
Y877304D03*
X806550Y870611D03*
X800258Y868938D03*
X812000Y890690D03*
Y883997D03*
X806550Y897383D03*
Y907423D03*
X800258Y905750D03*
X812000Y920808D03*
Y914115D03*
Y927501D03*
X806550Y934194D03*
X812000Y950926D03*
X800258Y942561D03*
X806550Y944234D03*
X812000Y957619D03*
Y971005D03*
Y964312D03*
Y984391D03*
Y977698D03*
Y997777D03*
Y991084D03*
Y1004470D03*
Y1044627D03*
Y1037934D03*
Y1031241D03*
Y1058013D03*
Y1051320D03*
Y1068052D03*
Y1074745D03*
X806550Y1081438D03*
X800258Y1089805D03*
X812000Y1098171D03*
Y1104863D03*
X806550Y1091478D03*
X812000Y1111556D03*
X806550Y1118249D03*
Y1128289D03*
X800258Y1126616D03*
X812000Y1134982D03*
Y1148367D03*
Y1141675D03*
X806550Y1165100D03*
X800258Y1163427D03*
X806550Y1155060D03*
X812000Y1178486D03*
Y1171793D03*
Y1185178D03*
X806550Y1191871D03*
X812000Y1208604D03*
X806550Y1201911D03*
X800258Y1200238D03*
X812000Y1221989D03*
Y1215297D03*
X806550Y1228682D03*
Y1238722D03*
X800258Y1237049D03*
X812000Y1245415D03*
Y1252108D03*
X822699Y56712D03*
X821119Y134632D03*
X825699Y139062D03*
X816322Y284369D03*
X826665Y423425D03*
X817426Y487232D03*
X824500Y514500D03*
X817441Y517941D03*
X822559Y530876D03*
X826552Y543612D03*
X823777Y560988D03*
X816400Y828781D03*
Y865592D03*
Y902403D03*
Y939214D03*
Y1086458D03*
Y1123269D03*
Y1160080D03*
Y1196891D03*
Y1233702D03*
X826112Y1269546D03*
X833407Y-26181D03*
X836660Y-26167D03*
Y-16167D03*
X833407Y-16181D03*
X839700Y-14972D03*
X833422Y-13666D03*
X836675Y-13652D03*
X833412Y-19948D03*
X836674D03*
X836675Y-23652D03*
X833422Y-23666D03*
X839700Y-24972D03*
X833412Y52D03*
X836674D03*
X833412Y-9948D03*
X836674D03*
X836675Y-3652D03*
X833422Y-3666D03*
X839700Y-4972D03*
X833407Y-6181D03*
X836660Y-6167D03*
X836675Y16348D03*
X833422Y16334D03*
X839700Y15028D03*
X833407Y13819D03*
X836660Y13833D03*
X836674Y10052D03*
X833412D03*
X836675Y6348D03*
X833422Y6334D03*
X839700Y5028D03*
X833407Y3819D03*
X836660Y3833D03*
X836659Y24250D03*
X836674Y26765D03*
X833406Y24236D03*
X839699Y25445D03*
X833421Y26751D03*
X833376Y19206D03*
X833391Y21721D03*
X831456Y49379D03*
X836127Y62681D03*
X837792Y85186D03*
X831298Y104206D03*
X834616Y94324D03*
X842865Y110296D03*
X830340Y228143D03*
X832525Y268579D03*
X829572Y296511D03*
X840288Y287593D03*
X829167Y288063D03*
X832686Y331028D03*
X836840Y382003D03*
X841862Y390441D03*
X834430Y434634D03*
X834251Y459578D03*
X835425Y477890D03*
X830743Y500740D03*
X831756Y901318D03*
X835554Y1281324D03*
X835682Y1285472D03*
X836670Y1291355D03*
X836587Y1295333D03*
X842500Y1310000D03*
Y1306000D03*
Y1302000D03*
X834017Y1333584D03*
X834071Y1342457D03*
X839188Y1348937D03*
X841203Y1361376D03*
X853456Y49379D03*
X854108Y91232D03*
X851895Y160141D03*
X853800Y265057D03*
X847939Y265092D03*
X854334Y276117D03*
X854225Y280027D03*
Y283527D03*
X857334Y276117D03*
X852780Y291559D03*
X852801Y288562D03*
X853201Y297462D03*
X856701Y304862D03*
X846275Y335575D03*
X849750Y401280D03*
X852240Y470946D03*
X849126Y530138D03*
X845126D03*
X848660Y651127D03*
X846725Y1269785D03*
X861351Y61672D03*
X858528Y262382D03*
X860834Y276817D03*
X863934Y276917D03*
X862044Y290047D03*
X862075Y398537D03*
X872020Y413300D03*
X867590Y642420D03*
X864700Y836100D03*
X859446Y1284288D03*
X875345Y51595D03*
X877462Y139540D03*
X878221Y192055D03*
X880944Y283347D03*
Y286347D03*
X875447Y301500D03*
X884740Y316000D03*
X874500Y328000D03*
X873884Y453383D03*
X886707Y1254742D03*
Y1251742D03*
X881807Y1248920D03*
Y1245920D03*
X881937Y1251857D03*
X877480Y1248844D03*
X886707Y1257742D03*
X885000Y1307500D03*
X877000Y1340241D03*
X884462Y1446974D03*
X876044Y1444317D03*
X898720Y145206D03*
X888560Y469527D03*
X902376Y594657D03*
X903556Y614062D03*
X899678Y601043D03*
X897824Y909093D03*
X891648Y1137843D03*
X900723Y1146553D03*
X896107Y1254742D03*
Y1251742D03*
X896907Y1245920D03*
Y1248920D03*
X896107Y1257742D03*
X917386Y179500D03*
Y177000D03*
Y169500D03*
Y172000D03*
Y174500D03*
Y167000D03*
X909298Y195925D03*
X909161Y203012D03*
X909320Y210098D03*
Y217185D03*
Y224271D03*
Y231358D03*
X914575Y560027D03*
X906597Y579695D03*
X907035Y590172D03*
X906597Y628426D03*
X906734Y619373D03*
X906570Y663930D03*
X906387Y818471D03*
X903941Y874000D03*
X917622Y887545D03*
X909000Y909000D03*
X905000D03*
X904719Y921792D03*
X911500Y931000D03*
X908500Y927500D03*
X909890Y950217D03*
X910066Y960332D03*
X909203Y970709D03*
X916763Y972343D03*
X908799Y985291D03*
X910707Y1254742D03*
Y1251742D03*
X905007Y1248920D03*
Y1245920D03*
X905074Y1252177D03*
X910707Y1257742D03*
X920720Y145206D03*
X919886Y167000D03*
Y169500D03*
Y172000D03*
Y174500D03*
Y177000D03*
Y179500D03*
X927134Y189386D03*
X925321Y203399D03*
X926983Y604751D03*
X927127Y619251D03*
X930926Y664791D03*
X923916Y843990D03*
X918500Y856925D03*
X930925Y860925D03*
X929603Y889000D03*
X931948Y891397D03*
X919916Y908916D03*
X920276Y900554D03*
X931877Y918168D03*
X928535Y913454D03*
X920409Y918274D03*
X918000Y928000D03*
X926062Y938727D03*
X926004Y952716D03*
X925200Y1110443D03*
Y1107843D03*
Y1117443D03*
Y1114843D03*
Y1124443D03*
Y1121843D03*
Y1131443D03*
Y1128843D03*
X920107Y1251742D03*
Y1254742D03*
Y1248920D03*
Y1245920D03*
Y1257742D03*
X924000Y1310000D03*
X920738Y1321363D03*
X927869Y1317417D03*
X923680Y1339520D03*
X919758Y1348990D03*
X931798Y1660762D03*
X923798D03*
X945006Y593609D03*
X935649Y590751D03*
X939391Y600571D03*
X946366Y668811D03*
X940391Y859947D03*
X944057Y882886D03*
X940514Y918134D03*
X933021Y933979D03*
X939670Y945169D03*
X942924Y982547D03*
X943135Y977129D03*
X938507Y1137843D03*
X945691Y1254742D03*
Y1251742D03*
X940791Y1248920D03*
Y1245920D03*
X940921Y1251857D03*
X936464Y1248844D03*
X945691Y1257742D03*
X938000Y1309500D03*
Y1301500D03*
Y1304500D03*
X933586Y1325501D03*
X933041Y1315920D03*
X944406Y1532791D03*
X939798Y1660762D03*
X955529Y614017D03*
X951839Y812730D03*
X958051Y859384D03*
X952425Y876575D03*
X948060Y891468D03*
X951367Y913648D03*
X951500Y930925D03*
X955091Y1254742D03*
Y1251742D03*
X955891Y1245920D03*
Y1248920D03*
X955000Y1267000D03*
X955091Y1257742D03*
X955000Y1271000D03*
Y1275000D03*
Y1279000D03*
X960518Y1656185D03*
X957758D03*
X957848Y1659375D03*
X960608D03*
X960558Y1662015D03*
X957798D03*
X947798Y1660762D03*
X964720Y145206D03*
X975689Y156950D03*
Y153950D03*
X971192Y219589D03*
X968692D03*
X973616Y317648D03*
X963134Y882936D03*
X968919Y1116177D03*
Y1118777D03*
Y1109177D03*
Y1111777D03*
X968800Y1130046D03*
Y1132646D03*
X968919Y1123177D03*
Y1125777D03*
X969691Y1254742D03*
Y1251742D03*
X963991Y1248920D03*
Y1245920D03*
X964058Y1252177D03*
X969691Y1257742D03*
X975000Y1307500D03*
X967500Y1340241D03*
X963120Y1520080D03*
Y1523080D03*
Y1526080D03*
X976858Y1656185D03*
X976898Y1662015D03*
X976948Y1659375D03*
X986720Y145206D03*
X988593Y189347D03*
X981445Y185389D03*
X982455Y264781D03*
Y275443D03*
X989227Y389311D03*
X992037Y485369D03*
X979091Y1251742D03*
Y1254742D03*
Y1248920D03*
Y1245920D03*
Y1257742D03*
X986486Y1523080D03*
Y1520080D03*
Y1526080D03*
X985318Y1656105D03*
X988078D03*
X979618Y1656185D03*
X985358Y1661935D03*
X988118D03*
X985408Y1659295D03*
X988168D03*
X979658Y1662015D03*
X979708Y1659375D03*
X995189Y263340D03*
Y274002D03*
X992915Y280389D03*
X1007083Y363461D03*
X996232Y424440D03*
X999304Y1282574D03*
Y1289215D03*
X999303Y1285693D03*
X1004418Y1656105D03*
X1007178D03*
X1004508Y1659295D03*
X1004458Y1661935D03*
X1008720Y145206D03*
X1020661Y146580D03*
X1023221Y191574D03*
X1019803Y218099D03*
X1017870Y294386D03*
X1009618Y396125D03*
X1021425Y404925D03*
X1013365Y433426D03*
X1008789Y488642D03*
Y493655D03*
X1012211Y547574D03*
X1015061D03*
X1015961Y554432D03*
X1007703Y759012D03*
X1007587Y800384D03*
Y802884D03*
Y811352D03*
Y813852D03*
Y822252D03*
Y824752D03*
Y833356D03*
Y835856D03*
Y844256D03*
X1021908Y1289124D03*
X1019314Y1289159D03*
X1017069Y1290346D03*
X1013500Y1312500D03*
X1013000Y1306500D03*
X1013500Y1325500D03*
X1011500Y1335000D03*
X1013500Y1344500D03*
X1009852Y1523080D03*
Y1520080D03*
Y1526080D03*
X1007268Y1659295D03*
X1007218Y1661935D03*
X1023187Y146580D03*
X1027724Y397726D03*
X1030525Y391362D03*
X1027760Y451832D03*
X1022461Y558932D03*
X1027579D03*
X1032579Y559934D03*
X1025493Y768719D03*
X1035645Y773582D03*
X1033218Y1523080D03*
Y1520080D03*
Y1526080D03*
X1033798Y1656675D03*
X1033748Y1659315D03*
X1040199Y49379D03*
X1040891Y406586D03*
X1045100Y427059D03*
X1045015Y444404D03*
X1041254Y523874D03*
X1043180Y547027D03*
X1040890Y735717D03*
X1050015Y756765D03*
Y760265D03*
X1045465Y776910D03*
X1050015Y767265D03*
X1045465Y783603D03*
X1041065Y795315D03*
X1045465Y807028D03*
Y813721D03*
Y820414D03*
X1041065Y832126D03*
X1045465Y850532D03*
Y843839D03*
Y857225D03*
X1041065Y868937D03*
X1045465Y880650D03*
Y887343D03*
Y894036D03*
X1041065Y905749D03*
X1045465Y917461D03*
Y924154D03*
Y930847D03*
X1041065Y942560D03*
X1045465Y954272D03*
Y967658D03*
Y960965D03*
Y974351D03*
Y981044D03*
Y987736D03*
Y994429D03*
Y1004469D03*
Y1041280D03*
Y1034587D03*
Y1047973D03*
Y1054666D03*
Y1061359D03*
Y1071398D03*
Y1078091D03*
X1041065Y1089804D03*
X1045465Y1101516D03*
Y1108209D03*
Y1114902D03*
X1041065Y1126615D03*
X1045465Y1138327D03*
Y1145020D03*
Y1151713D03*
X1041065Y1163426D03*
X1045465Y1175138D03*
Y1188524D03*
Y1181831D03*
X1041065Y1200237D03*
X1045465Y1211949D03*
Y1218642D03*
X1041065Y1237048D03*
X1045465Y1225335D03*
Y1248760D03*
Y1255453D03*
X1048684Y1350724D03*
X1051684D03*
X1050866Y1659548D03*
X1062199Y49379D03*
X1061456Y406560D03*
X1063614Y733409D03*
X1057057Y756765D03*
X1061607Y773563D03*
X1057057Y763765D03*
X1057207Y791969D03*
X1056157Y786949D03*
X1061607Y780256D03*
Y803681D03*
X1056157Y796988D03*
X1061607Y810374D03*
Y817067D03*
X1056157Y823760D03*
Y833799D03*
X1057207Y828780D03*
X1061607Y847185D03*
Y840492D03*
Y853878D03*
X1056157Y860571D03*
X1057207Y865591D03*
X1056157Y870610D03*
X1061607Y877303D03*
Y883996D03*
Y890689D03*
X1056157Y907422D03*
Y897382D03*
X1057207Y902402D03*
X1061607Y914114D03*
Y920807D03*
Y927500D03*
X1056157Y934193D03*
X1057207Y939213D03*
X1061607Y950925D03*
X1056157Y944233D03*
X1061607Y964311D03*
Y971004D03*
Y957618D03*
Y977697D03*
Y984390D03*
Y991083D03*
Y997776D03*
Y1004469D03*
Y1037933D03*
Y1044626D03*
Y1031240D03*
Y1051319D03*
Y1058012D03*
Y1074744D03*
Y1068051D03*
X1057207Y1086457D03*
X1056157Y1081437D03*
Y1091477D03*
X1061607Y1098170D03*
Y1104862D03*
X1056157Y1118248D03*
X1061607Y1111555D03*
Y1134981D03*
X1057207Y1123268D03*
X1056157Y1128288D03*
X1061607Y1141674D03*
Y1148366D03*
X1056157Y1155059D03*
Y1165099D03*
X1057207Y1160079D03*
X1061607Y1171792D03*
Y1178485D03*
X1056157Y1191870D03*
X1061607Y1185177D03*
X1056157Y1201910D03*
X1057207Y1196890D03*
X1061607Y1208603D03*
Y1215296D03*
Y1221988D03*
X1056157Y1238721D03*
X1057207Y1233701D03*
X1056157Y1228681D03*
X1061607Y1245414D03*
Y1252107D03*
X1060684Y1350724D03*
X1057684D03*
X1054684D03*
X1056584Y1523080D03*
Y1520080D03*
Y1526080D03*
X1063751Y1653834D03*
X1064221Y1662726D03*
X1068221Y1662778D03*
X1068827Y389734D03*
X1074800Y391262D03*
X1077418Y411322D03*
Y416763D03*
Y421922D03*
X1081133Y461516D03*
X1071239Y479655D03*
X1081632Y648854D03*
X1079716Y756765D03*
Y760265D03*
Y767265D03*
X1075166Y776910D03*
Y783603D03*
X1070766Y795315D03*
X1075166Y807028D03*
Y813721D03*
Y820414D03*
X1070766Y832126D03*
X1075166Y850532D03*
Y843839D03*
Y857225D03*
X1070766Y868937D03*
X1075166Y880650D03*
Y887343D03*
Y894036D03*
X1070766Y905749D03*
X1075166Y917461D03*
Y924154D03*
Y930847D03*
X1070766Y942560D03*
X1075166Y954272D03*
Y967658D03*
Y960965D03*
Y974351D03*
Y981044D03*
Y987736D03*
Y994429D03*
Y1004469D03*
Y1034587D03*
Y1041280D03*
Y1047973D03*
Y1054666D03*
Y1061359D03*
Y1071398D03*
Y1078091D03*
X1070766Y1089804D03*
X1075166Y1101516D03*
Y1108209D03*
Y1114902D03*
X1070766Y1126615D03*
X1075166Y1138327D03*
Y1145020D03*
Y1151713D03*
X1070766Y1163426D03*
X1075166Y1175138D03*
Y1188524D03*
Y1181831D03*
X1070766Y1200237D03*
X1075166Y1211949D03*
Y1218642D03*
X1070766Y1237048D03*
X1075166Y1225335D03*
Y1248760D03*
Y1255453D03*
X1070949Y1337752D03*
X1067929Y1337702D03*
X1079215Y1357390D03*
X1076615D03*
X1071908Y1361660D03*
X1080889Y1367253D03*
X1076615Y1360497D03*
X1079215D03*
X1078459Y1367253D03*
Y1372853D03*
X1080889D03*
X1073733Y1388198D03*
X1068094Y1654099D03*
X1084199Y49379D03*
X1086936Y370532D03*
X1083583Y395195D03*
X1093722Y427960D03*
X1087000Y477500D03*
X1096473Y484391D03*
Y489391D03*
X1088730Y509362D03*
X1086758Y756765D03*
X1091308Y773563D03*
X1086758Y763765D03*
X1086908Y791969D03*
X1091308Y780256D03*
X1085858Y786949D03*
X1091308Y803681D03*
X1085858Y796988D03*
X1091308Y810374D03*
Y817067D03*
X1085858Y823760D03*
Y833799D03*
X1086908Y828780D03*
X1091308Y840492D03*
Y847185D03*
Y853878D03*
X1085858Y860571D03*
X1086908Y865591D03*
X1085858Y870610D03*
X1091308Y877303D03*
Y883996D03*
Y890689D03*
X1085858Y907422D03*
Y897382D03*
X1086908Y902402D03*
X1091308Y914114D03*
Y920807D03*
X1085858Y934193D03*
X1091308Y927500D03*
X1086908Y939213D03*
X1085858Y944233D03*
X1091308Y950925D03*
Y964311D03*
Y971004D03*
Y957618D03*
Y977697D03*
Y984390D03*
Y991083D03*
Y997776D03*
Y1004469D03*
Y1031240D03*
Y1037933D03*
Y1044626D03*
Y1051319D03*
Y1058012D03*
Y1074744D03*
Y1068051D03*
X1086908Y1086457D03*
X1085858Y1081437D03*
Y1091477D03*
X1091308Y1098170D03*
Y1104862D03*
X1085858Y1118248D03*
X1091308Y1111555D03*
Y1134981D03*
X1086908Y1123268D03*
X1085858Y1128288D03*
X1091308Y1141674D03*
Y1148366D03*
X1085858Y1155059D03*
Y1165099D03*
X1086908Y1160079D03*
X1091308Y1171792D03*
Y1178485D03*
X1085858Y1191870D03*
X1091308Y1185177D03*
X1085858Y1201910D03*
X1086908Y1196890D03*
X1091308Y1208603D03*
Y1215296D03*
Y1221988D03*
X1085858Y1238721D03*
Y1228681D03*
X1086908Y1233701D03*
X1091308Y1245414D03*
Y1252107D03*
X1095809Y1337824D03*
X1087015Y1357390D03*
X1095629Y1352252D03*
Y1349652D03*
Y1354852D03*
X1089515Y1357390D03*
X1091959Y1357406D03*
X1084415Y1357390D03*
X1081815D03*
X1092905Y1363394D03*
Y1360437D03*
X1083319Y1367253D03*
X1081815Y1360497D03*
X1084415D03*
X1081815Y1363454D03*
X1084415D03*
X1083319Y1372853D03*
X1083368Y1385268D03*
X1096469Y1643468D03*
X1090143Y1643625D03*
X1091026Y1653031D03*
X1092030Y1720841D03*
X1106199Y49379D03*
X1101942Y395361D03*
X1109416Y756765D03*
Y760265D03*
Y767265D03*
X1104866Y776910D03*
Y783603D03*
X1100466Y795315D03*
X1104866Y807028D03*
Y813721D03*
Y820414D03*
X1100466Y832126D03*
X1104866Y850532D03*
Y843839D03*
Y857225D03*
X1100466Y868937D03*
X1104866Y880650D03*
Y887343D03*
Y894036D03*
X1100466Y905749D03*
X1104866Y917461D03*
Y924154D03*
Y930847D03*
X1100466Y942560D03*
X1104866Y954272D03*
Y967658D03*
Y960965D03*
Y974351D03*
Y981044D03*
Y987736D03*
Y994429D03*
Y1004469D03*
Y1034587D03*
Y1041280D03*
Y1047973D03*
Y1054666D03*
Y1071398D03*
Y1061359D03*
Y1078091D03*
X1100466Y1089804D03*
X1104866Y1101516D03*
Y1108209D03*
Y1114902D03*
X1100466Y1126615D03*
X1104866Y1138327D03*
Y1145020D03*
Y1151713D03*
X1100466Y1163426D03*
X1104866Y1175138D03*
Y1188524D03*
Y1181831D03*
X1100466Y1200237D03*
X1104866Y1211949D03*
Y1218642D03*
X1100466Y1237048D03*
X1104866Y1225335D03*
Y1248760D03*
Y1255453D03*
X1103529Y1337792D03*
X1109289Y1337752D03*
X1098409Y1337824D03*
X1109215Y1357390D03*
X1098229Y1352252D03*
Y1349652D03*
X1096979Y1357352D03*
X1098229Y1354852D03*
X1104448Y1361680D03*
X1109215Y1360497D03*
X1111059Y1367253D03*
Y1372853D03*
X1103888Y1386721D03*
X1102230Y1384770D03*
X1105000Y1682132D03*
X1109521Y1724109D03*
X1113943Y452055D03*
X1116458Y756765D03*
X1121008Y773563D03*
X1116459Y763765D03*
X1116608Y791969D03*
X1121008Y780256D03*
X1115558Y786949D03*
X1121008Y803681D03*
X1115558Y796988D03*
X1121008Y810374D03*
Y817067D03*
X1115558Y823760D03*
Y833799D03*
X1116608Y828780D03*
X1121008Y847185D03*
Y840492D03*
Y853878D03*
X1115558Y860571D03*
X1116608Y865591D03*
X1115558Y870610D03*
X1121008Y877303D03*
Y883996D03*
Y890689D03*
X1115558Y907422D03*
Y897382D03*
X1116608Y902402D03*
X1121008Y914114D03*
Y920807D03*
X1115558Y934193D03*
X1121008Y927500D03*
X1116608Y939213D03*
X1115558Y944233D03*
X1121008Y950925D03*
Y964311D03*
Y971004D03*
Y957618D03*
Y977697D03*
Y984390D03*
Y991083D03*
Y997776D03*
Y1004469D03*
Y1031240D03*
Y1037933D03*
Y1044626D03*
Y1051319D03*
Y1058012D03*
Y1074744D03*
Y1068051D03*
X1116608Y1086457D03*
X1115558Y1081437D03*
Y1091477D03*
X1121008Y1098170D03*
Y1104862D03*
X1115558Y1118248D03*
X1121008Y1111555D03*
Y1134981D03*
X1116608Y1123268D03*
X1115558Y1128288D03*
X1121008Y1141674D03*
Y1148366D03*
X1115558Y1155059D03*
Y1165099D03*
X1116608Y1160079D03*
X1121008Y1171792D03*
Y1178485D03*
X1115558Y1191870D03*
X1121008Y1185177D03*
X1115558Y1201910D03*
X1116608Y1196890D03*
X1121008Y1208603D03*
Y1215296D03*
Y1221988D03*
X1115558Y1238721D03*
Y1228681D03*
X1116608Y1233701D03*
X1121008Y1245414D03*
Y1252107D03*
X1119615Y1357390D03*
X1122115D03*
X1124559Y1357406D03*
X1117015Y1357390D03*
X1111815D03*
X1114415D03*
X1117015Y1363454D03*
Y1360497D03*
X1115919Y1372853D03*
X1125505Y1363394D03*
Y1360437D03*
X1115919Y1367253D03*
X1113489D03*
X1114415Y1363454D03*
X1111815Y1360497D03*
X1114415D03*
X1113489Y1372853D03*
X1115968Y1385268D03*
X1117946Y1467955D03*
X1117828Y1473091D03*
X1118326Y1594118D03*
X1118004Y1584908D03*
X1113785Y1601462D03*
X1117263Y1601526D03*
X1115394Y1620306D03*
X1120376Y1641684D03*
X1125487Y1641754D03*
X1125771Y1652189D03*
X1120595Y1652037D03*
X1120200Y1646597D03*
X1116000Y1671029D03*
X1125732Y1666072D03*
X1120303Y1682055D03*
X1113948Y1714244D03*
X1128199Y49379D03*
X1142830Y53186D03*
X1139200Y380533D03*
Y385698D03*
X1127471Y404788D03*
X1132387Y615658D03*
X1139117Y756765D03*
Y760265D03*
Y767265D03*
X1134567Y776910D03*
Y783603D03*
X1130167Y795315D03*
X1134567Y807028D03*
Y813721D03*
Y820414D03*
X1130167Y832126D03*
X1134567Y850532D03*
Y843839D03*
Y857225D03*
X1130167Y868937D03*
X1134567Y880650D03*
Y887343D03*
Y894036D03*
X1130167Y905749D03*
X1134567Y917461D03*
Y924154D03*
Y930847D03*
X1130167Y942560D03*
X1134567Y954272D03*
Y967658D03*
Y960965D03*
Y974351D03*
Y981044D03*
Y987736D03*
Y994429D03*
Y1004469D03*
Y1034587D03*
Y1041280D03*
Y1047973D03*
Y1054666D03*
Y1061359D03*
Y1071398D03*
X1130167Y1089804D03*
X1134567Y1078091D03*
Y1101516D03*
Y1108209D03*
Y1114902D03*
X1130167Y1126615D03*
X1134567Y1138327D03*
Y1145020D03*
X1130167Y1163426D03*
X1134567Y1151713D03*
Y1175138D03*
Y1188524D03*
Y1181831D03*
X1130167Y1200237D03*
X1134567Y1211949D03*
Y1218642D03*
X1130167Y1237048D03*
X1134567Y1225335D03*
Y1248760D03*
Y1255453D03*
X1136219Y1337794D03*
X1133619D03*
X1130829Y1352252D03*
Y1349652D03*
Y1354852D03*
X1128229Y1352252D03*
Y1349652D03*
X1129579Y1357352D03*
X1128229Y1354852D03*
X1137218Y1361660D03*
X1136588Y1386721D03*
X1134930Y1384770D03*
X1137846Y1453487D03*
X1135043Y1553371D03*
X1137523Y1579453D03*
X1136173Y1573638D03*
X1131790Y1597984D03*
X1131832Y1607245D03*
X1132168Y1620860D03*
X1138752Y1624627D03*
X1130772Y1641753D03*
X1130684Y1646949D03*
X1130245Y1652189D03*
X1140117Y1671421D03*
X1132209Y1672033D03*
X1129230Y1666174D03*
X1137492Y1685240D03*
X1128934Y1688600D03*
X1150199Y49379D03*
X1155577Y73939D03*
X1147813Y492319D03*
X1146159Y756765D03*
X1150709Y773563D03*
X1146160Y763765D03*
X1146309Y791969D03*
X1145259Y786949D03*
X1150709Y780256D03*
X1145259Y796988D03*
X1150709Y803681D03*
Y810374D03*
Y817067D03*
X1146309Y828780D03*
X1145259Y823760D03*
Y833799D03*
X1150709Y840492D03*
Y847185D03*
X1146309Y865591D03*
X1145259Y860571D03*
X1150709Y853878D03*
X1145259Y870610D03*
X1150709Y877303D03*
Y883996D03*
Y890689D03*
X1145259Y907422D03*
X1146309Y902402D03*
X1145259Y897382D03*
X1150709Y914114D03*
Y920807D03*
X1145259Y934193D03*
X1146309Y939213D03*
X1150709Y927500D03*
X1145259Y944233D03*
X1150709Y950925D03*
Y964311D03*
Y971004D03*
Y957618D03*
Y977697D03*
Y984390D03*
Y991083D03*
Y997776D03*
Y1004469D03*
Y1031240D03*
Y1037933D03*
Y1044626D03*
Y1051319D03*
Y1058012D03*
Y1074744D03*
Y1068051D03*
X1146309Y1086457D03*
X1145259Y1081437D03*
Y1091477D03*
X1150709Y1098170D03*
Y1104862D03*
X1145259Y1118248D03*
X1150709Y1111555D03*
Y1134981D03*
X1146309Y1123268D03*
X1145259Y1128288D03*
X1150709Y1141674D03*
Y1148366D03*
X1145259Y1155059D03*
X1146309Y1160079D03*
X1145259Y1165099D03*
X1150709Y1171792D03*
Y1178485D03*
X1145259Y1191870D03*
X1150709Y1185177D03*
X1145259Y1201910D03*
X1146309Y1196890D03*
X1150709Y1208603D03*
Y1215296D03*
Y1221988D03*
X1145259Y1238721D03*
X1146309Y1233701D03*
X1145259Y1228681D03*
X1150709Y1245414D03*
Y1252107D03*
X1154839Y1337834D03*
X1145819D03*
X1143219D03*
X1152315Y1357390D03*
X1154815D03*
X1147115D03*
X1149715D03*
X1141915D03*
X1144515D03*
X1147115Y1360497D03*
X1149715Y1363454D03*
Y1360497D03*
X1147115Y1363454D03*
X1146189Y1372853D03*
X1148619D03*
Y1367253D03*
X1146189D03*
X1141915Y1360497D03*
X1144515D03*
X1143759Y1367253D03*
Y1372853D03*
X1148668Y1385268D03*
X1150458Y1433146D03*
X1144118Y1449628D03*
X1151384Y1556029D03*
X1143063Y1580334D03*
X1152186Y1570567D03*
X1149278Y1589453D03*
X1145060Y1588837D03*
X1141645Y1640017D03*
X1146316Y1649422D03*
X1143127Y1649068D03*
X1144107Y1671118D03*
X1146477Y1658441D03*
X1168687Y74202D03*
X1163113Y481691D03*
X1165589Y569118D03*
X1168818Y756765D03*
Y760265D03*
X1164268Y776910D03*
X1168818Y767265D03*
X1164268Y783603D03*
X1159868Y795315D03*
X1164268Y807028D03*
Y820414D03*
Y813721D03*
X1159868Y832126D03*
X1164268Y850532D03*
Y843839D03*
Y857225D03*
X1159868Y868937D03*
X1164268Y880650D03*
Y887343D03*
Y894036D03*
X1159868Y905749D03*
X1164268Y917461D03*
Y924154D03*
Y930847D03*
X1159868Y942560D03*
X1164268Y954272D03*
Y960965D03*
Y967658D03*
Y974351D03*
Y981044D03*
Y987736D03*
Y994429D03*
Y1004469D03*
Y1034587D03*
Y1041280D03*
Y1047973D03*
Y1054666D03*
Y1061359D03*
Y1071398D03*
X1159868Y1089804D03*
X1164268Y1078091D03*
Y1101516D03*
Y1108209D03*
Y1114902D03*
X1159868Y1126615D03*
X1164268Y1138327D03*
Y1145020D03*
X1159868Y1163426D03*
X1164268Y1151713D03*
Y1175138D03*
Y1181831D03*
Y1188524D03*
X1159868Y1200237D03*
X1164268Y1211949D03*
Y1218642D03*
X1159868Y1237048D03*
X1164268Y1225335D03*
Y1248760D03*
Y1255453D03*
X1167509Y1337884D03*
X1164909D03*
X1157439Y1337834D03*
X1160929Y1352252D03*
X1163529D03*
X1160929Y1349652D03*
X1163529D03*
X1162279Y1357352D03*
X1163529Y1354852D03*
X1157259Y1357406D03*
X1170138Y1361800D03*
X1158205Y1363394D03*
Y1360437D03*
X1169488Y1386721D03*
X1167830Y1384770D03*
X1161311Y1548204D03*
X1172523Y1573250D03*
X1160031Y1591163D03*
X1162144Y1658042D03*
X1159741Y1669759D03*
X1169187Y1687117D03*
X1174958Y-24648D03*
Y5352D03*
Y15352D03*
X1177429Y89556D03*
Y93556D03*
X1185952Y432202D03*
Y440202D03*
Y448202D03*
X1185707Y465272D03*
Y460202D03*
Y470392D03*
X1185117Y571807D03*
X1181445Y592868D03*
X1175860Y756765D03*
X1180410Y773563D03*
X1175860Y763765D03*
X1176010Y791969D03*
X1180410Y780256D03*
X1174960Y786949D03*
X1180410Y803681D03*
X1174960Y796988D03*
X1180410Y817067D03*
Y810374D03*
X1176010Y828780D03*
X1174960Y833799D03*
Y823760D03*
X1180410Y847185D03*
Y840492D03*
X1176010Y865591D03*
X1180410Y853878D03*
X1174960Y860571D03*
X1180410Y877303D03*
X1174960Y870610D03*
X1180410Y890689D03*
Y883996D03*
X1176010Y902402D03*
X1174960Y897382D03*
Y907422D03*
X1180410Y914114D03*
Y920807D03*
X1176010Y939213D03*
X1174960Y934193D03*
X1180410Y927500D03*
X1174960Y944233D03*
X1180410Y950925D03*
Y957618D03*
Y964311D03*
Y971004D03*
Y977697D03*
Y984390D03*
Y991083D03*
Y997776D03*
Y1004469D03*
Y1031240D03*
Y1037933D03*
Y1044626D03*
Y1051319D03*
Y1058012D03*
Y1068051D03*
Y1074744D03*
X1176010Y1086457D03*
X1174960Y1081437D03*
Y1091477D03*
X1180410Y1098170D03*
Y1104862D03*
X1174960Y1118248D03*
X1180410Y1111555D03*
X1176010Y1123268D03*
X1174960Y1128288D03*
X1180410Y1134981D03*
Y1141674D03*
Y1148366D03*
X1176010Y1160079D03*
X1174960Y1155059D03*
Y1165099D03*
X1180410Y1171792D03*
Y1178485D03*
X1174960Y1191870D03*
X1180410Y1185177D03*
X1176010Y1196890D03*
X1174960Y1201910D03*
X1180410Y1208603D03*
Y1215296D03*
Y1221988D03*
X1176010Y1233701D03*
X1174960Y1238721D03*
Y1228681D03*
X1180410Y1245414D03*
Y1252107D03*
X1182615Y1357390D03*
X1185215D03*
X1177415D03*
X1174815D03*
X1180015D03*
X1182615Y1363454D03*
Y1360497D03*
X1180015Y1363454D03*
X1174815Y1360497D03*
X1177415D03*
X1180015D03*
X1176659Y1367253D03*
Y1372853D03*
X1179089D03*
X1181519D03*
Y1367253D03*
X1179089D03*
X1181568Y1385268D03*
X1185000Y1396500D03*
Y1401000D03*
X1184100Y1410000D03*
X1185000Y1405500D03*
X1178400Y1433000D03*
X1181324Y1485895D03*
X1183234Y1483295D03*
Y1488495D03*
X1181314Y1492995D03*
X1176534D03*
X1174624Y1495595D03*
X1181314Y1498195D03*
X1176534D03*
X1180047Y1533247D03*
X1181853Y1561731D03*
X1172523Y1562350D03*
X1179187Y1666429D03*
X1175454Y1668046D03*
X1178932Y1686698D03*
X1185676Y1697249D03*
X1194199Y49379D03*
X1198694Y57015D03*
X1191488Y87125D03*
Y91125D03*
X1200518Y100875D03*
X1189701Y173187D03*
X1201157Y431875D03*
X1189540Y481691D03*
X1188192Y589263D03*
X1191646Y589567D03*
X1195729Y591022D03*
X1198519Y756765D03*
Y760265D03*
X1193969Y776910D03*
X1198519Y767265D03*
X1193969Y783603D03*
X1189569Y795315D03*
X1193969Y807028D03*
Y820414D03*
Y813721D03*
X1189569Y832126D03*
X1193969Y850532D03*
Y843839D03*
Y857225D03*
X1189569Y868937D03*
X1193969Y880650D03*
Y887343D03*
Y894036D03*
X1189569Y905749D03*
X1193969Y917461D03*
Y924154D03*
Y930847D03*
Y954272D03*
X1189569Y942560D03*
X1193969Y960965D03*
Y967658D03*
Y974351D03*
Y981044D03*
Y987736D03*
Y994429D03*
Y1004469D03*
Y1034587D03*
Y1041280D03*
Y1047973D03*
Y1054666D03*
Y1061359D03*
Y1071398D03*
X1189569Y1089804D03*
X1193969Y1078091D03*
Y1101516D03*
Y1108209D03*
Y1114902D03*
X1189569Y1126615D03*
X1193969Y1138327D03*
Y1145020D03*
X1189569Y1163426D03*
X1193969Y1151713D03*
Y1175138D03*
Y1181831D03*
Y1188524D03*
X1189569Y1200237D03*
X1193969Y1211949D03*
Y1218642D03*
X1189569Y1237048D03*
X1193969Y1225335D03*
Y1248760D03*
Y1255453D03*
X1196159Y1326549D03*
X1193659Y1326589D03*
Y1324049D03*
X1196259D03*
X1193659Y1321549D03*
X1196259D03*
X1199899Y1338065D03*
X1193829Y1352252D03*
X1196429D03*
X1193829Y1349652D03*
X1196429D03*
X1193829Y1354852D03*
X1190159Y1357406D03*
X1195179Y1357352D03*
X1196429Y1354852D03*
X1187715Y1357390D03*
X1191105Y1363394D03*
Y1360437D03*
X1200690Y1384572D03*
X1194000Y1418000D03*
X1187925Y1417000D03*
X1194000Y1428500D03*
Y1433000D03*
X1187925Y1440400D03*
X1188014Y1483295D03*
Y1488495D03*
X1194724Y1505295D03*
X1196634Y1502695D03*
Y1507895D03*
X1196127Y1583797D03*
X1195261Y1622884D03*
X1200217D03*
X1195050Y1620040D03*
X1195261Y1627876D03*
X1200217D03*
Y1654796D03*
X1195261D03*
X1200217Y1659788D03*
X1195261D03*
X1192903Y1666276D03*
X1189462Y1691366D03*
X1196767Y1712261D03*
X1196814Y1726261D03*
X1215528Y172395D03*
X1214156Y292066D03*
X1214856Y421018D03*
X1213866Y455376D03*
X1208400Y591631D03*
X1201440Y668138D03*
X1207177Y668115D03*
X1205561Y756765D03*
X1210111Y773563D03*
X1205561Y763765D03*
X1205711Y791969D03*
X1210111Y780256D03*
X1204661Y786949D03*
X1210111Y803681D03*
X1204661Y796988D03*
X1210111Y817067D03*
Y810374D03*
X1205711Y828780D03*
X1204661Y833799D03*
Y823760D03*
X1210111Y847185D03*
Y840492D03*
X1205711Y865591D03*
X1210111Y853878D03*
X1204661Y860571D03*
X1210111Y877303D03*
X1204661Y870610D03*
X1210111Y890689D03*
Y883996D03*
X1205711Y902402D03*
X1204661Y897382D03*
Y907422D03*
X1210111Y914114D03*
Y920807D03*
X1205711Y939213D03*
X1204661Y934193D03*
X1210111Y927500D03*
X1204661Y944233D03*
X1210111Y950925D03*
Y957618D03*
Y964311D03*
Y971004D03*
Y977697D03*
Y984390D03*
Y991083D03*
Y997776D03*
Y1004469D03*
Y1031240D03*
Y1037933D03*
Y1044626D03*
Y1051319D03*
Y1058012D03*
Y1068051D03*
Y1074744D03*
X1205711Y1086457D03*
X1204661Y1081437D03*
Y1091477D03*
X1210111Y1098170D03*
Y1104862D03*
X1204661Y1118248D03*
X1210111Y1111555D03*
X1205711Y1123268D03*
X1204661Y1128288D03*
X1210111Y1134981D03*
Y1141674D03*
Y1148366D03*
X1205711Y1160079D03*
X1204661Y1155059D03*
Y1165099D03*
X1210111Y1171792D03*
Y1178485D03*
X1204661Y1191870D03*
X1210111Y1185177D03*
X1205711Y1196890D03*
X1204661Y1201910D03*
X1210111Y1208603D03*
Y1215296D03*
Y1221988D03*
X1205711Y1233701D03*
X1204661Y1228681D03*
Y1238721D03*
X1210111Y1245414D03*
Y1252107D03*
X1205189Y1321492D03*
Y1323992D03*
X1202689Y1321492D03*
Y1324032D03*
X1211299Y1338105D03*
X1202399D03*
X1215415Y1357390D03*
X1212815D03*
X1210215D03*
X1207615D03*
X1202988Y1361490D03*
X1215415Y1363454D03*
Y1360497D03*
X1212815Y1363454D03*
Y1360497D03*
X1210215D03*
X1207615D03*
X1214319Y1372853D03*
X1211889D03*
X1209459D03*
Y1367253D03*
X1214319D03*
X1211889D03*
X1214368Y1385268D03*
X1202288Y1386721D03*
X1202484Y1402467D03*
X1203334Y1492995D03*
X1208114D03*
X1210034Y1483295D03*
X1214814D03*
X1208124Y1485895D03*
X1210034Y1488495D03*
X1214814D03*
X1201424Y1495595D03*
X1203334Y1498195D03*
X1208114D03*
X1201414Y1502695D03*
Y1507895D03*
X1200851Y1583797D03*
X1205576Y1583897D03*
X1210300Y1583697D03*
X1215025Y1583897D03*
X1207321Y1622884D03*
X1212277D03*
X1201291Y1637876D03*
Y1632884D03*
X1206247D03*
Y1637876D03*
X1213351D03*
Y1632884D03*
X1207321Y1627876D03*
X1212277D03*
X1207321Y1654796D03*
X1206247Y1649788D03*
X1201291D03*
X1212277Y1654796D03*
X1213351Y1649788D03*
X1206247Y1644796D03*
X1201291D03*
X1213351D03*
X1207321Y1659788D03*
X1212277D03*
X1204804Y1691375D03*
X1216199Y49379D03*
X1230156Y292066D03*
X1222094Y286948D03*
X1219463Y1338122D03*
X1229809Y1338105D03*
X1226629Y1352252D03*
X1229229D03*
X1226629Y1349652D03*
X1229229D03*
X1222959Y1357406D03*
X1227979Y1357352D03*
X1226629Y1354852D03*
X1229229D03*
X1220515Y1357390D03*
X1218015D03*
X1223905Y1363394D03*
Y1360437D03*
X1230134Y1492995D03*
X1228224Y1495595D03*
X1221524Y1505295D03*
X1230134Y1498195D03*
X1228214Y1502695D03*
X1223434D03*
Y1507895D03*
X1228214D03*
X1219749Y1583897D03*
X1224474Y1583697D03*
X1229198Y1583797D03*
X1219381Y1622884D03*
X1224337D03*
X1218307Y1637876D03*
Y1632884D03*
X1230367Y1637876D03*
X1225411D03*
X1230367Y1632884D03*
X1225411D03*
X1219381Y1627876D03*
X1224337D03*
Y1654796D03*
X1219381D03*
X1218307Y1649788D03*
X1225411D03*
X1230367D03*
X1218307Y1644796D03*
X1225411D03*
X1230367D03*
X1224337Y1659788D03*
X1219381D03*
X1219738Y1717011D03*
Y1731011D03*
X1236844Y-34348D03*
X1236829Y-36863D03*
X1236798Y-31476D03*
X1236813Y-28961D03*
X1240097Y-34334D03*
X1243122Y-35654D03*
X1240082Y-36849D03*
X1236877Y-26227D03*
X1236932Y-19948D03*
X1236942Y-13666D03*
X1236927Y-16181D03*
X1236892Y-23712D03*
X1240130Y-26213D03*
X1240194Y-19948D03*
X1240195Y-13652D03*
X1243220Y-14972D03*
X1240180Y-16167D03*
X1240145Y-23698D03*
X1243170Y-25018D03*
X1236932Y-9948D03*
Y52D03*
X1236942Y-3666D03*
X1236927Y-6181D03*
X1240194Y-9948D03*
Y52D03*
X1240195Y-3652D03*
X1243220Y-4972D03*
X1240180Y-6167D03*
X1236927Y13819D03*
X1236942Y16334D03*
X1236932Y10052D03*
X1236942Y6334D03*
X1236927Y3819D03*
X1240180Y13833D03*
X1243220Y15028D03*
X1240195Y16348D03*
X1240194Y10052D03*
X1240195Y6348D03*
X1243220Y5028D03*
X1240180Y3833D03*
X1236911Y21721D03*
X1236896Y19206D03*
X1236941Y26751D03*
X1236926Y24236D03*
X1243219Y25445D03*
X1240194Y26765D03*
X1240179Y24250D03*
X1238199Y49379D03*
X1245606Y1314351D03*
Y1311244D03*
X1240899Y1315460D03*
X1240240Y1339578D03*
X1232409Y1338105D03*
X1242500Y1430075D03*
X1237100Y1442500D03*
X1242500Y1437075D03*
X1234924Y1485895D03*
X1241614Y1483295D03*
X1236834D03*
X1241614Y1488495D03*
X1236834D03*
X1234914Y1492995D03*
Y1498195D03*
X1233923Y1583897D03*
X1238647D03*
X1243372D03*
X1231441Y1622884D03*
X1236397D03*
X1243501D03*
X1237471Y1637876D03*
Y1632884D03*
X1242427Y1637876D03*
Y1632884D03*
X1236397Y1627876D03*
X1231441D03*
X1243501D03*
X1231441Y1654796D03*
X1236397D03*
X1237471Y1649788D03*
X1243501Y1654796D03*
X1242427Y1649788D03*
X1237471Y1644796D03*
X1242427D03*
X1231441Y1659788D03*
X1236397D03*
X1243501D03*
X1260199Y49379D03*
X1256064Y101100D03*
X1254094Y286948D03*
X1245825Y305275D03*
X1260227Y407128D03*
Y411128D03*
X1248902Y470733D03*
X1257016Y467253D03*
X1246490Y483302D03*
X1257450Y1291721D03*
X1260050D03*
X1249650D03*
X1247050D03*
X1258506Y1311244D03*
X1256006D03*
X1253406Y1314351D03*
X1250806D03*
X1253406Y1311244D03*
X1250806D03*
X1248206Y1314351D03*
Y1311244D03*
X1252310Y1321107D03*
X1249880D03*
X1252310Y1326707D03*
X1253406Y1317308D03*
X1250806D03*
X1247450Y1326707D03*
Y1321107D03*
X1249880Y1326707D03*
X1252359Y1339122D03*
X1252315Y1417085D03*
X1254905Y1417026D03*
X1256934Y1492995D03*
X1255024Y1495595D03*
X1248324Y1505295D03*
X1256934Y1498195D03*
X1255014Y1502695D03*
X1250234D03*
X1255014Y1507895D03*
X1250234D03*
X1248096Y1583897D03*
X1252820Y1583697D03*
X1257544Y1583897D03*
X1248457Y1622884D03*
X1255561D03*
X1254487Y1637876D03*
Y1632884D03*
X1249531Y1637876D03*
Y1632884D03*
X1248457Y1627876D03*
X1255561D03*
X1248457Y1654796D03*
X1254487Y1649788D03*
X1249531D03*
X1255561Y1654796D03*
X1254487Y1644796D03*
X1249531D03*
X1248657Y1659588D03*
X1255561Y1659788D03*
X1266146Y121022D03*
X1263582Y164051D03*
Y160051D03*
Y180551D03*
Y176051D03*
Y172051D03*
Y168051D03*
Y185051D03*
X1270094Y286948D03*
X1262156Y292066D03*
X1270670Y1291624D03*
X1268070D03*
X1261896Y1314291D03*
X1260950Y1311260D03*
X1267220Y1306106D03*
Y1308706D03*
Y1303506D03*
X1265970Y1311206D03*
X1264620Y1303506D03*
Y1306106D03*
Y1308706D03*
X1273869Y1315300D03*
X1261896Y1317248D03*
X1273175Y1340547D03*
X1271517Y1338596D03*
X1275124Y1485895D03*
X1261724D03*
X1263634Y1483295D03*
X1268414D03*
X1263634Y1488495D03*
X1268414D03*
X1261714Y1492995D03*
Y1498195D03*
X1262269Y1583897D03*
X1266993Y1583797D03*
X1267621Y1622884D03*
X1260517D03*
X1272577D03*
X1261591Y1637876D03*
X1266547D03*
X1261591Y1632884D03*
X1266547D03*
X1273651Y1637876D03*
Y1632790D03*
X1267621Y1627876D03*
X1260517D03*
X1272577D03*
X1260517Y1654796D03*
X1267621D03*
X1266547Y1649788D03*
X1261591D03*
X1272577Y1654796D03*
X1273651Y1649788D03*
X1266547Y1644796D03*
X1261591D03*
X1273651D03*
X1260517Y1659788D03*
X1267621D03*
X1272577D03*
X1282199Y49379D03*
X1278111Y150030D03*
X1285391Y142553D03*
X1286094Y286948D03*
X1278156Y292066D03*
X1277598Y404428D03*
X1282165Y408987D03*
X1288202Y405741D03*
X1288902Y1311216D03*
X1286302Y1314323D03*
X1283702D03*
X1286302Y1311216D03*
X1283702D03*
X1278502Y1314323D03*
X1281102D03*
Y1311216D03*
X1278502D03*
X1285206Y1326679D03*
X1286302Y1317280D03*
X1283702D03*
X1285206Y1321079D03*
X1282776D03*
Y1326679D03*
X1280346Y1321079D03*
Y1326679D03*
X1285255Y1339094D03*
X1277034Y1483295D03*
X1281814D03*
X1277034Y1488495D03*
X1281814D03*
X1284510Y1556953D03*
X1278012Y1581563D03*
X1279681Y1622884D03*
X1284637D03*
X1278607Y1637876D03*
Y1632790D03*
X1285711Y1637876D03*
Y1632884D03*
X1279681Y1627876D03*
X1284637D03*
X1279681Y1654796D03*
X1278607Y1649788D03*
X1284637Y1654796D03*
X1285711Y1649788D03*
X1278607Y1644796D03*
X1285711D03*
X1279681Y1659788D03*
X1284637D03*
X1304199Y49379D03*
X1300668Y125739D03*
Y133739D03*
Y129739D03*
X1306431Y149330D03*
X1300668Y145739D03*
X1292082Y166051D03*
Y162051D03*
Y171551D03*
Y184051D03*
X1302094Y298066D03*
Y286948D03*
X1294156Y292066D03*
X1293277Y401125D03*
X1296228Y408125D03*
X1299076Y530023D03*
X1297487Y590607D03*
X1302890Y1291759D03*
X1298350Y1291721D03*
X1295750D03*
X1300116Y1306078D03*
Y1303478D03*
Y1308678D03*
X1298866Y1311178D03*
X1294792Y1314263D03*
X1297516Y1306078D03*
Y1303478D03*
Y1308678D03*
X1291402Y1311216D03*
X1293846Y1311232D03*
X1294792Y1317220D03*
X1304421Y1338539D03*
X1304596Y1492995D03*
X1302686Y1495595D03*
X1304596Y1498195D03*
X1291819Y1563595D03*
X1294319D03*
X1300560Y1554261D03*
X1291741Y1622884D03*
X1296697D03*
X1303801D03*
X1290667Y1637876D03*
Y1632884D03*
X1297771Y1637876D03*
Y1632884D03*
X1302727Y1637876D03*
Y1632884D03*
X1296697Y1627876D03*
X1291741D03*
X1303801D03*
X1291741Y1654796D03*
X1296697D03*
X1297771Y1649788D03*
X1290667D03*
X1303801Y1654796D03*
X1302727Y1649788D03*
X1297771Y1644796D03*
X1290667D03*
X1302727D03*
X1291741Y1659788D03*
X1296697D03*
X1303801D03*
X1306449Y92185D03*
X1306431Y152830D03*
X1310156Y292066D03*
X1305600Y1291759D03*
X1316606Y1314266D03*
Y1311159D03*
X1314006Y1314266D03*
Y1311159D03*
X1319206Y1314266D03*
Y1311159D03*
X1311406Y1314266D03*
Y1311159D03*
X1306799Y1315440D03*
X1315680Y1326622D03*
X1318110D03*
X1316606Y1317223D03*
X1319206D03*
X1318110Y1321022D03*
X1315680D03*
X1313250D03*
Y1326622D03*
X1318159Y1339037D03*
X1306079Y1340490D03*
X1314580Y1425240D03*
X1310580D03*
X1318580D03*
X1309386Y1485895D03*
X1311296Y1483295D03*
X1316076D03*
X1311296Y1488495D03*
X1316076D03*
X1309376Y1492995D03*
Y1498195D03*
X1308290Y1533380D03*
X1309423Y1543800D03*
Y1547420D03*
Y1551040D03*
X1309915Y1561731D03*
X1308757Y1622884D03*
X1315861D03*
X1309831Y1637876D03*
Y1632884D03*
X1314787Y1637876D03*
Y1632884D03*
X1308757Y1627876D03*
X1315861D03*
X1308757Y1654796D03*
X1309831Y1649788D03*
X1315861Y1654796D03*
X1314787Y1649788D03*
X1309831Y1644796D03*
X1314787D03*
X1308757Y1659788D03*
X1315861D03*
X1326199Y49379D03*
X1334156Y292066D03*
X1326094Y286948D03*
X1330277Y857388D03*
X1329477Y1222158D03*
X1331202Y1211488D03*
X1332680Y1291861D03*
X1330080D03*
X1333020Y1308621D03*
X1331770Y1311121D03*
X1333020Y1306021D03*
Y1303421D03*
X1330420Y1306021D03*
Y1303421D03*
Y1308621D03*
X1327696Y1314206D03*
X1321806Y1311159D03*
X1324306D03*
X1326750Y1311175D03*
X1327696Y1317163D03*
X1334580Y1425240D03*
X1330580D03*
X1326580D03*
X1322580D03*
X1331396Y1492995D03*
X1322786Y1505295D03*
X1329486Y1495595D03*
X1331396Y1498195D03*
X1324696Y1502695D03*
X1329476D03*
X1324696Y1507895D03*
X1329476D03*
X1328913Y1583797D03*
X1333638Y1583897D03*
X1324189Y1583797D03*
X1327921Y1622884D03*
X1320817D03*
X1332877D03*
X1321891Y1637876D03*
X1326847D03*
X1321891Y1632884D03*
X1326847D03*
X1333951Y1637876D03*
Y1632884D03*
X1327921Y1627876D03*
X1320817D03*
X1332877D03*
X1320817Y1654796D03*
X1327921D03*
X1326847Y1649788D03*
X1321891D03*
X1332877Y1654796D03*
X1333951Y1649788D03*
X1326847Y1644796D03*
X1321891D03*
X1333951D03*
X1320817Y1659788D03*
X1327921D03*
X1332877D03*
X1348199Y49379D03*
X1351750Y72826D03*
X1339840Y72860D03*
X1342094Y286948D03*
X1339347Y857388D03*
X1337975Y1177999D03*
X1338142Y1181642D03*
X1338440Y1291949D03*
X1335670Y1291899D03*
X1346806Y1311359D03*
X1349406D03*
X1346806Y1314466D03*
X1349406D03*
X1344206Y1311359D03*
Y1314466D03*
X1339429Y1315570D03*
X1348480Y1326822D03*
X1349406Y1317423D03*
X1346050Y1321222D03*
Y1326822D03*
X1348480Y1321222D03*
X1338879Y1340690D03*
X1337221Y1338739D03*
X1346580Y1425240D03*
X1342580D03*
X1338580D03*
X1336176Y1492995D03*
X1338096Y1483295D03*
X1342876D03*
X1336186Y1485895D03*
X1338096Y1488495D03*
X1342876D03*
X1349586Y1505295D03*
X1336176Y1498195D03*
X1343087Y1583897D03*
X1347811D03*
X1338362Y1583697D03*
X1339981Y1622884D03*
X1344937D03*
X1338907Y1637876D03*
Y1632884D03*
X1346011Y1637876D03*
Y1632884D03*
X1339981Y1627876D03*
X1344937D03*
X1339981Y1654796D03*
X1338907Y1649788D03*
X1344937Y1654796D03*
X1346011Y1649788D03*
X1338907Y1644796D03*
X1346011D03*
X1339981Y1659788D03*
X1344937D03*
X1361550Y67264D03*
X1350156Y292066D03*
X1358094Y286948D03*
X1354257Y675765D03*
X1364490Y1293694D03*
X1361830Y1291809D03*
X1360496Y1314406D03*
X1363220Y1308821D03*
X1364570Y1311321D03*
X1363220Y1306221D03*
Y1303621D03*
X1359550Y1311375D03*
X1352006Y1311359D03*
X1357106D03*
X1354606D03*
X1352006Y1314466D03*
X1360496Y1317363D03*
X1350910Y1326822D03*
X1352006Y1317423D03*
X1350910Y1321222D03*
X1350959Y1339237D03*
X1362580Y1425240D03*
X1358580D03*
X1354580D03*
X1350580D03*
X1362986Y1485895D03*
X1364896Y1483295D03*
Y1488495D03*
X1358196Y1492995D03*
X1362976D03*
X1356286Y1495595D03*
X1358196Y1498195D03*
X1362976D03*
X1356276Y1502695D03*
X1351496D03*
X1356276Y1507895D03*
X1351496D03*
X1357260Y1583797D03*
X1361985Y1583897D03*
X1352536Y1583697D03*
X1352041Y1622884D03*
X1356997D03*
X1364101D03*
X1350967Y1637876D03*
Y1632884D03*
X1358071Y1637876D03*
Y1632884D03*
X1363027Y1637876D03*
Y1632884D03*
X1356997Y1627876D03*
X1352041D03*
X1364101D03*
X1352041Y1654796D03*
X1356997D03*
X1358071Y1649788D03*
X1350967D03*
X1364101Y1654796D03*
X1363027Y1649788D03*
X1358071Y1644796D03*
X1350967D03*
X1363027D03*
X1352041Y1659788D03*
X1356997D03*
X1364101D03*
X1370199Y49379D03*
X1371259Y98000D03*
X1366156Y292066D03*
X1377862Y485552D03*
Y511052D03*
X1368305Y1307340D03*
X1365820Y1308821D03*
X1368305Y1309840D03*
X1365820Y1306221D03*
Y1303621D03*
X1372149Y1334890D03*
X1379388Y1330690D03*
Y1333797D03*
X1378632Y1340553D03*
X1376788Y1330690D03*
Y1333797D03*
X1378632Y1346153D03*
X1371422Y1359024D03*
X1368922D03*
X1379101Y1418621D03*
X1368299Y1425240D03*
X1372164Y1423810D03*
X1375341Y1421268D03*
X1369676Y1483295D03*
Y1488495D03*
X1376386Y1505295D03*
X1378296Y1502695D03*
Y1507895D03*
X1376158Y1583897D03*
X1366709D03*
X1371434D03*
X1369057Y1622884D03*
X1376161D03*
X1370131Y1637876D03*
Y1632790D03*
X1375087Y1637876D03*
Y1632790D03*
X1369057Y1627876D03*
X1376161D03*
X1369057Y1654796D03*
X1370131Y1649788D03*
X1376161Y1654796D03*
X1375087Y1649788D03*
X1370131Y1644796D03*
X1375087D03*
X1369057Y1659788D03*
X1376161D03*
X1392199Y49379D03*
X1389688Y1330690D03*
X1392132Y1330706D03*
X1393078Y1333737D03*
Y1336694D03*
X1383492Y1340553D03*
X1381062D03*
X1381988Y1336754D03*
X1384588D03*
X1387188Y1330690D03*
X1381988D03*
Y1333797D03*
X1384588Y1330690D03*
Y1333797D03*
X1383541Y1358568D03*
X1381062Y1346153D03*
X1383492D03*
X1383284Y1415973D03*
X1387308Y1413643D03*
X1392021Y1410360D03*
X1389786Y1485895D03*
X1391696Y1483295D03*
Y1488495D03*
X1384996Y1492995D03*
X1389776D03*
X1383086Y1495595D03*
X1384996Y1498195D03*
X1389776D03*
X1383076Y1502695D03*
Y1507895D03*
X1390331Y1583897D03*
X1380882Y1583697D03*
X1385606Y1583897D03*
X1381117Y1622884D03*
X1382191Y1637876D03*
X1387147D03*
X1382191Y1632884D03*
X1387147D03*
X1381117Y1627876D03*
Y1654796D03*
X1382191Y1649788D03*
X1387147D03*
X1382191Y1644796D03*
X1387147D03*
X1392068Y1667907D03*
X1381918D03*
X1381117Y1659788D03*
X1387620Y1721418D03*
X1385061D03*
X1403500Y458377D03*
X1402452Y642825D03*
X1405716Y1310618D03*
X1401740Y1311980D03*
X1399240D03*
X1408690Y1324803D03*
X1396302Y1328152D03*
Y1325552D03*
X1398902Y1328152D03*
Y1325552D03*
X1396302Y1322952D03*
X1398902D03*
X1401406Y1334918D03*
X1397652Y1330652D03*
X1398375Y1403688D03*
X1401764Y1399928D03*
X1405207Y1395480D03*
X1408543Y1391826D03*
X1395463Y1406918D03*
X1403186Y1485895D03*
X1405096Y1483295D03*
X1396476D03*
X1405096Y1488495D03*
X1396476D03*
X1409456Y1537872D03*
X1406074Y1581563D03*
X1395055Y1583797D03*
X1398058Y1619683D03*
X1409660Y1619853D03*
X1397367Y1639951D03*
X1402425Y1649532D03*
X1414199Y49379D03*
X1414000Y460362D03*
X1415426Y1042765D03*
Y1038765D03*
X1424561Y1305566D03*
X1420690Y1324803D03*
X1417690D03*
X1414690D03*
X1411690D03*
X1424163Y1373240D03*
X1411508Y1388384D03*
X1414950Y1384942D03*
X1417491Y1381183D03*
X1420774Y1377106D03*
X1409876Y1483295D03*
Y1488495D03*
X1423735Y1536715D03*
X1412572Y1556953D03*
X1421232Y1606126D03*
X1422914Y1601663D03*
X1421392Y1621706D03*
X1416357Y1644027D03*
X1420042Y1649716D03*
X1433817Y-34648D03*
Y-4648D03*
Y5352D03*
X1436199Y49379D03*
X1434513Y106950D03*
X1439232Y596291D03*
X1425437Y1308184D03*
X1426202Y1310752D03*
X1427314Y1313482D03*
X1428458Y1316481D03*
X1429517Y1319447D03*
X1430312Y1322412D03*
X1431106Y1325219D03*
X1426441Y1369427D03*
X1428559Y1365296D03*
X1430465Y1361060D03*
X1438798Y1495595D03*
X1430431Y1563595D03*
X1427931D03*
X1424971Y1566764D03*
Y1564264D03*
X1435584Y1596545D03*
X1430075Y1613904D03*
X1430319Y1623504D03*
X1425390Y1635496D03*
X1433327Y1643287D03*
X1446869Y105129D03*
X1451353Y116158D03*
X1443551Y539318D03*
Y535318D03*
X1453345Y1015473D03*
Y1019016D03*
Y1022559D03*
X1445498Y1485895D03*
X1447408Y1483295D03*
X1452188D03*
X1447408Y1488495D03*
X1452188D03*
X1445488Y1492995D03*
X1440708D03*
X1445488Y1498195D03*
X1440708D03*
X1444200Y1533240D03*
X1445535Y1551040D03*
Y1547420D03*
Y1543800D03*
X1446027Y1561731D03*
X1445500Y1611500D03*
X1448500Y1601000D03*
X1442579Y1673303D03*
X1447579D03*
X1452579D03*
X1453950Y1681450D03*
X1458199Y49379D03*
X1459682Y450372D03*
X1468395Y487582D03*
X1464257Y552977D03*
Y564977D03*
X1468257Y696265D03*
X1460926Y1015473D03*
X1467926D03*
X1460926Y1019016D03*
Y1022559D03*
X1467926Y1019016D03*
Y1022559D03*
X1467508Y1492995D03*
X1458898Y1505295D03*
X1465598Y1495595D03*
X1467508Y1498195D03*
X1460808Y1502695D03*
X1465588D03*
X1460808Y1507895D03*
X1465588D03*
X1465025Y1583797D03*
X1460301D03*
X1464391Y1622884D03*
X1459435D03*
X1465465Y1637876D03*
Y1632884D03*
X1459435Y1627876D03*
X1464391D03*
Y1654796D03*
X1465465Y1649788D03*
Y1644796D03*
X1459435Y1654796D03*
X1464391Y1659788D03*
X1466500Y1666000D03*
X1469034Y1667794D03*
X1459435Y1659788D03*
X1456852Y1673320D03*
X1466599Y1679401D03*
X1466260Y1675155D03*
X1460457Y1685160D03*
X1480199Y49379D03*
X1483820Y122713D03*
X1482257Y552977D03*
Y560477D03*
Y567977D03*
X1481934Y699670D03*
X1480300Y697750D03*
X1472288Y1492995D03*
X1474208Y1483295D03*
X1478988D03*
X1472298Y1485895D03*
X1474208Y1488495D03*
X1478988D03*
X1472288Y1498195D03*
X1479199Y1583897D03*
X1483923D03*
X1469750D03*
X1474474Y1583697D03*
X1476451Y1622884D03*
X1471495D03*
X1483555D03*
X1470421Y1632884D03*
Y1637876D03*
X1482481D03*
X1477525D03*
X1482481Y1632884D03*
X1477525D03*
X1471495Y1627876D03*
X1483555D03*
X1476451D03*
X1471495Y1654796D03*
X1470421Y1649788D03*
X1476451Y1654796D03*
X1483555D03*
X1482481Y1649788D03*
X1477525D03*
X1470421Y1644796D03*
X1477525D03*
X1482481D03*
X1471495Y1659788D03*
X1476451D03*
X1483555D03*
X1471616Y1670098D03*
X1479375Y1685984D03*
X1495539Y131237D03*
X1492237Y123842D03*
X1489757Y552977D03*
X1497257D03*
Y560477D03*
X1489757Y567977D03*
X1497257D03*
X1494371Y594462D03*
X1492673Y828513D03*
X1494386Y1178743D03*
X1499098Y1485895D03*
X1494308Y1492995D03*
X1499088D03*
X1492398Y1495595D03*
X1485698Y1505295D03*
X1494308Y1498195D03*
X1499088D03*
X1492388Y1502695D03*
X1487608D03*
X1492388Y1507895D03*
X1487608D03*
X1493372Y1583797D03*
X1498097Y1583897D03*
X1488648Y1583697D03*
X1488511Y1622884D03*
X1495615D03*
X1494541Y1637876D03*
X1489585D03*
X1494541Y1632884D03*
X1489585D03*
X1488511Y1627876D03*
X1495615D03*
X1488511Y1654796D03*
X1495615D03*
X1489585Y1649788D03*
X1494541D03*
X1489585Y1644796D03*
X1494541D03*
X1488511Y1659788D03*
X1495615D03*
X1502199Y49379D03*
X1514576Y219730D03*
X1513348Y253954D03*
X1500757Y537438D03*
X1504757Y537378D03*
X1508757Y537456D03*
X1512757Y537477D03*
X1513382Y697750D03*
X1499243Y803513D03*
X1501730Y811872D03*
X1501338Y825147D03*
X1513470Y1178265D03*
X1504470D03*
X1505788Y1483295D03*
X1501008D03*
X1505788Y1488495D03*
X1501008D03*
X1512498Y1505295D03*
X1512270Y1583897D03*
X1502821D03*
X1507546D03*
X1500571Y1622884D03*
X1512631D03*
X1507675D03*
X1501645Y1637876D03*
Y1632884D03*
X1506601Y1637876D03*
Y1632884D03*
X1513705Y1637876D03*
Y1632884D03*
X1500571Y1627876D03*
X1512631D03*
X1507675D03*
X1500571Y1654796D03*
X1501645Y1649788D03*
X1507675Y1654796D03*
X1512631D03*
X1513705Y1649788D03*
X1506601D03*
X1501645Y1644796D03*
X1513705D03*
X1506601D03*
X1500571Y1659788D03*
X1507675D03*
X1512831Y1659588D03*
X1524124Y47570D03*
X1522917Y119912D03*
X1529384Y201245D03*
X1516452Y249724D03*
X1514900Y251839D03*
X1515016Y699670D03*
X1515192Y814294D03*
X1525898Y1485895D03*
X1527808Y1483295D03*
Y1488495D03*
X1521108Y1492995D03*
X1525888D03*
X1525898Y1505295D03*
X1519198Y1495595D03*
X1521108Y1498195D03*
X1525888D03*
X1519188Y1502695D03*
X1527808D03*
X1514408D03*
X1519188Y1507895D03*
X1514408D03*
X1526443Y1583897D03*
X1516994Y1583697D03*
X1521718Y1583897D03*
X1524691Y1622884D03*
X1519735D03*
X1518661Y1637876D03*
Y1632884D03*
X1525765Y1637876D03*
Y1632884D03*
X1519735Y1627876D03*
X1524691D03*
X1518661Y1649788D03*
X1524691Y1654796D03*
X1519735D03*
X1525765Y1649788D03*
X1518661Y1644796D03*
X1525765D03*
X1524991Y1659788D03*
X1519735D03*
X1530064Y-27930D03*
X1530049Y-30445D03*
X1533317Y-27916D03*
X1536342Y-29236D03*
X1533302Y-30431D03*
X1530048Y-20028D03*
X1530063Y-17513D03*
X1530018Y-25058D03*
X1530033Y-22543D03*
X1533301Y-20014D03*
X1533316Y-17499D03*
X1536341Y-18819D03*
X1543862Y75343D03*
X1539756Y71839D03*
X1534776D03*
X1539756Y66847D03*
X1534776D03*
X1532866Y69340D03*
X1536542Y300819D03*
Y304819D03*
X1539693Y535212D03*
X1542902Y543641D03*
X1540850Y1240863D03*
X1539298Y1485895D03*
X1541208Y1483295D03*
X1532588D03*
X1541208Y1488495D03*
X1532588D03*
X1542186Y1581563D03*
X1531167Y1583797D03*
X1536751Y1622884D03*
X1531795D03*
X1530721Y1637876D03*
Y1632884D03*
X1537825Y1637876D03*
X1542781D03*
X1537825Y1632790D03*
X1542781D03*
X1531795Y1627876D03*
X1536751D03*
X1531795Y1654796D03*
X1530721Y1649788D03*
X1536751Y1654796D03*
X1542781Y1649788D03*
X1537825D03*
X1530721Y1644796D03*
X1542781D03*
X1537825D03*
X1531795Y1659788D03*
X1536751D03*
X1550965Y3001D03*
X1555568Y17045D03*
Y22037D03*
X1553601Y19541D03*
X1555452Y25977D03*
X1553452Y23981D03*
X1548496D03*
X1546496Y25977D03*
X1554520Y37106D03*
X1547434D03*
X1554520Y48720D03*
X1547434D03*
X1556776Y71839D03*
X1550756Y72850D03*
X1545776D03*
X1554866Y69340D03*
X1556776Y66847D03*
X1550756Y77842D03*
X1545776D03*
X1552981Y220826D03*
X1555481Y218326D03*
X1553913Y298119D03*
X1558480Y302678D03*
X1545960Y565162D03*
X1551887Y606938D03*
X1555570Y1235968D03*
X1555367Y1248078D03*
X1555303Y1242557D03*
X1547062Y1258468D03*
X1553811Y1264488D03*
X1545988Y1483295D03*
Y1488495D03*
X1548684Y1556953D03*
X1555993Y1563595D03*
X1558493D03*
X1548811Y1622884D03*
X1543855D03*
X1555915D03*
X1549885Y1637876D03*
X1554841D03*
X1549885Y1632884D03*
X1554841D03*
X1543855Y1627876D03*
X1548811D03*
X1555915D03*
X1543855Y1654796D03*
X1555915D03*
X1548811D03*
X1554841Y1649788D03*
X1549885D03*
X1554841Y1644796D03*
X1549885D03*
X1543855Y1659788D03*
X1555915D03*
X1548811D03*
X1572965Y3001D03*
X1569742Y17045D03*
X1560548D03*
X1567774Y19541D03*
X1569742Y22037D03*
X1560548D03*
X1562669Y23981D03*
X1567625D03*
X1560669Y25977D03*
X1569625D03*
X1562557Y19541D03*
X1561607Y37106D03*
X1568693D03*
Y48720D03*
X1561607D03*
X1572756Y72847D03*
X1561756Y71839D03*
X1565866Y75340D03*
X1567776Y72847D03*
X1561756Y66847D03*
X1572756Y77839D03*
X1567776D03*
X1564517Y299432D03*
X1569592Y294816D03*
X1572283Y301816D03*
X1562995Y789522D03*
X1569518Y806684D03*
X1564267Y1253158D03*
X1573560Y1485895D03*
X1573550Y1492995D03*
X1568770D03*
X1566860Y1495595D03*
X1573550Y1498195D03*
X1568770D03*
X1572230Y1533000D03*
X1573597Y1543800D03*
Y1547420D03*
Y1551040D03*
X1564839Y1554561D03*
X1560871Y1622884D03*
X1572931D03*
X1567975D03*
X1561945Y1637876D03*
Y1632884D03*
X1566901Y1637876D03*
Y1632884D03*
X1560871Y1627876D03*
X1572931D03*
X1567975D03*
X1560871Y1654796D03*
X1561945Y1649788D03*
X1567975Y1654796D03*
X1572931D03*
X1566901Y1649788D03*
X1561945Y1644796D03*
X1566901D03*
X1560871Y1659788D03*
X1567975D03*
X1572931D03*
X1583915Y17045D03*
X1574722D03*
X1581947Y19541D03*
X1583915Y22037D03*
X1576730Y19541D03*
X1574722Y22037D03*
X1576842Y23981D03*
X1581798D03*
X1574842Y25977D03*
X1583798D03*
X1575780Y37106D03*
X1582867D03*
Y48720D03*
X1575780D03*
X1587866Y75340D03*
X1578776Y71839D03*
X1583756D03*
X1576866Y69340D03*
X1578776Y66847D03*
X1583756D03*
X1574546Y251294D03*
X1575370Y1252770D03*
X1581327Y1252858D03*
X1586835Y1271918D03*
X1583007Y1288958D03*
X1577913Y1341623D03*
X1575504Y1356103D03*
X1578336D03*
X1575470Y1483295D03*
X1580250D03*
X1575470Y1488495D03*
X1580250D03*
X1586960Y1505295D03*
X1574089Y1561731D03*
X1588363Y1583797D03*
X1584991Y1622884D03*
X1580035D03*
X1574005Y1637876D03*
Y1632884D03*
X1578961Y1637876D03*
Y1632884D03*
X1586065Y1637876D03*
Y1632884D03*
X1580035Y1627876D03*
X1584991D03*
X1574005Y1649788D03*
X1580035Y1654796D03*
X1578961Y1649788D03*
X1584991Y1654796D03*
X1586065Y1649788D03*
X1574005Y1644796D03*
X1578961D03*
X1586065D03*
X1580035Y1659788D03*
X1584991D03*
X1594965Y3001D03*
X1603072Y17045D03*
X1598092D03*
X1588895D03*
X1603072Y22037D03*
X1598092D03*
X1596121Y19541D03*
X1590903D03*
X1588895Y22037D03*
X1595972Y23981D03*
X1591016D03*
X1589016Y25977D03*
X1597972D03*
X1589953Y37106D03*
X1597040D03*
Y48720D03*
X1589953D03*
X1589776Y72847D03*
X1594756D03*
X1600776Y71842D03*
X1598866Y69343D03*
X1600776Y66850D03*
X1589776Y77839D03*
X1594756D03*
X1597562Y555463D03*
X1595036D03*
X1591962D03*
X1589436D03*
X1589557Y1252778D03*
X1590097Y1246768D03*
X1603507Y1306262D03*
X1601772Y1337293D03*
X1601959Y1351773D03*
X1599139Y1400464D03*
X1595570Y1492995D03*
X1600350D03*
X1602270Y1483295D03*
X1600360Y1485895D03*
X1602270Y1488495D03*
X1593660Y1495595D03*
X1595570Y1498195D03*
X1600350D03*
X1588870Y1502695D03*
X1593650D03*
X1588870Y1507895D03*
X1593650D03*
X1593087Y1583797D03*
X1597812Y1583897D03*
X1602536Y1583697D03*
X1597051Y1622884D03*
X1592095D03*
X1591021Y1637876D03*
Y1632884D03*
X1598125Y1637876D03*
X1603081D03*
X1598125Y1632884D03*
X1603081D03*
X1592095Y1627876D03*
X1597051D03*
X1592095Y1654796D03*
X1591021Y1649788D03*
X1597051Y1654796D03*
X1603081Y1649788D03*
X1598125D03*
X1591021Y1644796D03*
X1603081D03*
X1598125D03*
X1592095Y1659788D03*
X1597051D03*
X1616965Y3001D03*
X1605077Y19541D03*
X1604127Y37106D03*
Y48720D03*
X1609866Y75340D03*
X1611776Y72847D03*
X1616756D03*
X1605756Y71842D03*
Y66850D03*
X1611776Y77839D03*
X1616756D03*
X1608640Y640660D03*
X1607050Y1483295D03*
Y1488495D03*
X1613760Y1505295D03*
X1615670Y1502695D03*
Y1507895D03*
X1607261Y1583897D03*
X1611985D03*
X1616710Y1583697D03*
X1609111Y1622884D03*
X1604155D03*
X1616215D03*
X1610185Y1637876D03*
X1615141D03*
X1610185Y1632884D03*
X1615141D03*
X1604155Y1627876D03*
X1609111D03*
X1616215D03*
X1604155Y1654796D03*
X1616215D03*
X1609111D03*
X1615141Y1649788D03*
X1610185D03*
X1615141Y1644796D03*
X1610185D03*
X1604155Y1659788D03*
X1616215D03*
X1609111D03*
X1631987Y19541D03*
X1626882Y23981D03*
X1631838D03*
X1624882Y25977D03*
X1632906Y37106D03*
X1625819D03*
X1632906Y48720D03*
X1625819D03*
X1629662Y69343D03*
X1633070Y75340D03*
X1627756Y71842D03*
X1622776D03*
X1627756Y66850D03*
X1622776D03*
X1620862Y69343D03*
X1627410Y172008D03*
X1632500Y381500D03*
X1630927Y398002D03*
X1628046Y756765D03*
Y760265D03*
Y767265D03*
X1623496Y776910D03*
Y783603D03*
X1627896Y795315D03*
X1623496Y807028D03*
Y813721D03*
Y820414D03*
X1627896Y832126D03*
X1623496Y843839D03*
Y850532D03*
Y857225D03*
X1627896Y868937D03*
X1623496Y880650D03*
Y887343D03*
Y894036D03*
X1627896Y905749D03*
X1623496Y917461D03*
Y924154D03*
Y930847D03*
X1627896Y942560D03*
X1623496Y954272D03*
Y960965D03*
Y967658D03*
Y974351D03*
Y981044D03*
Y987736D03*
Y994429D03*
Y1004469D03*
Y1034587D03*
Y1041280D03*
Y1047973D03*
Y1054666D03*
Y1061359D03*
Y1071398D03*
X1627896Y1089804D03*
X1623496Y1078091D03*
Y1101516D03*
Y1108209D03*
Y1114902D03*
X1627896Y1126615D03*
X1623496Y1138327D03*
Y1145020D03*
X1627896Y1163426D03*
X1623496Y1151713D03*
Y1175138D03*
Y1181831D03*
Y1188524D03*
X1627896Y1200237D03*
X1623496Y1211949D03*
Y1218642D03*
X1627896Y1237048D03*
X1623496Y1225335D03*
Y1248760D03*
Y1255453D03*
X1627052Y1424716D03*
X1627160Y1485895D03*
X1629070Y1483295D03*
Y1488495D03*
X1622370Y1492995D03*
X1627150D03*
X1620460Y1495595D03*
X1622370Y1498195D03*
X1627150D03*
X1620450Y1502695D03*
Y1507895D03*
X1621434Y1583797D03*
X1626159Y1583897D03*
X1630883D03*
X1621171Y1622884D03*
X1628275D03*
X1622245Y1637876D03*
Y1632884D03*
X1627201Y1637876D03*
Y1632884D03*
X1621171Y1627876D03*
X1628275D03*
X1621171Y1654796D03*
X1622245Y1649788D03*
X1628275Y1654796D03*
X1627201Y1649788D03*
X1622245Y1644796D03*
X1627201D03*
X1621171Y1659788D03*
X1628275D03*
X1638965Y3001D03*
X1648128Y17045D03*
X1633954D03*
X1638934D03*
X1648128Y22037D03*
X1648011Y25977D03*
X1633954Y22037D03*
X1638934D03*
X1646160Y19541D03*
X1640943D03*
X1641055Y23981D03*
X1646011D03*
X1639055Y25977D03*
X1633838D03*
X1647079Y37106D03*
X1639993D03*
X1647079Y48720D03*
X1639993D03*
X1634980Y72847D03*
X1639960D03*
X1645980Y71839D03*
X1644070Y69340D03*
X1645980Y66847D03*
X1634980Y77839D03*
X1639960D03*
X1642240Y399603D03*
X1642135Y414202D03*
X1639800Y426982D03*
X1636800D03*
X1639800Y429982D03*
X1636800D03*
X1639800Y432982D03*
X1636800D03*
X1647110Y434177D03*
X1639800Y435982D03*
X1636800D03*
X1639800Y438982D03*
X1636800D03*
X1635088Y756765D03*
Y763765D03*
X1639638Y773563D03*
X1644038Y791969D03*
X1634188Y786949D03*
X1639638Y780256D03*
X1634188Y796988D03*
X1639638Y803681D03*
Y810374D03*
Y817067D03*
X1644038Y828780D03*
X1634188Y823760D03*
Y833799D03*
X1639638Y840492D03*
Y847185D03*
X1644038Y865591D03*
X1634188Y860571D03*
X1639638Y853878D03*
X1634188Y870610D03*
X1639638Y877303D03*
Y883996D03*
Y890689D03*
X1644038Y902402D03*
X1634188Y897382D03*
Y907422D03*
X1639638Y914114D03*
Y920807D03*
X1644038Y939213D03*
X1634188Y934193D03*
X1639638Y927500D03*
X1634188Y944233D03*
X1639638Y950925D03*
Y957618D03*
Y964311D03*
Y971004D03*
Y977697D03*
Y984390D03*
Y991083D03*
Y997776D03*
Y1004469D03*
Y1031240D03*
Y1037933D03*
Y1044626D03*
Y1051319D03*
Y1058012D03*
Y1068051D03*
Y1074744D03*
X1644038Y1086457D03*
X1634188Y1081437D03*
Y1091477D03*
X1639638Y1098170D03*
Y1104862D03*
X1634188Y1118248D03*
X1639638Y1111555D03*
X1644038Y1123268D03*
X1634188Y1128288D03*
X1639638Y1134981D03*
Y1141674D03*
Y1148366D03*
X1644038Y1160079D03*
X1634188Y1155059D03*
Y1165099D03*
X1639638Y1171792D03*
Y1178485D03*
X1634188Y1191870D03*
X1639638Y1185177D03*
X1644038Y1196890D03*
X1634188Y1201910D03*
X1639638Y1208603D03*
Y1215296D03*
Y1221988D03*
X1644038Y1233701D03*
X1634188Y1228681D03*
Y1238721D03*
X1639638Y1245414D03*
Y1252107D03*
X1641904Y1351467D03*
Y1348567D03*
X1633850Y1483295D03*
Y1488495D03*
X1647260Y1495595D03*
X1640560Y1505295D03*
X1647250Y1502695D03*
X1642470D03*
X1647250Y1507895D03*
X1642470D03*
X1640332Y1583897D03*
X1645056Y1583697D03*
X1635608Y1583897D03*
X1633231Y1622884D03*
X1645291D03*
X1640335D03*
X1634305Y1637876D03*
Y1632790D03*
X1639261Y1637876D03*
Y1632790D03*
X1646365Y1637876D03*
Y1632884D03*
X1633231Y1627876D03*
X1640335D03*
X1645291D03*
X1633231Y1654796D03*
X1634305Y1649788D03*
X1640335Y1654796D03*
X1639261Y1649788D03*
X1645291Y1654796D03*
X1646365Y1649788D03*
X1634305Y1644796D03*
X1639261D03*
X1646365D03*
X1633231Y1659788D03*
X1640335D03*
X1645291D03*
X1647700Y1674228D03*
X1648013Y1713684D03*
Y1728834D03*
X1660965Y3001D03*
X1653108Y17045D03*
X1655116Y19541D03*
X1653108Y22037D03*
X1654166Y37106D03*
Y48720D03*
X1650960Y66847D03*
X1655066Y75343D03*
X1662065Y72850D03*
X1656980D03*
X1650960Y71839D03*
X1662065Y77842D03*
X1656980D03*
X1652610Y394727D03*
X1659610D03*
X1652810Y407402D03*
X1661110Y434177D03*
X1657747Y756765D03*
Y760265D03*
Y767265D03*
X1653197Y776910D03*
Y783603D03*
X1657597Y795315D03*
X1653197Y807028D03*
Y813721D03*
Y820414D03*
X1657597Y832126D03*
X1653197Y843839D03*
Y850532D03*
Y857225D03*
X1657597Y868937D03*
X1653197Y880650D03*
Y887343D03*
Y894036D03*
X1657597Y905749D03*
X1653197Y917461D03*
Y924154D03*
Y930847D03*
X1657597Y942560D03*
X1653197Y954272D03*
Y960965D03*
Y967658D03*
Y974351D03*
Y981044D03*
Y987736D03*
Y994429D03*
Y1004469D03*
Y1034587D03*
Y1041280D03*
Y1047973D03*
Y1054666D03*
Y1061359D03*
Y1071398D03*
X1657597Y1089804D03*
X1653197Y1078091D03*
Y1101516D03*
Y1108209D03*
Y1114902D03*
X1657597Y1126615D03*
X1653197Y1138327D03*
Y1145020D03*
X1657597Y1163426D03*
X1653197Y1151713D03*
Y1175138D03*
Y1188524D03*
Y1181831D03*
X1657597Y1200237D03*
X1653197Y1211949D03*
Y1218642D03*
X1657597Y1237048D03*
X1653197Y1225335D03*
Y1248760D03*
Y1255453D03*
X1660594Y1298735D03*
X1651187D03*
X1660594Y1303935D03*
Y1306535D03*
Y1301335D03*
X1651187Y1303935D03*
Y1306535D03*
Y1301335D03*
X1650177Y1351467D03*
Y1348567D03*
X1658904Y1351467D03*
Y1348567D03*
X1662010Y1384570D03*
X1662766Y1377814D03*
X1660166D03*
X1662766Y1374707D03*
X1660166D03*
X1651301Y1378765D03*
X1662010Y1390170D03*
X1654774Y1402619D03*
X1648857Y1403424D03*
X1662465Y1444358D03*
X1653960Y1485895D03*
X1655870Y1483295D03*
X1660650D03*
X1655870Y1488495D03*
X1660650D03*
X1649170Y1492995D03*
X1653950D03*
X1649170Y1498195D03*
X1653950D03*
X1654505Y1583897D03*
X1659229Y1583797D03*
X1649780Y1583897D03*
X1651321Y1637876D03*
Y1632884D03*
Y1649788D03*
Y1644796D03*
X1653464Y1668416D03*
X1661101Y1671631D03*
X1651101Y1700478D03*
X1660541Y1704237D03*
X1677972Y25977D03*
X1676121Y19541D03*
X1675972Y23981D03*
X1671016D03*
X1669016Y25977D03*
X1677040Y37106D03*
X1669953D03*
X1677040Y48720D03*
X1669953D03*
X1677204Y75340D03*
X1672960Y71839D03*
X1667980Y66847D03*
X1672960D03*
X1667980Y71839D03*
X1666070Y69340D03*
X1663610Y394727D03*
X1664789Y756765D03*
Y763765D03*
X1669339Y773563D03*
X1673739Y791969D03*
X1663889Y786949D03*
X1669339Y780256D03*
X1663889Y796988D03*
X1669339Y803681D03*
Y810374D03*
Y817067D03*
X1673739Y828780D03*
X1663889Y823760D03*
Y833799D03*
X1669339Y840492D03*
Y847185D03*
X1673739Y865591D03*
X1663889Y860571D03*
X1669339Y853878D03*
X1663889Y870610D03*
X1669339Y877303D03*
Y883996D03*
Y890689D03*
X1673739Y902402D03*
X1663889Y897382D03*
Y907422D03*
X1669339Y914114D03*
Y920807D03*
X1673739Y939213D03*
X1663889Y934193D03*
X1669339Y927500D03*
X1663889Y944233D03*
X1669339Y950925D03*
Y957618D03*
Y964311D03*
Y971004D03*
Y977697D03*
Y984390D03*
Y991083D03*
Y997776D03*
Y1004469D03*
Y1031240D03*
Y1037933D03*
Y1044626D03*
Y1051319D03*
Y1058012D03*
Y1068051D03*
Y1074744D03*
X1673739Y1086457D03*
X1663889Y1081437D03*
Y1091477D03*
X1669339Y1098170D03*
Y1104862D03*
X1663889Y1118248D03*
X1669339Y1111555D03*
X1673739Y1123268D03*
X1663889Y1128288D03*
X1669339Y1134981D03*
Y1141674D03*
Y1148366D03*
X1673739Y1160079D03*
X1663889Y1155059D03*
Y1165099D03*
X1669339Y1171792D03*
Y1178485D03*
X1663889Y1191870D03*
X1669339Y1185177D03*
X1673739Y1196890D03*
X1663889Y1201910D03*
X1669339Y1208603D03*
Y1215296D03*
Y1221988D03*
X1673739Y1233701D03*
X1663889Y1228681D03*
Y1238721D03*
X1669339Y1245414D03*
Y1252107D03*
X1675187Y1298735D03*
Y1303935D03*
Y1306535D03*
Y1301335D03*
X1674831Y1351266D03*
Y1348366D03*
X1675901Y1377594D03*
Y1380551D03*
X1666870Y1384570D03*
X1664440D03*
X1675510Y1374723D03*
X1667966Y1374707D03*
X1670566D03*
X1665366Y1377814D03*
Y1380771D03*
Y1374707D03*
X1667966Y1377814D03*
Y1380771D03*
X1673066Y1374707D03*
X1666870Y1390170D03*
X1664440D03*
X1666919Y1402585D03*
X1671067Y1405418D03*
X1672277Y1407694D03*
X1674777D03*
X1672907Y1429928D03*
X1672273Y1420567D03*
X1666290Y1444391D03*
X1667360Y1485895D03*
X1669270Y1483295D03*
X1674050D03*
X1669270Y1488495D03*
X1674050D03*
X1673674Y1563575D03*
X1670248Y1581563D03*
X1670534Y1670149D03*
X1673245Y1673475D03*
X1664256Y1690794D03*
X1673132Y1690741D03*
X1665520Y1716877D03*
Y1732027D03*
X1682965Y3001D03*
X1692262Y17045D03*
X1678088D03*
X1683068D03*
X1692262Y22037D03*
X1692145Y25977D03*
X1678088Y22037D03*
X1683068D03*
X1690294Y19541D03*
X1685077D03*
X1690145Y23981D03*
X1685189D03*
X1683189Y25977D03*
X1684127Y37106D03*
X1691213D03*
Y48720D03*
X1684127D03*
X1679114Y72847D03*
X1688200Y69343D03*
X1690114Y66850D03*
Y71842D03*
X1684094Y72847D03*
X1679114Y77839D03*
X1684094D03*
X1687448Y756765D03*
Y760265D03*
X1682898Y776910D03*
X1687448Y767265D03*
X1682898Y783603D03*
X1687298Y795315D03*
X1682898Y807028D03*
Y820414D03*
Y813721D03*
X1687298Y832126D03*
X1682898Y850532D03*
Y843839D03*
Y857225D03*
X1687298Y868937D03*
X1682898Y880650D03*
Y894036D03*
Y887343D03*
X1687298Y905749D03*
X1682898Y917461D03*
Y924154D03*
Y930847D03*
X1687298Y942560D03*
X1682898Y954272D03*
Y967658D03*
Y960965D03*
Y981044D03*
Y974351D03*
Y994429D03*
Y987736D03*
Y1004469D03*
Y1041280D03*
Y1034587D03*
Y1054666D03*
Y1047973D03*
Y1061359D03*
Y1071398D03*
Y1078091D03*
X1687298Y1089804D03*
X1682898Y1101516D03*
Y1108209D03*
Y1114902D03*
X1687298Y1126615D03*
X1682898Y1138327D03*
Y1145020D03*
Y1151713D03*
X1687298Y1163426D03*
X1682898Y1175138D03*
Y1188524D03*
Y1181831D03*
X1687298Y1200237D03*
X1682898Y1211949D03*
Y1218642D03*
Y1225335D03*
X1687298Y1237048D03*
X1682898Y1248760D03*
Y1255453D03*
X1684708Y1298435D03*
Y1303635D03*
Y1306235D03*
Y1301035D03*
X1687233Y1351320D03*
X1679133Y1351420D03*
X1687233Y1348420D03*
X1679133Y1348520D03*
X1679180Y1372169D03*
X1681780D03*
X1679180Y1366969D03*
X1681780D03*
Y1369569D03*
X1679180D03*
X1683896Y1378765D03*
X1692948Y1377914D03*
Y1374807D03*
X1680530Y1374669D03*
X1685963Y1402187D03*
X1687621Y1404138D03*
X1684172Y1538135D03*
X1682561Y1552726D03*
X1691226Y1563526D03*
X1680558Y1555690D03*
X1691226Y1559526D03*
X1682494Y1568271D03*
Y1575125D03*
X1680491Y1578089D03*
Y1571235D03*
X1689880Y1572067D03*
X1679420Y1683597D03*
X1683013Y1713684D03*
X1680519Y1726825D03*
X1689383Y1729187D03*
X1704965Y3001D03*
X1697242Y17045D03*
X1699250Y19541D03*
X1697242Y22037D03*
X1698300Y37106D03*
X1705381Y37108D03*
X1698300Y48720D03*
X1705386D03*
X1701114Y72847D03*
X1706094D03*
X1699204Y75340D03*
X1695094Y66850D03*
Y71842D03*
X1706094Y77839D03*
X1701114D03*
X1694490Y756765D03*
Y763765D03*
X1699040Y773563D03*
X1703440Y791969D03*
X1699040Y780256D03*
X1693590Y786949D03*
X1699040Y803681D03*
X1693590Y796988D03*
X1699040Y817067D03*
Y810374D03*
X1693590Y823760D03*
X1703440Y828780D03*
X1693590Y833799D03*
X1699040Y847185D03*
Y840492D03*
Y853878D03*
X1693590Y860571D03*
X1703440Y865591D03*
X1693590Y870610D03*
X1699040Y877303D03*
Y883996D03*
Y890689D03*
X1693590Y907422D03*
X1703440Y902402D03*
X1693590Y897382D03*
X1699040Y914114D03*
Y920807D03*
X1693590Y934193D03*
X1699040Y927500D03*
X1703440Y939213D03*
X1693590Y944233D03*
X1699040Y950925D03*
Y964311D03*
Y971004D03*
Y957618D03*
Y977697D03*
Y984390D03*
Y997776D03*
Y991083D03*
Y1004469D03*
Y1044626D03*
Y1037933D03*
Y1031240D03*
Y1058012D03*
Y1051319D03*
Y1074744D03*
Y1068051D03*
X1703440Y1086457D03*
X1693590Y1081437D03*
Y1091477D03*
X1699040Y1104862D03*
Y1098170D03*
Y1111555D03*
X1693590Y1118248D03*
X1699040Y1134981D03*
X1703440Y1123268D03*
X1693590Y1128288D03*
X1699040Y1141674D03*
Y1148366D03*
X1693590Y1155059D03*
Y1165099D03*
X1703440Y1160079D03*
X1699040Y1171792D03*
Y1178485D03*
X1693590Y1191870D03*
X1699040Y1185177D03*
X1693590Y1201910D03*
X1703440Y1196890D03*
X1699040Y1208603D03*
Y1221988D03*
Y1215296D03*
X1693590Y1228681D03*
Y1238721D03*
X1703440Y1233701D03*
X1699040Y1245414D03*
Y1252107D03*
X1699087Y1298435D03*
Y1303635D03*
Y1306235D03*
Y1301035D03*
X1695533Y1351320D03*
Y1348420D03*
X1694792Y1384670D03*
X1700748Y1377914D03*
Y1380871D03*
Y1374807D03*
X1703348D03*
X1705848D03*
X1698148Y1377914D03*
X1695548D03*
X1698148Y1380871D03*
X1695548Y1374807D03*
X1698148D03*
X1699652Y1384670D03*
X1697222D03*
X1699652Y1390270D03*
X1694792D03*
X1697222D03*
X1699701Y1402685D03*
X1700520Y1716877D03*
X1702777Y1723593D03*
X1695166Y1717606D03*
X1720148Y22910D03*
X1710886Y82208D03*
X1715550Y102923D03*
X1721400Y374462D03*
X1718241Y652105D03*
X1717149Y756765D03*
Y760265D03*
X1712599Y776910D03*
X1717149Y767265D03*
X1712599Y783603D03*
Y807028D03*
X1716999Y795315D03*
X1712599Y820414D03*
Y813721D03*
X1716999Y832126D03*
X1712599Y850532D03*
Y843839D03*
Y857225D03*
X1716999Y868937D03*
X1712599Y880650D03*
Y894036D03*
Y887343D03*
X1716999Y905749D03*
X1712599Y917461D03*
Y924154D03*
Y930847D03*
X1716999Y942560D03*
X1712599Y954272D03*
Y967658D03*
Y960965D03*
Y981044D03*
Y974351D03*
Y994429D03*
Y987736D03*
Y1004469D03*
Y1041280D03*
Y1034587D03*
Y1054666D03*
Y1047973D03*
Y1061359D03*
Y1071398D03*
Y1078091D03*
X1716999Y1089804D03*
X1712599Y1101516D03*
Y1108209D03*
Y1114902D03*
X1716999Y1126615D03*
X1712599Y1138327D03*
Y1145020D03*
Y1151713D03*
X1716999Y1163426D03*
X1712599Y1175138D03*
Y1188524D03*
Y1181831D03*
X1716999Y1200237D03*
X1712599Y1218642D03*
Y1211949D03*
Y1225335D03*
X1716999Y1237048D03*
X1712599Y1248760D03*
Y1255453D03*
X1721754Y1299488D03*
X1708754Y1298388D03*
X1721847Y1307298D03*
X1721754Y1304688D03*
X1708754Y1300988D03*
X1721754Y1302088D03*
X1708754Y1303588D03*
Y1306188D03*
X1718813Y1348450D03*
Y1351350D03*
X1709533Y1351520D03*
Y1348620D03*
X1711962Y1367069D03*
X1714562D03*
X1711962Y1369669D03*
X1714562D03*
X1719902Y1368509D03*
Y1365909D03*
Y1363409D03*
X1708678Y1380621D03*
Y1377664D03*
X1716267Y1375178D03*
X1713312Y1374769D03*
X1708292Y1374823D03*
X1720210Y1435330D03*
X1719893Y1594940D03*
Y1612940D03*
Y1599740D03*
Y1603040D03*
Y1606340D03*
Y1609640D03*
X1722133Y1725340D03*
X1727111Y-38849D03*
Y-28849D03*
X1726965Y3001D03*
X1732286Y28208D03*
X1728786D03*
X1725286D03*
X1727336Y57024D03*
X1726596Y61784D03*
X1729836Y57024D03*
X1726596Y64284D03*
X1726814Y102968D03*
X1733344Y134953D03*
X1736474D03*
X1730364Y177588D03*
X1725400Y372062D03*
X1737260Y368132D03*
X1732660Y372692D03*
X1725500Y383662D03*
X1723259Y653641D03*
X1726334Y670345D03*
X1724191Y756765D03*
Y763765D03*
X1728741Y773563D03*
X1733141Y791969D03*
X1723291Y786949D03*
X1728741Y780256D03*
Y803681D03*
X1723291Y796988D03*
X1728741Y817067D03*
Y810374D03*
X1733141Y828780D03*
X1723291Y823760D03*
Y833799D03*
X1728741Y847185D03*
Y840492D03*
Y853878D03*
X1733141Y865591D03*
X1723291Y860571D03*
Y870610D03*
X1728741Y877303D03*
Y883996D03*
Y890689D03*
X1723291Y907422D03*
X1733141Y902402D03*
X1723291Y897382D03*
X1728741Y914114D03*
Y920807D03*
X1723291Y934193D03*
X1728741Y927500D03*
X1733141Y939213D03*
X1723291Y944233D03*
X1728741Y950925D03*
Y964311D03*
Y971004D03*
Y957618D03*
Y977697D03*
Y984390D03*
Y997776D03*
Y991083D03*
Y1004469D03*
Y1044626D03*
Y1037933D03*
Y1031240D03*
Y1058012D03*
Y1051319D03*
Y1074744D03*
Y1068051D03*
X1733141Y1086457D03*
X1723291Y1081437D03*
Y1091477D03*
X1728741Y1104862D03*
Y1098170D03*
Y1111555D03*
X1723291Y1118248D03*
X1728741Y1134981D03*
X1733141Y1123268D03*
X1723291Y1128288D03*
X1728741Y1141674D03*
Y1148366D03*
X1723291Y1155059D03*
X1733141Y1160079D03*
X1723291Y1165099D03*
X1728741Y1171792D03*
Y1178485D03*
X1723291Y1191870D03*
X1728741Y1185177D03*
X1723291Y1201910D03*
X1733141Y1196890D03*
X1728741Y1208603D03*
Y1221988D03*
Y1215296D03*
X1733141Y1233701D03*
X1723291Y1228681D03*
Y1238721D03*
X1728741Y1245414D03*
Y1252107D03*
X1732624Y1299718D03*
X1732717Y1307528D03*
X1732624Y1302318D03*
Y1304918D03*
X1735202Y1368279D03*
Y1365679D03*
Y1363179D03*
X1723917Y1380518D03*
Y1377178D03*
X1737126Y1403838D03*
Y1401238D03*
X1722810Y1435330D03*
X1737541Y1543707D03*
X1734575Y1562068D03*
X1724323Y1676965D03*
X1748965Y3001D03*
X1752008Y25146D03*
X1748116Y37058D03*
X1745451Y119585D03*
X1747448Y121413D03*
X1750325Y179827D03*
X1750851Y216427D03*
X1748325D03*
X1752461Y255337D03*
Y252337D03*
X1742652Y671494D03*
X1746850Y756765D03*
Y760265D03*
X1742300Y776910D03*
X1746850Y767265D03*
X1742300Y783603D03*
X1746700Y795315D03*
X1742300Y807028D03*
Y820414D03*
Y813721D03*
X1746700Y832126D03*
X1742300Y850532D03*
Y843839D03*
Y857225D03*
X1746700Y868937D03*
X1742300Y880650D03*
Y894036D03*
Y887343D03*
X1746700Y905749D03*
X1742300Y917461D03*
Y924154D03*
Y930847D03*
X1746700Y942560D03*
X1742300Y954272D03*
Y960965D03*
Y967658D03*
Y981044D03*
Y974351D03*
Y994429D03*
Y987736D03*
Y1004469D03*
Y1041280D03*
Y1034587D03*
Y1054666D03*
Y1047973D03*
Y1061359D03*
Y1071398D03*
Y1078091D03*
X1746700Y1089804D03*
X1742300Y1101516D03*
Y1108209D03*
Y1114902D03*
X1746700Y1126615D03*
X1742300Y1138327D03*
Y1145020D03*
Y1151713D03*
X1746700Y1163426D03*
X1742300Y1175138D03*
Y1188524D03*
Y1181831D03*
X1746700Y1200237D03*
X1742300Y1218642D03*
Y1211949D03*
Y1225335D03*
X1746700Y1237048D03*
X1742300Y1248760D03*
Y1255453D03*
X1743072Y1432211D03*
X1743188Y1543871D03*
Y1547871D03*
X1740587Y1547946D03*
X1737738Y1548021D03*
X1740400Y1543682D03*
X1752364Y1556323D03*
Y1559430D03*
X1744564Y1556323D03*
Y1559430D03*
X1749764Y1556323D03*
Y1559430D03*
X1747164Y1556323D03*
Y1559430D03*
X1752564Y1562537D03*
X1751518Y1566186D03*
X1740079Y1559505D03*
X1740188Y1556371D03*
X1746558Y1566186D03*
X1749038D03*
X1749964Y1562537D03*
X1751518Y1571786D03*
X1746558D03*
X1749038D03*
X1739640Y1713383D03*
Y1728533D03*
X1762420Y17031D03*
X1763840Y37790D03*
X1753398Y48720D03*
X1760485D03*
X1759666Y57708D03*
X1764366Y57508D03*
X1758047Y68637D03*
X1758539Y87153D03*
Y83653D03*
X1758534Y79743D03*
X1765034Y80443D03*
X1766244Y93673D03*
X1766911Y179890D03*
X1752851Y179827D03*
X1757385Y179890D03*
X1764385D03*
X1759911D03*
X1757951Y216427D03*
X1755425D03*
X1762485Y216490D03*
X1765011D03*
X1758859Y251544D03*
Y248544D03*
X1766399Y251361D03*
Y248361D03*
X1753892Y756765D03*
Y763765D03*
X1758442Y773563D03*
X1762842Y791969D03*
X1752992Y786949D03*
X1758442Y780256D03*
Y803681D03*
X1752992Y796988D03*
X1758442Y817067D03*
Y810374D03*
X1752992Y823760D03*
Y833799D03*
X1762842Y828780D03*
X1758442Y847185D03*
Y840492D03*
X1752992Y860571D03*
X1758442Y853878D03*
X1762842Y865591D03*
X1752992Y870610D03*
X1758442Y877303D03*
Y883996D03*
Y890689D03*
X1752992Y907422D03*
Y897382D03*
X1762842Y902402D03*
X1758442Y914114D03*
Y920807D03*
X1752992Y934193D03*
X1758442Y927500D03*
X1762842Y939213D03*
X1752992Y944233D03*
X1758442Y950925D03*
Y964311D03*
Y971004D03*
Y957618D03*
Y977697D03*
Y984390D03*
Y997776D03*
Y991083D03*
Y1004469D03*
Y1044626D03*
Y1037933D03*
Y1031240D03*
Y1058012D03*
Y1051319D03*
Y1074744D03*
Y1068051D03*
X1752992Y1081437D03*
X1762842Y1086457D03*
X1752992Y1091477D03*
X1758442Y1104862D03*
Y1098170D03*
X1752992Y1118248D03*
X1758442Y1111555D03*
Y1134981D03*
X1752992Y1128288D03*
X1762842Y1123268D03*
X1758442Y1141674D03*
Y1148366D03*
X1752992Y1155059D03*
Y1165099D03*
X1762842Y1160079D03*
X1758442Y1171792D03*
Y1178485D03*
X1752992Y1191870D03*
X1758442Y1185177D03*
X1752992Y1201910D03*
X1762842Y1196890D03*
X1758442Y1208603D03*
Y1221988D03*
Y1215296D03*
X1752992Y1228681D03*
Y1238721D03*
X1762842Y1233701D03*
X1758442Y1245414D03*
Y1252107D03*
X1758238Y1556238D03*
X1761108Y1556339D03*
Y1559446D03*
X1761079Y1562605D03*
X1755038Y1556238D03*
X1765709Y1556050D03*
X1754479Y1585905D03*
X1754763Y1641665D03*
X1752864Y1716383D03*
X1770965Y3001D03*
X1772886Y37430D03*
X1768134Y80543D03*
X1771385Y179890D03*
X1773911D03*
X1778500Y183790D03*
X1769585Y215090D03*
X1772111D03*
X1776585D03*
X1779111D03*
X1778874Y253799D03*
Y256799D03*
X1770520Y364148D03*
Y368148D03*
X1771236Y557224D03*
X1776550Y756765D03*
Y760265D03*
X1772000Y776910D03*
X1776550Y767265D03*
X1772000Y783603D03*
Y807028D03*
X1776400Y795315D03*
X1772000Y813721D03*
Y820414D03*
X1776400Y832126D03*
X1772000Y850532D03*
Y843839D03*
Y857225D03*
X1776400Y868937D03*
X1772000Y880650D03*
Y894036D03*
Y887343D03*
X1776400Y905749D03*
X1772000Y917461D03*
Y924154D03*
Y930847D03*
X1776400Y942560D03*
X1772000Y954272D03*
Y967658D03*
Y960965D03*
Y981044D03*
Y974351D03*
Y994429D03*
Y987736D03*
Y1004469D03*
Y1041280D03*
Y1034587D03*
Y1047973D03*
Y1054666D03*
Y1061359D03*
Y1071398D03*
Y1078091D03*
X1776400Y1089804D03*
X1772000Y1101516D03*
Y1108209D03*
Y1114902D03*
X1776400Y1126615D03*
X1772000Y1138327D03*
Y1145020D03*
Y1151713D03*
X1776400Y1163426D03*
X1772000Y1175138D03*
Y1188524D03*
Y1181831D03*
X1776400Y1200237D03*
X1772000Y1218642D03*
Y1211949D03*
Y1225335D03*
X1776400Y1237048D03*
X1772000Y1248760D03*
Y1255453D03*
X1776188Y1543871D03*
Y1546871D03*
X1769188D03*
Y1543871D03*
X1768688Y1552871D03*
Y1549871D03*
X1772688Y1543871D03*
Y1546871D03*
X1776113Y1541172D03*
X1769113D03*
X1772613D03*
X1780307Y1559430D03*
Y1556323D03*
X1775979Y1556805D03*
Y1559805D03*
X1782301Y1566186D03*
X1768209Y1556000D03*
X1769826Y1562559D03*
X1782301Y1571786D03*
X1792965Y3001D03*
X1796781Y46686D03*
X1785144Y86973D03*
Y89973D03*
X1783448Y212957D03*
X1795794Y253719D03*
X1787534Y253769D03*
X1795794Y256719D03*
X1787534Y256769D03*
X1795479Y408056D03*
X1795468Y421334D03*
X1783592Y756765D03*
X1788142Y773563D03*
X1792542Y791969D03*
X1782692Y786949D03*
X1788142Y780256D03*
X1782692Y796988D03*
X1788142Y803681D03*
Y817067D03*
Y810374D03*
X1782692Y823760D03*
Y833799D03*
X1792542Y828780D03*
X1788142Y847185D03*
Y840492D03*
Y853878D03*
X1792542Y865591D03*
X1782692Y860571D03*
Y870610D03*
X1788142Y877303D03*
Y883996D03*
Y890689D03*
X1782692Y907422D03*
Y897382D03*
X1792542Y902402D03*
X1788142Y914114D03*
Y920807D03*
X1782692Y934193D03*
X1788142Y927500D03*
X1792542Y939213D03*
X1782692Y944233D03*
X1788142Y950925D03*
Y964311D03*
Y971004D03*
Y957618D03*
Y977697D03*
Y984390D03*
Y997776D03*
Y991083D03*
Y1004469D03*
Y1044626D03*
Y1037933D03*
Y1031240D03*
Y1058012D03*
Y1051319D03*
Y1074744D03*
Y1068051D03*
X1782692Y1081437D03*
X1792542Y1086457D03*
X1782692Y1091477D03*
X1788142Y1098170D03*
Y1104862D03*
X1782692Y1118248D03*
X1788142Y1111555D03*
Y1134981D03*
X1782692Y1128288D03*
X1792542Y1123268D03*
X1788142Y1141674D03*
Y1148366D03*
X1782692Y1155059D03*
Y1165099D03*
X1792542Y1160079D03*
X1788142Y1171792D03*
Y1178485D03*
X1782692Y1191870D03*
X1788142Y1185177D03*
X1782692Y1201910D03*
X1792542Y1196890D03*
X1788142Y1208603D03*
Y1221988D03*
Y1215296D03*
X1782692Y1228681D03*
Y1238721D03*
X1792542Y1233701D03*
X1788142Y1245414D03*
Y1252107D03*
X1796838Y1556125D03*
X1788107Y1556323D03*
X1793833Y1556195D03*
X1790633D03*
X1788107Y1559430D03*
X1788307Y1562537D03*
X1787261Y1566186D03*
X1782907Y1559430D03*
Y1556323D03*
X1784781Y1566186D03*
X1785507Y1559430D03*
Y1556323D03*
X1785707Y1562537D03*
X1796257Y1561255D03*
Y1558755D03*
X1787261Y1571786D03*
X1784781D03*
X1788679Y1585805D03*
X1807515Y56461D03*
X1807546Y59443D03*
X1807296Y255033D03*
X1804174Y253739D03*
Y256739D03*
X1803129Y362293D03*
X1802929Y385293D03*
X1804688Y1545871D03*
Y1542371D03*
Y1552871D03*
Y1549371D03*
X1801688Y1545871D03*
Y1542371D03*
Y1552871D03*
Y1549371D03*
X1804688Y1555871D03*
X1801688D03*
X1804688Y1559371D03*
X1818615Y49379D03*
X1818155Y149325D03*
X1819529Y320321D03*
X1820307Y373829D03*
X1820656Y388051D03*
X1820144Y398052D03*
X1819374Y410432D03*
X1818874Y423932D03*
X1840615Y49379D03*
X1853692Y308447D03*
G54D40*
X311115Y1214093D03*
X310957Y1219126D03*
X388805Y1218420D03*
X388647Y1223453D03*
X386461Y1235718D03*
X386303Y1240751D03*
X1898799Y1810398D03*
X1908799D03*
X1931395Y572237D03*
X1921395D03*
X1942395Y1184617D03*
X1940886Y1810370D03*
X1963362Y572379D03*
X1952395Y1184617D03*
X1950886Y1810370D03*
X1973362Y572379D03*
X1984482Y1184589D03*
X1992856Y1810550D03*
X1982856D03*
X2005452Y572389D03*
X1994482Y1184589D03*
X2015452Y572389D03*
X2036452Y1184769D03*
X2026452D03*
X2047419Y572531D03*
X2057419D03*
X2078539Y1184741D03*
X2068539D03*
G54D56*
X828780Y1684890D03*
X818780D03*
X828780Y1694890D03*
X818780D03*
X828780Y1704890D03*
X818780D03*
X828780Y1714890D03*
X818780D03*
X853780Y1684890D03*
Y1694890D03*
Y1704890D03*
Y1714890D03*
X863780Y1684890D03*
Y1694890D03*
Y1704890D03*
Y1714890D03*
X888780Y1684890D03*
Y1694890D03*
Y1704890D03*
Y1714890D03*
X898780Y1684890D03*
Y1694890D03*
Y1704890D03*
Y1714890D03*
X918780Y1704890D03*
X958780Y1684890D03*
Y1694890D03*
Y1704890D03*
Y1714890D03*
X968780Y1684890D03*
Y1694890D03*
Y1704890D03*
Y1714890D03*
X993780Y1684890D03*
Y1694890D03*
Y1704890D03*
Y1714890D03*
X1003780Y1684890D03*
Y1694890D03*
Y1704890D03*
Y1714890D03*
X1028780Y1684890D03*
X1038780D03*
X1028780Y1694890D03*
X1038780D03*
X1028780Y1704890D03*
Y1714890D03*
X1038780Y1704890D03*
Y1714890D03*
G54D29*
X182947Y1507512D03*
X186530Y1521453D03*
X185688Y1519195D03*
X186860Y1514243D03*
X186579Y1536063D03*
X177579Y1528725D03*
Y1523810D03*
X183051Y1542425D03*
X185966Y1592380D03*
Y1624292D03*
X188254Y1507295D03*
X192979D03*
X197703D03*
X191254Y1521453D03*
X195979D03*
X200703D03*
X196309Y1514243D03*
X201033D03*
X191584D03*
X187081Y1528853D03*
X191805D03*
X196530D03*
X201254D03*
X196029Y1536063D03*
X200753D03*
X191304D03*
X197703Y1542641D03*
X188254D03*
X192979D03*
X198026Y1592380D03*
X193766D03*
X192006Y1602380D03*
X199786D03*
X193766Y1624292D03*
X198026D03*
X199786Y1614292D03*
X192006D03*
X202427Y1507295D03*
X207152D03*
X211876D03*
X216601D03*
X205427Y1521453D03*
X210152D03*
X214876D03*
X205758Y1514243D03*
X215206D03*
X210482D03*
X205978Y1528853D03*
X210703D03*
X215427D03*
X214926Y1536063D03*
X211876Y1542641D03*
X202427D03*
X207152D03*
X216601D03*
X210086Y1592380D03*
X205826D03*
X216126Y1602380D03*
X204066D03*
X211846D03*
X205826Y1624292D03*
X210086D03*
X216126Y1614292D03*
X211846D03*
X204066D03*
X221325Y1507295D03*
X226049D03*
X230774D03*
X219601Y1521453D03*
X224325D03*
X229049D03*
X219931Y1514243D03*
X224655D03*
X229380D03*
X220152Y1528853D03*
X224876D03*
X229600D03*
X224375Y1536063D03*
X226049Y1542641D03*
X230774D03*
X221325D03*
X229946Y1592380D03*
X217886D03*
X222146D03*
X223906Y1602380D03*
X228186D03*
X229946Y1624292D03*
X222146D03*
X217886D03*
X228186Y1614292D03*
X223906D03*
X235498Y1507295D03*
X240223D03*
X244947D03*
X243223Y1521453D03*
X238498D03*
X233774D03*
X234104Y1514243D03*
X238828D03*
X243553D03*
X243774Y1528853D03*
X239049D03*
X234325D03*
X238548Y1536063D03*
X240223Y1542641D03*
X235498D03*
X244947D03*
X242006Y1592380D03*
X234206D03*
X246266D03*
X235966Y1602380D03*
X240246D03*
X246266Y1624292D03*
X242006D03*
X234206D03*
X240246Y1614292D03*
X235966D03*
X241141Y1679320D03*
Y1683857D03*
X233267Y1675383D03*
Y1679920D03*
Y1684454D03*
X241141Y1688391D03*
Y1693493D03*
Y1698030D03*
X233267Y1689556D03*
Y1694093D03*
Y1698627D03*
X241141Y1702564D03*
Y1707666D03*
Y1712203D03*
Y1716737D03*
X233267Y1703729D03*
Y1708266D03*
Y1712800D03*
X241141Y1721840D03*
Y1726377D03*
Y1730911D03*
X233267Y1717903D03*
Y1722440D03*
Y1726974D03*
X259120Y1507295D03*
X249671D03*
X254396D03*
X257396Y1521453D03*
X252672D03*
X247947D03*
X248277Y1514243D03*
X257726D03*
X257947Y1528853D03*
X253223D03*
X248498D03*
X257446Y1536063D03*
X247997D03*
X254396Y1542641D03*
X259120D03*
X249671D03*
X258326Y1592380D03*
X254066D03*
X248026Y1602380D03*
X252306D03*
X260086D03*
X258326Y1624292D03*
X254066D03*
X248026Y1614292D03*
X252306D03*
X260086D03*
X256889Y1679320D03*
Y1683857D03*
X249015Y1684454D03*
Y1679920D03*
Y1675383D03*
X256889Y1688391D03*
Y1693493D03*
Y1698030D03*
X249015Y1698627D03*
Y1694093D03*
Y1689556D03*
X256889Y1702564D03*
Y1707666D03*
Y1712203D03*
Y1716737D03*
X249015Y1712800D03*
Y1708266D03*
Y1703729D03*
X256889Y1721840D03*
Y1726377D03*
Y1730911D03*
X249015Y1726974D03*
Y1722440D03*
Y1717903D03*
X262141Y1521453D03*
X262777Y1536063D03*
X270386Y1592380D03*
X266126D03*
X264366Y1602380D03*
X272146D03*
X270386Y1624292D03*
X266126D03*
X272146Y1614292D03*
X264366D03*
X272637Y1679320D03*
Y1683857D03*
X264763Y1684454D03*
Y1679920D03*
Y1675383D03*
X272637Y1688391D03*
Y1693493D03*
Y1698030D03*
X264763Y1698627D03*
Y1694093D03*
Y1689556D03*
X272637Y1702564D03*
Y1707666D03*
Y1712203D03*
Y1716737D03*
X264763Y1712800D03*
Y1708266D03*
Y1703729D03*
X272637Y1721840D03*
Y1726377D03*
Y1730911D03*
X264763Y1726974D03*
Y1722440D03*
Y1717903D03*
X290246Y1592380D03*
X278186D03*
X282446D03*
X276426Y1602380D03*
X284206D03*
X288486D03*
X290236Y1624292D03*
X282446D03*
X278186D03*
X288486Y1614292D03*
X284206D03*
X276426D03*
X288385Y1683857D03*
Y1679320D03*
X280511Y1684454D03*
Y1679920D03*
Y1675383D03*
X288385Y1688391D03*
Y1693494D03*
Y1698031D03*
X280511Y1698627D03*
Y1694093D03*
Y1689556D03*
X288385Y1712204D03*
Y1716738D03*
Y1702565D03*
Y1707667D03*
X280511Y1712800D03*
Y1708266D03*
Y1703729D03*
X288385Y1721840D03*
Y1726377D03*
Y1730911D03*
X280511Y1726974D03*
Y1722440D03*
Y1717903D03*
X305641Y1528725D03*
Y1523810D03*
X302306Y1592380D03*
X294506D03*
X296266Y1602380D03*
X300546D03*
X302306Y1624292D03*
X294516D03*
X300546Y1614292D03*
X296266D03*
X300196Y1675383D03*
Y1679920D03*
Y1684454D03*
Y1689556D03*
Y1694093D03*
Y1698627D03*
Y1703729D03*
Y1708266D03*
Y1712800D03*
Y1717903D03*
Y1722440D03*
Y1726974D03*
X309886Y1028056D03*
X315437Y1031245D03*
X317288Y1040812D03*
X309886D03*
X317288Y1034434D03*
X309886D03*
X315437Y1044001D03*
X309886Y1047190D03*
X311736Y1056757D03*
X309886Y1053568D03*
X315437Y1050379D03*
X317288Y1053568D03*
Y1059946D03*
X309886D03*
X313587D03*
X315437Y1063135D03*
X317288Y1072702D03*
X309886D03*
Y1066324D03*
X315437Y1069513D03*
X317288Y1079080D03*
X309886D03*
X315437Y1082269D03*
Y1088647D03*
X309886Y1085458D03*
Y1091836D03*
X317288D03*
X309886Y1104592D03*
X315437Y1101403D03*
X317288Y1098214D03*
X309886D03*
X315437Y1107781D03*
X309886Y1110970D03*
X317288D03*
X309886Y1117348D03*
X317288D03*
X309886Y1123726D03*
X315437Y1120537D03*
Y1126915D03*
X309886Y1130103D03*
X317288D03*
X309886Y1136481D03*
X315437Y1139670D03*
X317288Y1136481D03*
X309886Y1142859D03*
X317288Y1149237D03*
X309886D03*
X315437Y1146048D03*
X317288Y1155615D03*
X309886D03*
X313587D03*
X308036Y1158804D03*
X311736Y1165182D03*
X320988Y1155615D03*
Y1161993D03*
X311009Y1507514D03*
X316316Y1507295D03*
X321041D03*
X319316Y1521453D03*
X314592D03*
X313750Y1519195D03*
X314922Y1514243D03*
X319646D03*
X319867Y1528853D03*
X315143D03*
X319366Y1536063D03*
X314641D03*
X311113Y1542425D03*
X316316Y1542641D03*
X321041D03*
X318626Y1592380D03*
X306566D03*
X314366D03*
X308326Y1602380D03*
X312606D03*
X320386D03*
X314366Y1624292D03*
X318626D03*
X306566D03*
X320386Y1614292D03*
X312606D03*
X308326D03*
X315944Y1675383D03*
Y1679920D03*
Y1684454D03*
X308070Y1683857D03*
Y1679320D03*
X315944Y1689556D03*
Y1694093D03*
Y1698627D03*
X308070Y1698030D03*
Y1693493D03*
Y1688391D03*
X315944Y1703729D03*
Y1708266D03*
Y1712800D03*
X308070Y1716737D03*
Y1712203D03*
Y1707666D03*
Y1702564D03*
X315944Y1722440D03*
Y1726974D03*
X308070Y1730911D03*
Y1726377D03*
Y1721840D03*
X315944Y1717903D03*
X328390Y1028056D03*
X335791D03*
X322839Y1031245D03*
Y1037623D03*
Y1044001D03*
X328390Y1040812D03*
Y1034434D03*
X330240Y1031245D03*
Y1037623D03*
Y1044001D03*
X335791Y1040812D03*
Y1034434D03*
X328390Y1047190D03*
X322839Y1050379D03*
Y1056757D03*
X326539D03*
X328390Y1053568D03*
Y1059946D03*
X324689D03*
X330240Y1050379D03*
Y1056757D03*
X335791Y1047190D03*
Y1053568D03*
Y1059946D03*
X328390Y1072702D03*
X330240Y1069513D03*
X335791Y1072702D03*
Y1066324D03*
X322839Y1063135D03*
X330240D03*
X322839Y1069513D03*
X328390Y1066324D03*
X322839Y1075891D03*
X330240D03*
X328390Y1079080D03*
X322839Y1088647D03*
X328390Y1085458D03*
X330240Y1088647D03*
X322839Y1082269D03*
X330240D03*
X335791Y1079080D03*
Y1085458D03*
X328390Y1091836D03*
X322839Y1095025D03*
X330240D03*
X328390Y1104592D03*
Y1098214D03*
X322839Y1101403D03*
X330240D03*
X335791Y1091836D03*
Y1104592D03*
Y1098214D03*
X322839Y1107781D03*
X330240D03*
X328390Y1110970D03*
Y1117348D03*
X330240Y1114159D03*
X322839D03*
X335791Y1110970D03*
Y1117348D03*
X330240Y1126915D03*
X322839D03*
X328390Y1123726D03*
X330240Y1120537D03*
X322839D03*
Y1133293D03*
X330240D03*
X328390Y1130103D03*
X335791Y1123726D03*
X335792Y1130105D03*
X328390Y1142859D03*
X322839Y1139670D03*
X328390Y1136481D03*
X330240Y1139670D03*
X328390Y1149237D03*
X330240Y1146048D03*
X322839D03*
X335791Y1136481D03*
Y1142859D03*
Y1149237D03*
X328390Y1155615D03*
X330240Y1152426D03*
X322839D03*
X326539Y1158804D03*
X330240D03*
X333941D03*
X322839D03*
X328390Y1161993D03*
X330240Y1165182D03*
X335791Y1155615D03*
Y1161993D03*
X330489Y1507295D03*
X335214D03*
X325765D03*
X333489Y1521453D03*
X328765D03*
X324041D03*
X324371Y1514243D03*
X329095D03*
X333820D03*
X334040Y1528853D03*
X329316D03*
X324592D03*
X324091Y1536063D03*
X328815D03*
X325765Y1542641D03*
X330489D03*
X335214D03*
X330686Y1592380D03*
X326426D03*
X324666Y1602380D03*
X332446D03*
X326426Y1624292D03*
X330686D03*
X332446Y1614292D03*
X324666D03*
X331692Y1675383D03*
Y1679920D03*
Y1684454D03*
X323818Y1683857D03*
Y1679320D03*
X331692Y1689556D03*
Y1694093D03*
Y1698627D03*
X323818Y1698030D03*
Y1693493D03*
Y1688391D03*
X331692Y1703729D03*
Y1708266D03*
Y1712800D03*
X323818Y1716737D03*
Y1712203D03*
Y1707666D03*
Y1702564D03*
Y1721840D03*
X331692Y1717903D03*
Y1722440D03*
Y1726974D03*
X323818Y1730911D03*
Y1726377D03*
X348744Y1031245D03*
X341343D03*
X343193Y1040812D03*
X348744Y1037623D03*
X343193Y1034434D03*
X348744Y1044001D03*
X341343D03*
X350595Y1059946D03*
X337642Y1056757D03*
X348744D03*
X343193Y1053568D03*
X341343Y1050379D03*
X348744D03*
X343193Y1059946D03*
X339492D03*
X341343Y1063135D03*
X348744D03*
X341343Y1069513D03*
X343193Y1072702D03*
X348744Y1069513D03*
X343193Y1079080D03*
X348744Y1075891D03*
X341343Y1082269D03*
X348744D03*
X341343Y1088647D03*
X348744D03*
Y1095025D03*
X343193Y1091836D03*
X348744Y1101403D03*
X341343D03*
X343193Y1098214D03*
X341343Y1107781D03*
X348744D03*
X343193Y1110970D03*
Y1117348D03*
X348744Y1114159D03*
Y1120537D03*
X341343D03*
Y1126915D03*
X348744D03*
Y1133293D03*
X343193Y1130103D03*
X341343Y1139670D03*
X343193Y1136481D03*
X348744Y1139670D03*
X343193Y1149237D03*
X348744Y1146048D03*
X341343D03*
X348744Y1152426D03*
X337642Y1158804D03*
X341343D03*
X348744D03*
X339492Y1155615D03*
X343193D03*
X346894D03*
X337642Y1165182D03*
X343193Y1161993D03*
X346894D03*
X348744Y1165182D03*
X339938Y1507295D03*
X344663D03*
X349387D03*
X347663Y1521453D03*
X342938D03*
X338214D03*
X338544Y1514243D03*
X343268D03*
X347993D03*
X348214Y1528853D03*
X343489D03*
X338765D03*
X342988Y1536063D03*
X339938Y1542641D03*
X344663D03*
X349387D03*
X338486Y1592380D03*
X342746D03*
X350546D03*
X336726Y1602380D03*
X344506D03*
X348786D03*
X350546Y1624292D03*
X342746D03*
X338486D03*
X348786Y1614292D03*
X344506D03*
X336726D03*
X347440Y1675383D03*
Y1679920D03*
Y1684454D03*
X339566Y1683857D03*
Y1679320D03*
X347440Y1694093D03*
Y1698627D03*
X339566Y1698030D03*
Y1693493D03*
Y1688391D03*
X347440Y1689556D03*
Y1703729D03*
Y1708266D03*
Y1712800D03*
X339566Y1716737D03*
Y1712203D03*
Y1707666D03*
Y1702564D03*
X347440Y1717903D03*
Y1722440D03*
Y1726974D03*
X339566Y1730911D03*
Y1726377D03*
Y1721840D03*
X354295Y1028056D03*
X361697D03*
Y1040812D03*
X356146Y1044001D03*
X354295Y1040812D03*
Y1034434D03*
X356146Y1031245D03*
Y1037623D03*
X361697Y1034434D03*
X354295Y1047190D03*
X361697D03*
X354295Y1053568D03*
Y1059946D03*
X363547Y1056757D03*
X356146D03*
Y1050379D03*
X361697Y1053568D03*
X365398Y1059946D03*
X361697D03*
X352445Y1056757D03*
X356146Y1063135D03*
X354295Y1072702D03*
Y1066324D03*
X356146Y1069513D03*
X361697Y1066324D03*
Y1072702D03*
X356146Y1075891D03*
X354295Y1079080D03*
X361697D03*
X354295Y1085458D03*
X356146Y1088647D03*
X361697Y1085458D03*
X356146Y1082269D03*
X354295Y1091836D03*
X361697D03*
X356146Y1095025D03*
X354295Y1104592D03*
Y1098214D03*
X361697Y1104592D03*
X356146Y1101403D03*
X361697Y1098214D03*
X356146Y1107781D03*
X354295Y1110970D03*
X361697D03*
Y1117348D03*
X356146Y1114159D03*
X354295Y1117348D03*
Y1123726D03*
X356146Y1126915D03*
Y1120537D03*
X361697Y1123726D03*
X356146Y1133293D03*
X361697Y1130103D03*
X354296Y1130105D03*
X354295Y1136481D03*
X356146Y1139670D03*
X361697Y1136481D03*
X354295Y1142859D03*
X361697D03*
Y1149237D03*
X356146Y1146048D03*
X354295Y1149237D03*
X363547Y1165182D03*
X356146D03*
X361697Y1161993D03*
X363547Y1158804D03*
X356146D03*
X359847D03*
X352445D03*
X365398Y1155615D03*
X356146Y1152426D03*
X361697Y1155615D03*
X354295D03*
Y1161993D03*
X354111Y1507295D03*
X358836D03*
X363560D03*
X361836Y1521453D03*
X357111D03*
X352387D03*
X352717Y1514243D03*
X357442D03*
X362166D03*
X362387Y1528853D03*
X357662D03*
X352938D03*
X352437Y1536063D03*
X354111Y1542641D03*
X358836D03*
X363560D03*
X362606Y1592380D03*
X354806D03*
X356566Y1602380D03*
X360846D03*
X354806Y1624292D03*
X360846Y1614292D03*
X356566D03*
X362606Y1624292D03*
X355314Y1683857D03*
Y1679320D03*
Y1688391D03*
Y1698030D03*
Y1693493D03*
Y1716737D03*
Y1712203D03*
Y1707666D03*
Y1702564D03*
Y1730911D03*
Y1726377D03*
Y1721840D03*
X380201Y1028056D03*
X367248Y1031245D03*
Y1044001D03*
X369099Y1034434D03*
Y1040812D03*
X374650Y1031245D03*
X380201Y1040812D03*
Y1034434D03*
X374650Y1037623D03*
Y1044001D03*
X367248Y1050379D03*
X380201Y1047190D03*
X369099Y1053568D03*
Y1059946D03*
X380201Y1053568D03*
X378351Y1056757D03*
X374650Y1050379D03*
Y1056757D03*
X380201Y1059946D03*
X376500D03*
X367248Y1063135D03*
Y1069513D03*
X374650Y1063135D03*
X369099Y1072702D03*
X380201D03*
X374650Y1069513D03*
X367248Y1088647D03*
Y1082269D03*
X374650Y1075891D03*
X369099Y1079080D03*
X380201Y1085458D03*
X374650Y1088647D03*
Y1082269D03*
X367248Y1101403D03*
X369099Y1091836D03*
X374650Y1095025D03*
X369099Y1098214D03*
X380201Y1104592D03*
Y1098214D03*
X374650Y1101403D03*
X367248Y1107781D03*
X374650D03*
X369099Y1110970D03*
Y1117348D03*
X380201D03*
X374650Y1114159D03*
X367248Y1120537D03*
Y1126915D03*
X374650Y1120537D03*
Y1126915D03*
X380201Y1130103D03*
X374650Y1133293D03*
X369099Y1130103D03*
X367248Y1139670D03*
Y1146048D03*
X380201Y1142859D03*
X374650Y1139670D03*
X369099Y1136481D03*
Y1149237D03*
X374650Y1146048D03*
X380201Y1155615D03*
X369099D03*
X372799D03*
X374650Y1152426D03*
X378351Y1158804D03*
X374650D03*
X376500Y1161993D03*
X377523Y1222274D03*
X372730Y1216782D03*
X367697Y1216624D03*
X377733Y1507295D03*
X368285D03*
X373009D03*
X376009Y1521453D03*
X380734D03*
X366560D03*
X371285D03*
X376339Y1514243D03*
X366890D03*
X371615D03*
X376560Y1528853D03*
X367111D03*
X371836D03*
X376059Y1536063D03*
X366610D03*
X377733Y1542641D03*
X368285D03*
X373009D03*
X374666Y1592380D03*
X366866D03*
X380696Y1602380D03*
X368626Y1602286D03*
X372906Y1602380D03*
X374666Y1624292D03*
X380696Y1614292D03*
X372906D03*
X368626D03*
X366866Y1624292D03*
X387603Y1028056D03*
X395004D03*
X393154Y1044001D03*
X385752Y1031245D03*
Y1037623D03*
Y1044001D03*
X395004Y1040812D03*
X387603Y1034434D03*
Y1040812D03*
X395004Y1034434D03*
X393154Y1031245D03*
Y1037623D03*
X395004Y1047190D03*
X387603D03*
Y1053568D03*
X391303Y1059946D03*
X395004Y1053568D03*
X385752Y1050379D03*
X393154Y1056757D03*
Y1050379D03*
X382051Y1063135D03*
Y1069513D03*
X393154Y1063135D03*
X395004Y1066324D03*
X387603D03*
X383902D03*
X391303Y1072702D03*
Y1066324D03*
X393154Y1069513D03*
X382051Y1075891D03*
Y1088647D03*
Y1082269D03*
X393154Y1075891D03*
X387603Y1079080D03*
X383902D03*
X391303D03*
X395004D03*
X393154Y1082269D03*
X391303Y1085458D03*
X393154Y1088647D03*
X382051Y1095025D03*
X383902Y1091836D03*
X393154Y1095025D03*
X391303Y1091836D03*
X395004D03*
X387603D03*
X391303Y1098214D03*
Y1104592D03*
X395004D03*
X387603D03*
X383902D03*
X382051Y1107781D03*
Y1114159D03*
X383902Y1110970D03*
X387603D03*
X393154Y1107781D03*
X391303Y1110970D03*
X395004D03*
X391303Y1117348D03*
X393154Y1114159D03*
X391304Y1130105D03*
X382051Y1126915D03*
Y1120537D03*
Y1133293D03*
X383902Y1123726D03*
X387603D03*
X393154Y1126915D03*
X391303Y1123726D03*
X395004D03*
X393154Y1120537D03*
Y1133293D03*
X382051Y1139670D03*
Y1146048D03*
X393154Y1139670D03*
X395004Y1136481D03*
X391303D03*
X383902D03*
X387603D03*
X391303Y1142859D03*
X393154Y1146048D03*
X395004Y1149237D03*
X383902D03*
X387603D03*
X389453Y1158804D03*
X391303Y1155615D03*
X395004D03*
X383902D03*
X387603D03*
Y1161993D03*
X382458Y1507295D03*
X387182D03*
X390203Y1521453D03*
X385458D03*
X385788Y1514243D03*
X381285Y1528853D03*
X386009D03*
X385508Y1536063D03*
X390839D03*
X382458Y1542641D03*
X387182D03*
X398705Y1028056D03*
X409795Y1028064D03*
X398705Y1034434D03*
X402406Y1040812D03*
X400555Y1031245D03*
Y1037623D03*
Y1044001D03*
X409795Y1034442D03*
Y1040820D03*
X402406Y1047190D03*
X409807D03*
X402406Y1053568D03*
X407957Y1056757D03*
X402406Y1059946D03*
X409807Y1053568D03*
X400555Y1056757D03*
Y1050379D03*
X407957D03*
X398705Y1066324D03*
X404256Y1063135D03*
X402406Y1072702D03*
X404256Y1069513D03*
X406107Y1066324D03*
X409807D03*
X402406D03*
X398705Y1079080D03*
X404256Y1075891D03*
X406107Y1079080D03*
X409807D03*
X402406D03*
X404256Y1088647D03*
X402406Y1085458D03*
X404256Y1082269D03*
X398705Y1091836D03*
Y1104592D03*
X404256Y1095025D03*
X406107Y1091836D03*
X409807D03*
X402406D03*
Y1098214D03*
Y1104592D03*
X398705Y1110970D03*
X404256Y1107781D03*
X406107Y1110970D03*
X409807D03*
X402406D03*
X404256Y1114159D03*
X402406Y1117348D03*
X398705Y1123726D03*
X406107D03*
X409807D03*
X404256Y1120537D03*
X402406Y1123726D03*
X404256Y1126915D03*
Y1133293D03*
X402406Y1130103D03*
X398705Y1136481D03*
Y1149237D03*
X402406Y1142859D03*
X404256Y1139670D03*
X406107Y1136481D03*
X409807D03*
X402406D03*
X404256Y1146048D03*
X406107Y1149237D03*
X409807D03*
X398705Y1155615D03*
Y1161993D03*
X406107Y1155615D03*
X409807D03*
X402406D03*
X400555Y1158804D03*
X409807Y1161993D03*
X400555Y1165182D03*
X424598Y1040820D03*
X417197D03*
X413508Y1059946D03*
X417209Y1047190D03*
X424610D03*
Y1053568D03*
X422760Y1056757D03*
X424610Y1059946D03*
X417209Y1053568D03*
X415358Y1056757D03*
Y1050379D03*
X422760D03*
X413508Y1072702D03*
Y1066324D03*
X415358Y1063135D03*
X424610Y1072702D03*
Y1066324D03*
X420910D03*
X417209D03*
X415358Y1069513D03*
X413508Y1079080D03*
Y1085458D03*
X415358Y1075891D03*
X420910Y1079080D03*
X424610D03*
X417209D03*
X424610Y1085458D03*
X415358Y1088647D03*
Y1082269D03*
X413508Y1091836D03*
Y1098214D03*
Y1104592D03*
X415358Y1095025D03*
X420910Y1091836D03*
X424610D03*
X417209D03*
X420910Y1104592D03*
X424610D03*
Y1098214D03*
X417209Y1104592D03*
X415358Y1101403D03*
X413508Y1110970D03*
Y1117348D03*
X415358Y1107781D03*
X424610Y1110970D03*
X420910D03*
X417209D03*
X424610Y1117348D03*
X415358Y1114159D03*
Y1120537D03*
Y1126915D03*
X424610Y1123726D03*
X420910D03*
X417209D03*
X415358Y1133293D03*
X413508Y1123726D03*
Y1130103D03*
X424611Y1130105D03*
X413508Y1142859D03*
Y1136481D03*
X424610Y1142859D03*
Y1136481D03*
X420910D03*
X415358Y1139670D03*
X417209Y1136481D03*
X420910Y1149237D03*
X417209D03*
X415358Y1146048D03*
X413508Y1155615D03*
X411658Y1158804D03*
X424610Y1155615D03*
X420910D03*
X417209D03*
X422760Y1158804D03*
Y1165182D03*
X420910Y1161993D03*
X430162Y1056757D03*
Y1050379D03*
X432012Y1047190D03*
Y1053568D03*
X435713Y1059946D03*
X426461Y1063135D03*
X430162D03*
X426461Y1069513D03*
X433862Y1063135D03*
X435713Y1072702D03*
Y1066324D03*
X430162Y1075891D03*
X426461D03*
X430162Y1088647D03*
X426461D03*
Y1082269D03*
X433862Y1075891D03*
X435713Y1079080D03*
Y1085458D03*
X433862Y1088647D03*
X426461Y1095025D03*
X430162Y1101403D03*
X426461D03*
X435713Y1091836D03*
Y1098214D03*
Y1104592D03*
X433862Y1101403D03*
X430162Y1107781D03*
X426461D03*
Y1114159D03*
X433862Y1107781D03*
X435713Y1110970D03*
Y1117348D03*
X426461Y1126915D03*
X430162Y1120537D03*
X426461D03*
X430162Y1133293D03*
X426461D03*
X435713Y1123726D03*
X433862Y1120537D03*
X435713Y1130103D03*
X433862Y1133293D03*
X426461Y1139670D03*
Y1146048D03*
X428311Y1149237D03*
X435713Y1136481D03*
Y1142859D03*
Y1149237D03*
X432012D03*
X430162Y1158804D03*
X435713Y1155615D03*
Y1161993D03*
X454204Y1040820D03*
X446790Y1047190D03*
Y1053568D03*
Y1059946D03*
X454192Y1047190D03*
X448641Y1056757D03*
X454192Y1053568D03*
X448641Y1050379D03*
X446790Y1066324D03*
Y1072702D03*
X452341Y1063135D03*
X448641D03*
X446790Y1079080D03*
Y1085458D03*
X452341Y1075891D03*
X448641D03*
X452341Y1088647D03*
X448641D03*
X446790Y1091836D03*
Y1098214D03*
Y1104592D03*
X452341Y1101403D03*
X448641D03*
X446790Y1110970D03*
Y1117348D03*
X452341Y1107781D03*
X448641D03*
X446790Y1123726D03*
Y1130103D03*
X448641Y1120537D03*
X452341D03*
Y1133293D03*
X448641D03*
X446790Y1136481D03*
Y1142859D03*
Y1149237D03*
X454192D03*
X450491D03*
X446790Y1155615D03*
Y1161993D03*
X454192Y1155615D03*
X447120Y1507512D03*
X452427Y1507295D03*
X450703Y1521453D03*
X451033Y1514243D03*
X449861Y1519195D03*
X451254Y1528853D03*
X450752Y1536063D03*
X441752Y1523810D03*
Y1528725D03*
X452427Y1542641D03*
X447224Y1542425D03*
X450139Y1592380D03*
Y1624292D03*
X469007Y1040820D03*
X461606D03*
X461593Y1047190D03*
Y1053568D03*
X456042Y1056757D03*
X457893Y1059946D03*
X456042Y1050379D03*
X468995Y1047190D03*
Y1053568D03*
Y1059946D03*
X463444Y1056757D03*
Y1050379D03*
X456042Y1063135D03*
Y1069513D03*
X457893Y1072702D03*
Y1066324D03*
X461593D03*
X467145Y1063135D03*
X468995Y1072702D03*
Y1066324D03*
X467145Y1069513D03*
X465294Y1066324D03*
X456042Y1075891D03*
X461593Y1079080D03*
X457893D03*
X456042Y1088647D03*
X457893Y1085458D03*
X456042Y1082269D03*
X467145Y1075891D03*
X468995Y1079080D03*
X465294D03*
X468995Y1085458D03*
X467145Y1088647D03*
Y1082269D03*
X457893Y1091836D03*
X461593D03*
X456042Y1095025D03*
X457893Y1098214D03*
X456042Y1101403D03*
X457893Y1104592D03*
X461593D03*
X467145Y1095025D03*
X468995Y1091836D03*
X465294D03*
X468995Y1104592D03*
X465294D03*
X468995Y1098214D03*
X467145Y1101403D03*
X456042Y1107781D03*
X457893Y1110970D03*
X461593D03*
X457893Y1117348D03*
X456042Y1114159D03*
X468995Y1110970D03*
X465294D03*
X467145Y1107781D03*
Y1114159D03*
X468995Y1117348D03*
X456042Y1126915D03*
X461593Y1123726D03*
X457893D03*
X456042Y1120537D03*
Y1133293D03*
X468995Y1123726D03*
X467145Y1120537D03*
X465294Y1123726D03*
X467145Y1126915D03*
X468995Y1130103D03*
X467145Y1133293D03*
X457893Y1130104D03*
X456042Y1139670D03*
X461593Y1136481D03*
X457893D03*
Y1142859D03*
X456042Y1146048D03*
X461593Y1149237D03*
X468995Y1142859D03*
X467145Y1139670D03*
X468995Y1136481D03*
X465294D03*
X467145Y1146048D03*
X465294Y1149237D03*
X459743Y1158804D03*
Y1152426D03*
X465294Y1155615D03*
X457152Y1507295D03*
X461876D03*
X466600D03*
X469600Y1521453D03*
X464876D03*
X460152D03*
X455427D03*
X455757Y1514243D03*
X460482D03*
X465206D03*
X469931D03*
X470151Y1528853D03*
X465427D03*
X460703D03*
X455978D03*
X464926Y1536063D03*
X460202D03*
X455477D03*
X466600Y1542641D03*
X457152D03*
X461876D03*
X469999Y1592380D03*
X457939D03*
X462199D03*
X463959Y1602380D03*
X456179D03*
X468239D03*
X457939Y1624292D03*
X463959Y1614292D03*
X456179D03*
X468239D03*
X469999Y1624292D03*
X462199D03*
X480097Y1028056D03*
X478247Y1037623D03*
Y1044001D03*
X480097Y1034434D03*
X483798Y1040812D03*
X481948Y1031245D03*
X476400Y1040820D03*
X476397Y1047190D03*
Y1053568D03*
X470845Y1056757D03*
X478247D03*
X470845Y1050379D03*
X478247D03*
X483798Y1047190D03*
Y1053568D03*
X480097Y1059946D03*
X478247Y1063135D03*
X472696Y1066324D03*
X476397D03*
X478247Y1069513D03*
X483798Y1066324D03*
X480097Y1072702D03*
Y1066324D03*
X478247Y1075891D03*
X476397Y1079080D03*
X472696D03*
X478247Y1088647D03*
Y1082269D03*
X483798Y1079080D03*
X480097D03*
Y1085458D03*
Y1104592D03*
X483798D03*
X480097Y1098214D03*
X478247Y1095025D03*
X472696Y1091836D03*
X476397D03*
X480097D03*
X483798D03*
X472696Y1110970D03*
X476397D03*
X478247Y1107781D03*
Y1114159D03*
X483798Y1110970D03*
X480097D03*
Y1117348D03*
X476397Y1123726D03*
X472696D03*
X478247Y1120537D03*
Y1126915D03*
Y1133293D03*
X483798Y1123726D03*
X480097D03*
Y1130103D03*
X478247Y1139670D03*
X476397Y1136481D03*
X472696D03*
X476397Y1149237D03*
X472696D03*
X478247Y1146048D03*
X483798Y1136481D03*
X480097D03*
Y1142859D03*
X483798Y1149237D03*
X476397Y1155615D03*
X474546Y1152426D03*
X470845Y1158804D03*
X481948D03*
X471325Y1507295D03*
X476049D03*
X480774D03*
X483774Y1521453D03*
X479049D03*
X474325D03*
X474655Y1514243D03*
X479379D03*
X484104D03*
X484325Y1528853D03*
X479600D03*
X474876D03*
X479099Y1536063D03*
X476049Y1542641D03*
X471325D03*
X480774D03*
X482059Y1592380D03*
X474259D03*
X476019Y1602380D03*
X480299D03*
X482059Y1624292D03*
X476019Y1614292D03*
X474259Y1624292D03*
X480299Y1614292D03*
X494901Y1028056D03*
X487499D03*
X485649Y1044001D03*
X494901Y1034434D03*
X491200Y1040812D03*
X487499Y1034434D03*
X489349Y1031245D03*
X493050Y1037623D03*
X485649D03*
X493050Y1044001D03*
X496751Y1031245D03*
X498601Y1040812D03*
X491200Y1047190D03*
X493050Y1056757D03*
X491200Y1059946D03*
Y1053568D03*
X485649Y1056757D03*
X493050Y1050379D03*
X485649D03*
X498601Y1047190D03*
Y1053568D03*
X489349Y1063135D03*
X494901Y1066324D03*
X491200D03*
X487499D03*
X491200Y1072702D03*
X489349Y1069513D03*
X498601Y1066324D03*
X489349Y1082269D03*
X498601Y1079080D03*
X494901D03*
X489349Y1075891D03*
X487499Y1079080D03*
X491200D03*
Y1085458D03*
X489349Y1088647D03*
X494901Y1091836D03*
X487499D03*
X491200D03*
X489349Y1095025D03*
X494901Y1104592D03*
X491200Y1098214D03*
Y1104592D03*
X487499D03*
X498601Y1091836D03*
Y1104592D03*
X496751Y1101403D03*
X491200Y1110970D03*
X489349Y1114159D03*
X491200Y1117348D03*
X498601Y1110970D03*
X494901D03*
X489349Y1107781D03*
X487499Y1110970D03*
X494901Y1123726D03*
X489349Y1126915D03*
X491200Y1123726D03*
X487499D03*
X489349Y1120537D03*
X491200Y1130103D03*
X489349Y1133293D03*
X498601Y1123726D03*
X494901Y1136481D03*
X489349Y1139670D03*
X491200Y1136481D03*
X487499D03*
X491200Y1142859D03*
X494901Y1149237D03*
X489349Y1146048D03*
X487499Y1149237D03*
X498601Y1136481D03*
Y1149237D03*
X487499Y1155615D03*
X485649Y1152426D03*
X493050Y1158804D03*
X498601Y1155615D03*
X496751Y1152426D03*
X485498Y1507295D03*
X490222D03*
X499671D03*
X494947D03*
X497947Y1521453D03*
X493222D03*
X488498D03*
X488828Y1514243D03*
X493553D03*
X498277D03*
X498498Y1528853D03*
X493773D03*
X489049D03*
X488548Y1536063D03*
X494947Y1542641D03*
X485498D03*
X490222D03*
X499671D03*
X498379Y1592380D03*
X486319D03*
X494119D03*
X488079Y1602380D03*
X492359D03*
X498379Y1624292D03*
X488079Y1614292D03*
X486319Y1624292D03*
X494119D03*
X492359Y1614292D03*
X497440Y1684454D03*
Y1679920D03*
Y1675383D03*
Y1698627D03*
Y1694093D03*
Y1689556D03*
Y1712800D03*
Y1708266D03*
Y1703729D03*
Y1726974D03*
Y1722440D03*
Y1717903D03*
X502302Y1028056D03*
X513405D03*
X507853Y1037623D03*
X500452D03*
X502302Y1034434D03*
X507853Y1044001D03*
X500452D03*
X507853Y1031245D03*
X513405Y1034434D03*
Y1040812D03*
X507853Y1056757D03*
Y1050379D03*
X500452Y1056757D03*
X504153D03*
X500452Y1050379D03*
X502302Y1059946D03*
X506003D03*
X513405Y1053568D03*
Y1059946D03*
X507853Y1063135D03*
X500452D03*
X507853Y1069513D03*
X500452D03*
X502302Y1072702D03*
X513405D03*
X507853Y1075891D03*
X500452D03*
X507853Y1088647D03*
X500452D03*
X502302Y1085458D03*
X507853Y1082269D03*
X500452D03*
X513405Y1079080D03*
X507853Y1095025D03*
X500452D03*
X502302Y1098214D03*
X507853Y1101403D03*
X502302Y1104592D03*
X513405Y1091836D03*
Y1098214D03*
X507853Y1107781D03*
X500452D03*
X507853Y1114159D03*
X502302Y1117348D03*
X500452Y1114159D03*
X513405Y1110970D03*
Y1117348D03*
X507853Y1120537D03*
X500452D03*
X507853Y1126915D03*
X500452D03*
X507853Y1133293D03*
X500452D03*
X502302Y1130103D03*
X513405Y1130104D03*
X507853Y1139670D03*
X500452D03*
X502302Y1142859D03*
X507853Y1146048D03*
X500452D03*
X513405Y1136481D03*
Y1149237D03*
X511554Y1165182D03*
X509704Y1155615D03*
X507853Y1152426D03*
X502302Y1155615D03*
X507853Y1158804D03*
X504153D03*
X513405Y1155615D03*
X504396Y1507295D03*
X509120D03*
X513844D03*
X512120Y1521453D03*
X507396D03*
X502671D03*
X503001Y1514243D03*
X507726D03*
X512450D03*
X512671Y1528853D03*
X507947D03*
X503222D03*
X512170Y1536063D03*
X502721D03*
X513844Y1542641D03*
X504396D03*
X509120D03*
X510439Y1592380D03*
X506179D03*
X512199Y1602380D03*
X500139D03*
X504419D03*
X512199Y1614292D03*
X500139D03*
X506179Y1624292D03*
X510439D03*
X504419Y1614292D03*
X505314Y1679320D03*
Y1683857D03*
X513188Y1684454D03*
Y1679920D03*
Y1675383D03*
X505314Y1688391D03*
Y1693493D03*
Y1698030D03*
X513188Y1698627D03*
Y1694093D03*
Y1689556D03*
X505314Y1707666D03*
Y1712203D03*
X513188Y1712800D03*
Y1708266D03*
Y1703729D03*
X505314Y1716737D03*
Y1702564D03*
Y1721840D03*
Y1726377D03*
Y1730911D03*
X513188Y1726974D03*
Y1722440D03*
Y1717903D03*
X520806Y1028056D03*
X528208D03*
X526357Y1037623D03*
Y1044001D03*
Y1031245D03*
X515255D03*
X520806Y1040812D03*
Y1034434D03*
X515255Y1044001D03*
X528208Y1040812D03*
Y1034434D03*
X520806Y1047190D03*
X526357Y1050379D03*
Y1056757D03*
X520806Y1053568D03*
X515255Y1050379D03*
X518956Y1056757D03*
X520806Y1059946D03*
X517105D03*
X528208Y1047190D03*
Y1053568D03*
Y1059946D03*
X526357Y1063135D03*
X515255D03*
X526357Y1069513D03*
X520806Y1066324D03*
Y1072702D03*
X515255Y1069513D03*
X528208Y1066324D03*
Y1072702D03*
X526357Y1075891D03*
X520806Y1079080D03*
X526357Y1088647D03*
Y1082269D03*
X520806Y1085458D03*
X515255Y1088647D03*
Y1082269D03*
X528208Y1079080D03*
Y1085458D03*
X526357Y1095025D03*
X520806Y1091836D03*
X526357Y1101403D03*
X520806Y1104592D03*
Y1098214D03*
X515255Y1101403D03*
X528208Y1091836D03*
Y1104592D03*
Y1098214D03*
X526357Y1107781D03*
X520806Y1110970D03*
X515255Y1107781D03*
X526357Y1114159D03*
X520806Y1117348D03*
X528208Y1110970D03*
Y1117348D03*
Y1130104D03*
X526357Y1120537D03*
Y1126915D03*
X520806Y1123726D03*
X515255Y1120537D03*
Y1126915D03*
X526357Y1133293D03*
X520806Y1130103D03*
X528208Y1123726D03*
X515255Y1139670D03*
X520806Y1142859D03*
X526357Y1139670D03*
X520806Y1136481D03*
X526357Y1146048D03*
X520806Y1149237D03*
X515255Y1146048D03*
X528208Y1136481D03*
Y1142859D03*
Y1149237D03*
X526357Y1152426D03*
Y1158804D03*
X520806Y1155615D03*
X517105D03*
X522657Y1158804D03*
X515255D03*
X517105Y1161993D03*
X528208Y1155615D03*
X518569Y1507295D03*
X523293D03*
X526314Y1521453D03*
X521569D03*
X516845D03*
X521899Y1514243D03*
X522120Y1528853D03*
X517396D03*
X521619Y1536063D03*
X526950D03*
X523293Y1542641D03*
X518569D03*
X518239Y1592380D03*
X522499D03*
X524259Y1602380D03*
X528539D03*
X516479D03*
X524259Y1614292D03*
X518239Y1624292D03*
X522499D03*
X528539Y1614292D03*
X516479D03*
X521062Y1679320D03*
Y1683857D03*
X528936Y1684454D03*
Y1679920D03*
Y1675383D03*
X521062Y1688391D03*
Y1693493D03*
Y1698030D03*
X528936Y1698627D03*
Y1694093D03*
Y1689556D03*
X521062Y1716737D03*
Y1702564D03*
Y1707666D03*
Y1712203D03*
X528936Y1712800D03*
Y1708266D03*
Y1703729D03*
X521062Y1721840D03*
Y1726377D03*
Y1730911D03*
X528936Y1726974D03*
Y1722440D03*
Y1717903D03*
X539310Y1028056D03*
X541160Y1031245D03*
X533759D03*
X539310Y1034434D03*
Y1040812D03*
X533759Y1037623D03*
X541160Y1044001D03*
X533759D03*
X543011Y1059946D03*
X530058Y1056757D03*
X541160Y1050379D03*
X539310Y1053568D03*
X533759Y1050379D03*
Y1056757D03*
X539310Y1059946D03*
X531908D03*
X541160Y1063135D03*
X533759D03*
X541160Y1069513D03*
X539310Y1072702D03*
X533759Y1069513D03*
Y1075891D03*
X539310Y1079080D03*
X541160Y1088647D03*
X533759D03*
X541160Y1082269D03*
X533759D03*
X539310Y1091836D03*
X533759Y1095025D03*
X539310Y1098214D03*
X541160Y1101403D03*
X533759D03*
X541160Y1107781D03*
X533759D03*
X539310Y1110970D03*
Y1117348D03*
X533759Y1114159D03*
X541160Y1120537D03*
X533759D03*
X541160Y1126915D03*
X533759D03*
X539310Y1130103D03*
X533759Y1133293D03*
X541160Y1139670D03*
X539310Y1136481D03*
X533759Y1139670D03*
Y1146048D03*
X541160D03*
X539310Y1149237D03*
X543011Y1155615D03*
X533759Y1158804D03*
X530058D03*
X539310Y1155615D03*
X535609D03*
X533759Y1152426D03*
X543011Y1161993D03*
X542359Y1592380D03*
X530299D03*
X534559D03*
X536319Y1602380D03*
X540599D03*
X542359Y1624292D03*
X536319Y1614292D03*
X530299Y1624292D03*
X534559D03*
X540599Y1614292D03*
X536810Y1679320D03*
Y1683857D03*
X544684Y1684454D03*
Y1679920D03*
Y1675383D03*
X536810Y1688391D03*
Y1693493D03*
Y1698030D03*
X544684Y1698627D03*
Y1694093D03*
Y1689556D03*
X536810Y1716737D03*
Y1702564D03*
Y1707666D03*
Y1712203D03*
X544684Y1712800D03*
Y1708266D03*
Y1703729D03*
X536810Y1721840D03*
Y1726377D03*
Y1730911D03*
X544684Y1726974D03*
Y1722440D03*
Y1717903D03*
X554113Y1028056D03*
X546712D03*
Y1040812D03*
Y1034434D03*
X552263Y1031245D03*
X554113Y1040812D03*
X552263Y1037623D03*
X554113Y1034434D03*
X552263Y1044001D03*
X559664Y1031245D03*
Y1037623D03*
Y1044001D03*
X546712Y1047190D03*
X554113D03*
X544861Y1056757D03*
X546712Y1053568D03*
Y1059946D03*
X552263Y1056757D03*
X555964D03*
X554113Y1053568D03*
X552263Y1050379D03*
X554113Y1059946D03*
X557814D03*
X559664Y1050379D03*
Y1056757D03*
X552263Y1063135D03*
X546712Y1072702D03*
Y1066324D03*
X552263Y1069513D03*
X554113Y1066324D03*
Y1072702D03*
X559664Y1063135D03*
Y1069513D03*
X552263Y1075891D03*
X546712Y1079080D03*
X554113D03*
X546712Y1085458D03*
X552263Y1088647D03*
X554113Y1085458D03*
X552263Y1082269D03*
X559664Y1075891D03*
Y1088647D03*
Y1082269D03*
X546712Y1091836D03*
X554113D03*
X552263Y1095025D03*
Y1101403D03*
X554113Y1098214D03*
X546712Y1104592D03*
Y1098214D03*
X554113Y1104592D03*
X559664Y1095025D03*
Y1101403D03*
X552263Y1107781D03*
X554113Y1110970D03*
X546712D03*
X554113Y1117348D03*
X552263Y1114159D03*
X546712Y1117348D03*
X559664Y1107781D03*
Y1114159D03*
X546712Y1123726D03*
X554113D03*
X552263Y1120537D03*
Y1126915D03*
Y1133293D03*
X554113Y1130103D03*
X559664Y1120537D03*
Y1126915D03*
Y1133293D03*
X546712Y1130104D03*
X552263Y1139670D03*
X554113Y1136481D03*
X546712D03*
X554113Y1142859D03*
X546712D03*
Y1149237D03*
X552263Y1146048D03*
X554113Y1149237D03*
X559664Y1139670D03*
Y1146048D03*
X555964Y1165182D03*
X554113Y1155615D03*
X552263Y1152426D03*
X555964Y1158804D03*
X552263D03*
X548562D03*
X546712Y1155615D03*
X554113Y1161993D03*
X559664Y1152426D03*
Y1158804D03*
X558679Y1592380D03*
X546619D03*
X554419D03*
X548379Y1602380D03*
X552659D03*
X558679Y1624292D03*
X548379Y1614292D03*
X546619Y1624292D03*
X554419D03*
X552659Y1614292D03*
X552558Y1679320D03*
Y1683857D03*
Y1688391D03*
Y1693493D03*
Y1698030D03*
Y1716737D03*
Y1702564D03*
Y1707666D03*
Y1712203D03*
Y1721840D03*
Y1726377D03*
Y1730911D03*
X565216Y1028056D03*
X572617D03*
X567066Y1031245D03*
X565215Y1034434D03*
Y1040812D03*
X572617Y1034434D03*
Y1040812D03*
X567066Y1044001D03*
X565215Y1059946D03*
X572617Y1047190D03*
X567066Y1050379D03*
X572617Y1053568D03*
X570767Y1056757D03*
X565215Y1053568D03*
X572617Y1059946D03*
X568916D03*
X567066Y1063135D03*
X572617Y1066324D03*
Y1072702D03*
X567066Y1069513D03*
X565215Y1072702D03*
Y1079080D03*
X572617D03*
X567066Y1088647D03*
X572617Y1085458D03*
X567066Y1082269D03*
X572617Y1091836D03*
X565215D03*
X572617Y1104592D03*
Y1098214D03*
X567066Y1101403D03*
X565215Y1098214D03*
X567066Y1107781D03*
X572617Y1110970D03*
X565215D03*
X572617Y1117348D03*
X565215D03*
X572617Y1123726D03*
X567066Y1120537D03*
Y1126915D03*
X572617Y1130103D03*
X565215D03*
X572617Y1136481D03*
X565215Y1149237D03*
X572617D03*
X567066Y1146048D03*
X572617Y1142859D03*
X567066Y1139670D03*
X565215Y1136481D03*
X574467Y1158804D03*
X565215Y1155615D03*
X568916D03*
X572617D03*
X561515D03*
X565215Y1161993D03*
X569814Y1523810D03*
Y1528725D03*
X570739Y1592380D03*
X566479D03*
X572499Y1602380D03*
X560439D03*
X564719D03*
X572499Y1614292D03*
X570739Y1624292D03*
X560439Y1614292D03*
X566479Y1624292D03*
X564719Y1614292D03*
X572243Y1683857D03*
X564369Y1684454D03*
Y1679920D03*
Y1675383D03*
X572243Y1679320D03*
X564369Y1694093D03*
Y1689556D03*
X572243Y1688391D03*
Y1693493D03*
Y1698030D03*
X564369Y1698627D03*
X572243Y1702564D03*
Y1707666D03*
Y1712203D03*
X564369Y1712800D03*
Y1708266D03*
Y1703729D03*
X572243Y1716737D03*
Y1726377D03*
Y1730911D03*
X564369Y1726974D03*
Y1722440D03*
Y1717903D03*
X572243Y1721840D03*
X577728Y906182D03*
Y912560D03*
Y918938D03*
Y925316D03*
Y931694D03*
Y938072D03*
Y944450D03*
Y950828D03*
Y957206D03*
Y963584D03*
Y969962D03*
Y976340D03*
Y982718D03*
Y989096D03*
Y995474D03*
Y1008230D03*
Y1001852D03*
X578909Y1030198D03*
Y1036576D03*
Y1042954D03*
Y1049332D03*
Y1055710D03*
Y1062088D03*
Y1074844D03*
Y1068466D03*
Y1087600D03*
Y1081222D03*
Y1093978D03*
Y1100356D03*
Y1106734D03*
Y1113112D03*
Y1119490D03*
Y1125868D03*
Y1132246D03*
Y1138623D03*
Y1145001D03*
Y1151379D03*
X578168Y1158804D03*
X575182Y1507514D03*
X580489Y1507295D03*
X585214D03*
X588214Y1521453D03*
X583489D03*
X578765D03*
X579095Y1514243D03*
X583819D03*
X588544D03*
X577923Y1519195D03*
X588765Y1528853D03*
X584040D03*
X579316D03*
X588264Y1536063D03*
X583539D03*
X578814D03*
X585214Y1542641D03*
X580489D03*
X575286Y1542425D03*
X578539Y1592380D03*
X582799D03*
X584559Y1602380D03*
X588839D03*
X576779D03*
X584559Y1614292D03*
X582799Y1624292D03*
X578539D03*
X588839Y1614292D03*
X576779D03*
X587991Y1679320D03*
Y1683857D03*
X580117Y1684454D03*
Y1679920D03*
Y1675383D03*
X587991Y1688391D03*
Y1693493D03*
Y1698030D03*
X580117Y1698627D03*
Y1694093D03*
Y1689556D03*
X587991Y1716737D03*
Y1702564D03*
Y1707666D03*
Y1712203D03*
X580117Y1712800D03*
Y1708266D03*
Y1703729D03*
X587991Y1721840D03*
Y1726377D03*
Y1730911D03*
X580117Y1726974D03*
Y1722440D03*
Y1717903D03*
X589938Y1507295D03*
X594662D03*
X599387D03*
X604111D03*
X602387Y1521453D03*
X597662D03*
X592938D03*
X593268Y1514243D03*
X597993D03*
X602717D03*
X602938Y1528853D03*
X598213D03*
X593489D03*
X592988Y1536063D03*
X589938Y1542641D03*
X604111D03*
X599387D03*
X594662D03*
X602659Y1592380D03*
X590599D03*
X594859D03*
X596619Y1602380D03*
X600899D03*
X602659Y1624292D03*
X596619Y1614292D03*
X594859Y1624292D03*
X590599D03*
X600899Y1614292D03*
X603739Y1679320D03*
Y1683857D03*
X595865Y1684454D03*
Y1679920D03*
Y1675383D03*
X603739Y1688391D03*
Y1693493D03*
Y1698030D03*
X595865Y1698627D03*
Y1694093D03*
Y1689556D03*
X603739Y1716737D03*
Y1702564D03*
Y1707666D03*
Y1712203D03*
X595865Y1712800D03*
Y1708266D03*
Y1703729D03*
X603739Y1721840D03*
Y1726377D03*
Y1730911D03*
X595865Y1726974D03*
Y1722440D03*
Y1717903D03*
X608836Y1507295D03*
X613560D03*
X618284D03*
X616560Y1521453D03*
X611836D03*
X607111D03*
X607441Y1514243D03*
X612166D03*
X616890D03*
X617111Y1528853D03*
X612387D03*
X607662D03*
X607161Y1536063D03*
X616610D03*
X613560Y1542641D03*
X618284D03*
X608836D03*
X618979Y1592380D03*
X614719D03*
X606919D03*
X608679Y1602380D03*
X612959D03*
X618979Y1624292D03*
X608679Y1614292D03*
X606919Y1624292D03*
X614719D03*
X612959Y1614292D03*
X611613Y1684454D03*
Y1679920D03*
Y1675383D03*
Y1698627D03*
Y1694093D03*
Y1689556D03*
Y1712800D03*
Y1708266D03*
Y1703729D03*
Y1726974D03*
Y1722440D03*
Y1717903D03*
X623009Y1507295D03*
X627733D03*
X632458D03*
X630733Y1521453D03*
X626009D03*
X621284D03*
X621615Y1514243D03*
X626339D03*
X631063D03*
X631284Y1528853D03*
X626560D03*
X621835D03*
X630783Y1536063D03*
X632458Y1542641D03*
X627733D03*
X623009D03*
X631039Y1592380D03*
X626779D03*
X632799Y1602286D03*
X620739Y1602380D03*
X625019D03*
X631039Y1624292D03*
X632799Y1614292D03*
X626779Y1624292D03*
X620739Y1614292D03*
X625019D03*
X619487Y1679320D03*
Y1683857D03*
Y1688391D03*
Y1693493D03*
Y1698030D03*
Y1716737D03*
Y1702564D03*
Y1707666D03*
Y1712203D03*
Y1721840D03*
Y1726377D03*
Y1730911D03*
X637182Y1507295D03*
X641906D03*
X646631D03*
X644907Y1521453D03*
X640182D03*
X635458D03*
X635788Y1514243D03*
X640512D03*
X645458Y1528853D03*
X640733D03*
X636009D03*
X640232Y1536063D03*
X646631Y1542641D03*
X641906D03*
X637182D03*
X638839Y1592380D03*
X644869Y1602380D03*
X637079D03*
X644869Y1614292D03*
X638839Y1624292D03*
X637079Y1614292D03*
X651355Y1507295D03*
X654376Y1521453D03*
X649631D03*
X649961Y1514243D03*
X650182Y1528853D03*
X649681Y1536063D03*
X655012D03*
X651355Y1542641D03*
X1185452Y1556810D03*
Y1561725D03*
X1190820Y1540512D03*
X1194733Y1547243D03*
X1196127Y1540295D03*
X1199457Y1547243D03*
X1193561Y1552195D03*
X1199127Y1554453D03*
X1194403D03*
X1199678Y1561853D03*
X1194954D03*
X1199177Y1569063D03*
X1196127Y1575641D03*
X1194452Y1569063D03*
X1190924Y1575425D03*
X1193839Y1625380D03*
X1199879Y1635380D03*
Y1647292D03*
X1193839Y1657292D03*
X1200852Y1540295D03*
X1204182Y1547243D03*
X1205576Y1540295D03*
X1208906Y1547243D03*
X1210300Y1540295D03*
X1213631Y1547243D03*
X1215025Y1540295D03*
X1213300Y1554453D03*
X1208576D03*
X1203852D03*
X1213851Y1561853D03*
X1209127D03*
X1204403D03*
X1210300Y1575641D03*
X1208626Y1569063D03*
X1203902D03*
X1200852Y1575641D03*
X1205576D03*
X1215025D03*
X1205899Y1625380D03*
X1201639D03*
X1213699D03*
X1207659Y1635380D03*
X1211939D03*
X1207659Y1647292D03*
X1211939D03*
X1201639Y1657292D03*
X1205899D03*
X1213699D03*
X1218355Y1547243D03*
X1219749Y1540295D03*
X1223079Y1547243D03*
X1227804D03*
X1229198Y1540295D03*
X1224474D03*
X1227474Y1554453D03*
X1222749D03*
X1218025D03*
X1228025Y1561853D03*
X1223300D03*
X1218576D03*
X1222799Y1569063D03*
X1219749Y1575641D03*
X1224474D03*
X1229198D03*
X1217959Y1625380D03*
X1225759D03*
X1230019D03*
X1223999Y1635380D03*
X1219719D03*
X1223999Y1647292D03*
X1219719D03*
X1217959Y1657292D03*
X1230019D03*
X1225759D03*
X1232528Y1547243D03*
X1233922Y1540295D03*
X1237253Y1547243D03*
X1241977D03*
X1243371Y1540295D03*
X1238647D03*
X1241647Y1554453D03*
X1236922D03*
X1232198D03*
X1242198Y1561853D03*
X1237473D03*
X1232749D03*
X1238647Y1575641D03*
X1232248Y1569063D03*
X1233922Y1575641D03*
X1243371D03*
X1237819Y1625380D03*
X1242079D03*
X1231779Y1635380D03*
X1236059D03*
X1243839D03*
X1236059Y1647292D03*
X1231779D03*
X1243839D03*
X1237819Y1657292D03*
X1242079D03*
X1241140Y1684454D03*
Y1679920D03*
Y1675383D03*
Y1698627D03*
Y1694093D03*
Y1689556D03*
Y1712800D03*
Y1708266D03*
Y1703729D03*
Y1726974D03*
Y1722440D03*
Y1717903D03*
X1246701Y1547243D03*
X1248096Y1540295D03*
X1251426Y1547243D03*
X1252820Y1540295D03*
X1256150Y1547243D03*
X1257544Y1540295D03*
X1255820Y1554453D03*
X1251096D03*
X1246371D03*
X1256371Y1561853D03*
X1251647D03*
X1246922D03*
X1257544Y1575641D03*
X1255870Y1569063D03*
X1246421D03*
X1248096Y1575641D03*
X1252820D03*
X1249879Y1625380D03*
X1254139D03*
X1248119Y1635380D03*
X1255899D03*
X1260179D03*
X1248119Y1647292D03*
X1255899D03*
X1260179D03*
X1254139Y1657292D03*
X1249879D03*
X1249014Y1679320D03*
Y1683857D03*
X1256888Y1684454D03*
Y1679920D03*
Y1675383D03*
X1249014Y1688391D03*
Y1693493D03*
Y1698030D03*
X1256888Y1698627D03*
Y1694093D03*
Y1689556D03*
Y1703729D03*
X1249014Y1716737D03*
Y1702564D03*
Y1707666D03*
Y1712203D03*
X1256888Y1712800D03*
Y1708266D03*
X1249014Y1721840D03*
Y1726377D03*
Y1730911D03*
X1256888Y1726974D03*
Y1722440D03*
Y1717903D03*
X1262269Y1540295D03*
X1265599Y1547243D03*
X1266993Y1540295D03*
X1270014Y1554453D03*
X1265269D03*
X1260545D03*
X1265820Y1561853D03*
X1261096D03*
X1270650Y1569063D03*
X1266993Y1575641D03*
X1265319Y1569063D03*
X1262269Y1575641D03*
X1266199Y1625380D03*
X1261939D03*
X1273999D03*
X1267959Y1635380D03*
X1272239D03*
X1267959Y1647292D03*
X1272239D03*
X1266199Y1657292D03*
X1261939D03*
X1273999D03*
X1264762Y1679320D03*
Y1683857D03*
X1272636Y1684454D03*
Y1679920D03*
Y1675383D03*
X1264762Y1688391D03*
Y1693493D03*
Y1698030D03*
X1272636Y1698627D03*
Y1694093D03*
Y1689556D03*
X1264762Y1716737D03*
Y1702564D03*
Y1707666D03*
Y1712203D03*
X1272636Y1712800D03*
Y1708266D03*
Y1703729D03*
X1264762Y1721840D03*
Y1726377D03*
Y1730911D03*
X1272636Y1726974D03*
Y1722440D03*
Y1717903D03*
X1286028Y1028055D03*
Y1034433D03*
Y1040811D03*
Y1047189D03*
Y1053567D03*
X1287878Y1056756D03*
X1289729Y1059945D03*
X1286028D03*
Y1066323D03*
Y1072701D03*
Y1079079D03*
Y1085457D03*
Y1091835D03*
Y1098213D03*
Y1104591D03*
Y1110969D03*
Y1117347D03*
Y1123725D03*
Y1130102D03*
Y1136480D03*
Y1142858D03*
Y1149236D03*
X1289729Y1155614D03*
X1286028D03*
X1284178Y1158803D03*
X1287878Y1165181D03*
X1278259Y1625380D03*
X1286059D03*
X1280019Y1635380D03*
X1284299D03*
X1280019Y1647292D03*
X1284299D03*
X1278259Y1657292D03*
X1286059D03*
X1280510Y1679320D03*
Y1683857D03*
X1288384Y1684454D03*
Y1679920D03*
Y1675383D03*
X1280510Y1688391D03*
Y1693493D03*
Y1698030D03*
X1288384Y1698627D03*
Y1694093D03*
Y1689556D03*
X1280510Y1716737D03*
Y1702564D03*
Y1707666D03*
Y1712203D03*
X1288384Y1712800D03*
Y1708266D03*
Y1703729D03*
X1280510Y1721840D03*
Y1726377D03*
Y1730911D03*
X1288384Y1726974D03*
Y1722440D03*
Y1717903D03*
X1304532Y1028055D03*
X1293430Y1034433D03*
Y1040811D03*
X1298981Y1044000D03*
Y1037622D03*
X1304532Y1034433D03*
Y1040811D03*
X1298981Y1031244D03*
X1291579D03*
Y1044000D03*
X1304532Y1047189D03*
X1291579Y1050378D03*
X1293430Y1053567D03*
Y1059945D03*
X1304532Y1053567D03*
X1298981Y1050378D03*
X1302681Y1056756D03*
X1298981D03*
X1300831Y1059945D03*
X1304532D03*
X1298981Y1063134D03*
X1291579D03*
Y1069512D03*
X1293430Y1072701D03*
X1304532D03*
Y1066323D03*
X1298981Y1069512D03*
Y1075890D03*
X1293430Y1079079D03*
X1304532D03*
Y1085457D03*
X1298981Y1088646D03*
X1291579Y1082268D03*
X1298981D03*
X1291579Y1088646D03*
X1293430Y1091835D03*
X1304532D03*
X1298981Y1095024D03*
X1293430Y1098213D03*
X1298981Y1101402D03*
X1304532Y1098213D03*
Y1104591D03*
X1291579Y1101402D03*
X1298981Y1107780D03*
X1291579D03*
X1293430Y1110969D03*
X1304532D03*
X1293430Y1117347D03*
X1298981Y1114158D03*
X1304532Y1117347D03*
X1291579Y1120536D03*
X1298981D03*
X1304532Y1123725D03*
X1291579Y1126914D03*
X1298981D03*
X1304532Y1130102D03*
X1298981Y1133292D03*
X1293430Y1130102D03*
X1304532Y1136480D03*
X1298981Y1139669D03*
X1291579D03*
X1293430Y1136480D03*
X1304532Y1142858D03*
X1291579Y1146047D03*
X1293430Y1149236D03*
X1298981Y1146047D03*
X1304532Y1149236D03*
X1293430Y1155614D03*
X1304532D03*
X1298981Y1152425D03*
X1297130Y1155614D03*
X1302681Y1158803D03*
X1298981D03*
X1304532Y1161992D03*
X1297130D03*
X1298119Y1625380D03*
X1290319D03*
X1302379D03*
X1292079Y1635380D03*
X1296359D03*
X1304139D03*
X1296359Y1647292D03*
X1292079D03*
X1304139D03*
X1298119Y1657292D03*
X1290319D03*
X1302379D03*
X1296258Y1679320D03*
Y1683857D03*
Y1688391D03*
Y1693493D03*
Y1698030D03*
Y1716737D03*
Y1702564D03*
Y1707666D03*
Y1712203D03*
Y1721840D03*
Y1726377D03*
Y1730911D03*
X1311933Y1028055D03*
X1306382Y1044000D03*
Y1037622D03*
Y1031244D03*
X1319335Y1034433D03*
X1311933Y1040811D03*
X1319335D03*
X1317485Y1031244D03*
Y1044000D03*
X1311933Y1034433D03*
X1306382Y1050378D03*
Y1056756D03*
X1311933Y1047189D03*
X1313784Y1056756D03*
X1311933Y1059945D03*
X1315634D03*
X1319335D03*
X1317485Y1050378D03*
X1319335Y1053567D03*
X1311933D03*
X1306382Y1063134D03*
Y1069512D03*
X1317485Y1063134D03*
X1319335Y1072701D03*
X1317485Y1069512D03*
X1311933Y1066323D03*
Y1072701D03*
X1306382Y1075890D03*
Y1088646D03*
Y1082268D03*
X1319335Y1079079D03*
X1311933D03*
Y1085457D03*
X1317485Y1088646D03*
Y1082268D03*
X1306382Y1095024D03*
Y1101402D03*
X1319335Y1091835D03*
X1311933D03*
Y1098213D03*
X1319335D03*
X1317485Y1101402D03*
X1311933Y1104591D03*
X1306382Y1107780D03*
Y1114158D03*
X1317485Y1107780D03*
X1319335Y1110969D03*
X1311933D03*
Y1117347D03*
X1319335D03*
X1306382Y1120536D03*
Y1126914D03*
Y1133292D03*
X1317485Y1120536D03*
X1311933Y1123725D03*
X1317485Y1126914D03*
X1319335Y1130102D03*
X1311933Y1130103D03*
X1306382Y1139669D03*
Y1146047D03*
X1319335Y1136480D03*
X1317485Y1139669D03*
X1311933Y1136480D03*
Y1142858D03*
X1317485Y1146047D03*
X1319335Y1149236D03*
X1311933D03*
X1317485Y1158803D03*
X1313784D03*
X1319335Y1161992D03*
X1311933D03*
X1306382Y1165181D03*
X1313784D03*
X1306382Y1152425D03*
Y1158803D03*
X1319335Y1155614D03*
X1315634D03*
X1311933D03*
X1310083Y1158803D03*
X1318882Y1540514D03*
X1313514Y1556810D03*
Y1561725D03*
X1318986Y1575425D03*
X1310179Y1625380D03*
X1314439D03*
X1308419Y1635380D03*
X1316199D03*
X1308419Y1647292D03*
X1316199D03*
X1310179Y1657292D03*
X1314439D03*
X1315943Y1679320D03*
Y1683857D03*
X1308069Y1684454D03*
Y1679920D03*
Y1675383D03*
X1315943Y1688391D03*
Y1693493D03*
Y1698030D03*
X1308069Y1698627D03*
Y1694093D03*
Y1689556D03*
X1315943Y1716737D03*
Y1702564D03*
Y1707666D03*
Y1712203D03*
X1308069Y1712800D03*
Y1708266D03*
Y1703729D03*
X1315943Y1721840D03*
Y1726377D03*
Y1730911D03*
X1308069Y1726974D03*
Y1722440D03*
Y1717903D03*
X1330437Y1028055D03*
X1324886Y1031244D03*
X1332288D03*
X1324886Y1044000D03*
Y1037622D03*
X1332288Y1044000D03*
X1330437Y1034433D03*
X1332288Y1037622D03*
X1330437Y1040811D03*
Y1047189D03*
X1324886Y1050378D03*
Y1056756D03*
X1332288Y1050378D03*
X1330437Y1053567D03*
X1328587Y1056756D03*
X1332288D03*
X1326737Y1059945D03*
X1330437D03*
X1332288Y1063134D03*
X1324886D03*
Y1069512D03*
X1330437Y1066323D03*
X1332288Y1069512D03*
X1330437Y1072701D03*
X1324886Y1075890D03*
X1332288D03*
X1330437Y1079079D03*
X1324886Y1088646D03*
X1330437Y1085457D03*
X1332288Y1088646D03*
X1324886Y1082268D03*
X1332288D03*
X1330437Y1091835D03*
X1324886Y1095024D03*
X1332288D03*
X1324886Y1101402D03*
X1330437Y1098213D03*
X1332288Y1101402D03*
X1330437Y1104591D03*
X1324886Y1107780D03*
X1332288D03*
X1330437Y1110969D03*
X1324886Y1114158D03*
X1332288D03*
X1330437Y1117347D03*
X1324886Y1120536D03*
X1332288D03*
X1330437Y1123725D03*
X1324886Y1126914D03*
X1332288D03*
X1324886Y1133292D03*
X1332288D03*
X1330439Y1130102D03*
X1324886Y1139669D03*
X1330437Y1136480D03*
X1332288Y1139669D03*
X1330437Y1142858D03*
X1332288Y1146047D03*
X1330437Y1149236D03*
X1324886Y1146047D03*
X1332288Y1165181D03*
X1323036Y1155614D03*
Y1161992D03*
X1332288Y1152425D03*
X1330437Y1155614D03*
X1324886Y1152425D03*
X1332288Y1158803D03*
X1328587D03*
X1324886D03*
X1330437Y1161992D03*
X1324886Y1165181D03*
X1322795Y1547243D03*
X1324189Y1540295D03*
X1327519Y1547243D03*
X1328914Y1540295D03*
X1332244Y1547243D03*
X1333638Y1540295D03*
X1321623Y1552195D03*
X1331914Y1554453D03*
X1327189D03*
X1322465D03*
X1332465Y1561853D03*
X1327740D03*
X1323016D03*
X1333638Y1575641D03*
X1331964Y1569063D03*
X1328914Y1575641D03*
X1327239Y1569063D03*
X1324189Y1575641D03*
X1322514Y1569063D03*
X1326499Y1625380D03*
X1322239D03*
X1334299D03*
X1320479Y1635380D03*
X1328259D03*
X1332539D03*
X1328259Y1647292D03*
X1320479D03*
X1332539D03*
X1322239Y1657292D03*
X1326499D03*
X1334299D03*
X1331691Y1679320D03*
Y1683857D03*
X1323817Y1684454D03*
Y1679920D03*
Y1675383D03*
X1331691Y1688391D03*
Y1693493D03*
Y1698030D03*
X1323817Y1698627D03*
Y1694093D03*
Y1689556D03*
X1331691Y1716737D03*
Y1702564D03*
Y1707666D03*
Y1712203D03*
X1323817Y1712800D03*
Y1708266D03*
Y1703729D03*
X1331691Y1721840D03*
Y1726377D03*
Y1730911D03*
X1323817Y1726974D03*
Y1722440D03*
Y1717903D03*
X1337839Y1028055D03*
Y1040811D03*
Y1034433D03*
X1343390Y1031244D03*
Y1044000D03*
X1345241Y1040811D03*
Y1034433D03*
X1337839Y1047189D03*
Y1053567D03*
Y1059945D03*
X1339689Y1056756D03*
X1343390Y1050378D03*
X1345241Y1053567D03*
X1341540Y1059945D03*
X1345241D03*
X1337839Y1072701D03*
Y1066323D03*
X1343390Y1063134D03*
Y1069512D03*
X1345241Y1072701D03*
X1337839Y1079079D03*
Y1085457D03*
X1345241Y1079079D03*
X1343390Y1088646D03*
Y1082268D03*
X1337839Y1091835D03*
Y1098213D03*
Y1104591D03*
X1345241Y1091835D03*
X1343390Y1101402D03*
X1345241Y1098213D03*
X1337839Y1110969D03*
Y1117347D03*
X1343390Y1107780D03*
X1345241Y1110969D03*
Y1117347D03*
X1337839Y1123725D03*
Y1130102D03*
X1343390Y1120536D03*
Y1126914D03*
X1345241Y1130102D03*
X1337839Y1136480D03*
Y1142858D03*
Y1149236D03*
X1343390Y1139669D03*
X1345241Y1136480D03*
Y1149236D03*
X1343390Y1146047D03*
X1337839Y1155614D03*
X1335989Y1158803D03*
X1337839Y1161992D03*
X1341540Y1155614D03*
X1339689Y1158803D03*
X1348941Y1155614D03*
X1345241D03*
X1339689Y1165181D03*
X1336968Y1547243D03*
X1338362Y1540295D03*
X1341693Y1547243D03*
X1343087Y1540295D03*
X1346417Y1547243D03*
X1347811Y1540295D03*
X1346087Y1554453D03*
X1341362D03*
X1336638D03*
X1346638Y1561853D03*
X1341913D03*
X1337189D03*
X1347811Y1575641D03*
X1343087D03*
X1338362D03*
X1336688Y1569063D03*
X1338559Y1625380D03*
X1346359D03*
X1340319Y1635380D03*
X1344599D03*
X1340319Y1647292D03*
X1344599D03*
X1338559Y1657292D03*
X1346359D03*
X1347439Y1679320D03*
Y1683857D03*
X1339565Y1684454D03*
Y1679920D03*
Y1675383D03*
X1347439Y1688391D03*
Y1693493D03*
Y1698030D03*
X1339565Y1698627D03*
Y1694093D03*
Y1689556D03*
X1347439Y1716737D03*
Y1702564D03*
Y1707666D03*
Y1712203D03*
X1339565Y1712800D03*
Y1708266D03*
Y1703729D03*
X1347439Y1721840D03*
Y1726377D03*
Y1730911D03*
X1339565Y1726974D03*
Y1722440D03*
Y1717903D03*
X1356343Y1028055D03*
X1363745D03*
X1350792Y1031244D03*
Y1044000D03*
Y1037622D03*
X1356343Y1034433D03*
Y1040811D03*
X1363745Y1034433D03*
Y1040811D03*
X1361894Y1044000D03*
Y1037622D03*
Y1031244D03*
X1354493Y1056756D03*
X1350792D03*
Y1050378D03*
X1352642Y1059945D03*
X1356343Y1047189D03*
X1363745D03*
X1356343Y1053567D03*
X1361894Y1050378D03*
X1356343Y1059945D03*
X1363745Y1053567D03*
X1350792Y1063134D03*
Y1069512D03*
X1358193Y1063134D03*
X1356343Y1072701D03*
X1363745Y1066323D03*
X1358193Y1069512D03*
X1360044Y1066323D03*
X1350792Y1075890D03*
Y1082268D03*
Y1088646D03*
X1358193Y1075890D03*
X1363745Y1079079D03*
X1360044D03*
X1356343Y1085457D03*
X1358193Y1088646D03*
Y1082268D03*
X1350792Y1095024D03*
Y1101402D03*
X1356343Y1104591D03*
X1363745Y1091835D03*
X1360044D03*
X1358193Y1095024D03*
X1356343Y1098213D03*
X1363745Y1104591D03*
X1360044D03*
X1350792Y1107780D03*
Y1114158D03*
X1358193Y1107780D03*
X1360044Y1110969D03*
X1363745D03*
X1356343Y1117347D03*
X1358193Y1114158D03*
X1350792Y1120536D03*
Y1126914D03*
Y1133292D03*
X1358193Y1126914D03*
X1363745Y1123725D03*
X1360044D03*
X1358193Y1120536D03*
X1356343Y1130102D03*
X1358193Y1133292D03*
X1350792Y1139669D03*
Y1146047D03*
X1358193Y1139669D03*
X1363745Y1136480D03*
X1360044D03*
X1356343Y1142858D03*
X1363745Y1149236D03*
X1360044D03*
X1358193Y1146047D03*
X1354493Y1158803D03*
X1350792Y1152425D03*
Y1158803D03*
X1352642Y1161992D03*
X1356343Y1155614D03*
X1363745D03*
X1360044D03*
X1363745Y1161992D03*
X1351141Y1547243D03*
X1352536Y1540295D03*
X1355866Y1547243D03*
X1357260Y1540295D03*
X1360590Y1547243D03*
X1361984Y1540295D03*
X1360260Y1554453D03*
X1355536D03*
X1350811D03*
X1360811Y1561853D03*
X1356087D03*
X1351362D03*
X1361984Y1575641D03*
X1360310Y1569063D03*
X1352536Y1575641D03*
X1350861Y1569063D03*
X1357260Y1575641D03*
X1350619Y1625380D03*
X1358419D03*
X1362679D03*
X1352379Y1635380D03*
X1356659D03*
X1364439D03*
X1356659Y1647292D03*
X1352379D03*
X1364439D03*
X1358419Y1657292D03*
X1350619D03*
X1362679D03*
X1363187Y1679320D03*
Y1683857D03*
X1355313Y1684454D03*
Y1679920D03*
Y1675383D03*
Y1694093D03*
Y1689556D03*
X1363187Y1688391D03*
Y1693493D03*
Y1698030D03*
X1355313Y1698627D03*
X1363187Y1716737D03*
Y1702564D03*
Y1707666D03*
Y1712203D03*
X1355313Y1712800D03*
Y1708266D03*
Y1703729D03*
X1363187Y1726377D03*
Y1730911D03*
X1355313Y1726974D03*
Y1722440D03*
Y1717903D03*
X1363187Y1721840D03*
X1371146Y1028055D03*
X1374847D03*
X1369296Y1044000D03*
Y1037622D03*
Y1031244D03*
X1371146Y1034433D03*
X1376697Y1037622D03*
X1378548Y1040811D03*
X1371146D03*
X1374847Y1034433D03*
X1376697Y1031244D03*
Y1044000D03*
X1378548Y1053567D03*
X1376697Y1050378D03*
X1367445Y1059945D03*
X1369296Y1056756D03*
Y1050378D03*
X1371146Y1047189D03*
X1378548D03*
X1376697Y1056756D03*
X1371146Y1053567D03*
X1378548Y1059945D03*
X1369296Y1063134D03*
Y1069512D03*
X1367445Y1066323D03*
Y1072701D03*
X1371146Y1066323D03*
X1378548D03*
X1374847D03*
X1378548Y1072701D03*
X1369296Y1075890D03*
X1367445Y1079079D03*
X1369296Y1088646D03*
X1367445Y1085457D03*
X1369296Y1082268D03*
X1371146Y1079079D03*
X1378548D03*
X1374847D03*
X1378548Y1085457D03*
X1367445Y1091835D03*
X1369296Y1095024D03*
X1367445Y1104591D03*
Y1098213D03*
X1371146Y1091835D03*
X1378548D03*
X1374847D03*
X1371146Y1104591D03*
X1374847D03*
X1378548Y1098213D03*
Y1104591D03*
X1369296Y1107780D03*
X1367445Y1110969D03*
X1369296Y1114158D03*
X1367445Y1117347D03*
X1371146Y1110969D03*
X1378548D03*
X1374847D03*
X1378548Y1117347D03*
X1367445Y1130103D03*
X1369296Y1126914D03*
Y1120536D03*
X1367445Y1123725D03*
X1369296Y1133292D03*
X1374847Y1123725D03*
X1371146D03*
X1378548D03*
Y1130102D03*
X1369296Y1139669D03*
X1367445Y1136480D03*
Y1142858D03*
X1369296Y1146047D03*
X1374847Y1136480D03*
X1371146D03*
X1378548D03*
Y1142858D03*
X1371146Y1149236D03*
X1374847D03*
X1367445Y1155614D03*
X1365595Y1158803D03*
X1371146Y1155614D03*
X1378548D03*
X1374847D03*
X1376697Y1158803D03*
Y1165181D03*
X1374847Y1161992D03*
X1365315Y1547243D03*
X1366709Y1540295D03*
X1370039Y1547243D03*
X1371433Y1540295D03*
X1374763Y1547243D03*
X1376158Y1540295D03*
X1379488Y1547243D03*
X1379158Y1554453D03*
X1374433D03*
X1369709D03*
X1364984D03*
X1374984Y1561853D03*
X1370260D03*
X1365535D03*
X1371433Y1575641D03*
X1366709D03*
X1376158D03*
X1374483Y1569063D03*
X1370479Y1625380D03*
X1374740D03*
X1368719Y1635380D03*
X1376499Y1635286D03*
X1368719Y1647292D03*
X1376499D03*
X1370479Y1657292D03*
X1374739D03*
X1385937Y1028063D03*
Y1034441D03*
X1393339Y1040819D03*
X1385937D03*
X1385949Y1047189D03*
Y1053567D03*
X1384099Y1056756D03*
Y1050378D03*
X1393351Y1047189D03*
Y1053567D03*
X1389650Y1059945D03*
X1391500Y1056756D03*
Y1050378D03*
X1389650Y1066323D03*
X1391500Y1069512D03*
X1389650Y1072701D03*
X1380398Y1063134D03*
X1385949Y1066323D03*
X1382249D03*
X1380398Y1069512D03*
X1391500Y1063134D03*
X1393351Y1066323D03*
X1380398Y1075890D03*
X1385949Y1079079D03*
X1382249D03*
X1380398Y1088646D03*
Y1082268D03*
X1391500Y1075890D03*
X1393351Y1079079D03*
X1389650D03*
X1391500Y1088646D03*
X1389650Y1085457D03*
X1391500Y1082268D03*
X1385949Y1091835D03*
X1382249D03*
X1380398Y1095024D03*
X1393351Y1091835D03*
X1389650D03*
X1391500Y1095024D03*
Y1101402D03*
X1389650Y1098213D03*
X1393351Y1104591D03*
X1389650D03*
X1385949Y1110969D03*
X1382249D03*
X1380398Y1107780D03*
Y1114158D03*
X1393351Y1110969D03*
X1389650D03*
X1391500Y1107780D03*
X1389650Y1117347D03*
X1391500Y1114158D03*
X1385949Y1123725D03*
X1382249D03*
X1380398Y1120536D03*
Y1126914D03*
Y1133292D03*
X1393351Y1123725D03*
X1389650D03*
X1391500Y1120536D03*
Y1126914D03*
Y1133292D03*
X1389650Y1130102D03*
X1380398Y1139669D03*
X1385949Y1136480D03*
X1382249D03*
X1385949Y1149236D03*
X1382249D03*
X1380398Y1146047D03*
X1391500Y1139669D03*
X1393351Y1136480D03*
X1389650D03*
Y1142858D03*
X1393351Y1149236D03*
X1391500Y1146047D03*
X1385949Y1155614D03*
X1382249D03*
X1385949Y1161992D03*
X1387800Y1158803D03*
X1393351Y1155614D03*
X1389650D03*
X1380882Y1540295D03*
X1384212Y1547243D03*
X1385606Y1540295D03*
X1390331D03*
X1393661Y1547243D03*
X1393331Y1554453D03*
X1388607D03*
X1383882D03*
X1393882Y1561853D03*
X1389158D03*
X1384433D03*
X1379709D03*
X1385606Y1575641D03*
X1383932Y1569063D03*
X1380882Y1575641D03*
X1390331D03*
X1393381Y1569063D03*
X1382539Y1625380D03*
X1388569Y1635380D03*
X1380779D03*
Y1647292D03*
X1388569D03*
X1382539Y1657292D03*
X1400740Y1040819D03*
X1400752Y1047189D03*
X1398902Y1056756D03*
X1400752Y1053567D03*
Y1059945D03*
X1398902Y1050378D03*
X1408154Y1047189D03*
Y1053567D03*
X1406304Y1056756D03*
Y1050378D03*
X1402603Y1063134D03*
Y1069512D03*
X1397052Y1066323D03*
X1400752D03*
Y1072701D03*
X1406304Y1063134D03*
X1402603Y1075890D03*
X1400752Y1079079D03*
X1397052D03*
X1402603Y1088646D03*
Y1082268D03*
X1400752Y1085457D03*
X1406304Y1075890D03*
Y1088646D03*
X1402603Y1095024D03*
X1400752Y1091835D03*
X1397052D03*
X1402603Y1101402D03*
X1400752Y1104591D03*
X1397052D03*
X1400752Y1098213D03*
X1406304Y1101402D03*
X1402603Y1107780D03*
X1397052Y1110969D03*
X1400752D03*
X1402603Y1114158D03*
X1400752Y1117347D03*
X1406304Y1107780D03*
X1402603Y1120536D03*
Y1126914D03*
X1397052Y1123725D03*
X1400752D03*
X1402603Y1133292D03*
X1406304Y1120536D03*
Y1133292D03*
X1400752Y1130103D03*
X1402603Y1139669D03*
X1397052Y1136480D03*
X1400752D03*
Y1142858D03*
X1402603Y1146047D03*
X1397052Y1149236D03*
X1408154D03*
X1404453D03*
X1398902Y1158803D03*
X1397052Y1155614D03*
X1400752D03*
X1397052Y1161992D03*
X1398902Y1165181D03*
X1406304Y1158803D03*
X1395055Y1540295D03*
X1398076Y1554453D03*
X1395055Y1575641D03*
X1398712Y1569063D03*
X1411855Y1059945D03*
X1422932Y1047189D03*
Y1059945D03*
Y1053567D03*
X1410004Y1063134D03*
X1411855Y1066323D03*
Y1072701D03*
X1422932D03*
Y1066323D03*
X1410004Y1075890D03*
X1411855Y1079079D03*
Y1085457D03*
X1410004Y1088646D03*
X1422932Y1079079D03*
Y1085457D03*
Y1091835D03*
Y1104591D03*
Y1098213D03*
X1411855Y1091835D03*
Y1104591D03*
Y1098213D03*
X1410004Y1101402D03*
Y1107780D03*
X1411855Y1110969D03*
Y1117347D03*
X1422932Y1110969D03*
Y1117347D03*
X1411855Y1123725D03*
X1410004Y1120536D03*
X1411855Y1130102D03*
X1410004Y1133292D03*
X1422932Y1123725D03*
Y1130102D03*
X1411855Y1136480D03*
Y1142858D03*
Y1149236D03*
X1422932Y1136480D03*
Y1142858D03*
Y1149236D03*
X1411855Y1155614D03*
Y1161992D03*
X1422932Y1155614D03*
Y1161992D03*
X1430346Y1040819D03*
X1437748D03*
X1430334Y1047189D03*
X1424783Y1056756D03*
X1434035Y1059945D03*
X1432184Y1056756D03*
X1430334Y1053567D03*
X1424783Y1050378D03*
X1432184D03*
X1437735Y1047189D03*
Y1053567D03*
X1432184Y1063134D03*
X1428483D03*
X1424783D03*
X1432184Y1069512D03*
X1434035Y1072701D03*
Y1066323D03*
X1437735D03*
Y1079079D03*
X1428483Y1075890D03*
X1432184D03*
X1424783D03*
X1434035Y1079079D03*
X1424783Y1088646D03*
X1432184Y1082268D03*
X1428483Y1088646D03*
X1432184D03*
X1434035Y1085457D03*
X1432184Y1095024D03*
X1434035Y1091835D03*
Y1104591D03*
X1428483Y1101402D03*
X1432184D03*
X1434035Y1098213D03*
X1424783Y1101402D03*
X1437735Y1091835D03*
Y1104591D03*
X1428483Y1107780D03*
X1432184D03*
X1424783D03*
X1434035Y1110969D03*
Y1117347D03*
X1432184Y1114158D03*
X1437735Y1110969D03*
X1432184Y1126914D03*
Y1120536D03*
X1428483D03*
X1424783D03*
X1434035Y1123725D03*
X1424783Y1133292D03*
X1428483D03*
X1432184D03*
X1437735Y1123725D03*
X1434035Y1130103D03*
X1432184Y1139669D03*
X1434035Y1136480D03*
Y1142858D03*
X1430334Y1149236D03*
X1432184Y1146047D03*
X1426633Y1149236D03*
X1437735Y1136480D03*
Y1149236D03*
X1430333Y1155614D03*
X1435885Y1158803D03*
Y1152425D03*
X1452542Y1040819D03*
X1445149D03*
X1445137Y1047189D03*
X1446987Y1056756D03*
X1445137Y1059945D03*
X1439586Y1056756D03*
X1445137Y1053567D03*
X1439586Y1050378D03*
X1446987D03*
X1452539Y1047189D03*
Y1053567D03*
X1443287Y1063134D03*
X1445137Y1072701D03*
X1443287Y1069512D03*
X1448838Y1066323D03*
X1445137D03*
X1441436D03*
X1452539D03*
X1445137Y1079079D03*
X1448838D03*
X1441436D03*
X1443287Y1075890D03*
Y1088646D03*
X1445137Y1085457D03*
X1443287Y1082268D03*
X1452539Y1079079D03*
X1441436Y1091835D03*
X1448838D03*
X1445137D03*
X1443287Y1095024D03*
X1445137Y1104591D03*
X1443287Y1101402D03*
X1445137Y1098213D03*
X1441436Y1104591D03*
X1452539Y1091835D03*
X1441436Y1110969D03*
X1448838D03*
X1445137D03*
X1443287Y1107780D03*
X1445137Y1117347D03*
X1443287Y1114158D03*
X1452539Y1110969D03*
X1445137Y1123725D03*
X1448838D03*
X1443287Y1120536D03*
X1441436Y1123725D03*
X1443287Y1126914D03*
Y1133292D03*
X1445137Y1130102D03*
X1452539Y1123725D03*
X1448838Y1149236D03*
X1443287Y1146047D03*
X1441436Y1149236D03*
X1452539Y1136480D03*
Y1149236D03*
X1445137Y1142858D03*
X1443287Y1139669D03*
X1445137Y1136480D03*
X1448838D03*
X1441436D03*
X1446987Y1158803D03*
X1450688Y1152425D03*
X1441436Y1155614D03*
X1449626Y1556810D03*
Y1561725D03*
X1463641Y1028055D03*
X1456239D03*
X1459940Y1040811D03*
X1458090Y1031244D03*
X1463641Y1034433D03*
X1456239D03*
X1465491Y1031244D03*
X1454389Y1037622D03*
X1467342Y1040811D03*
X1454389Y1044000D03*
X1461791Y1037622D03*
Y1044000D03*
X1459940Y1047189D03*
X1456239Y1059945D03*
X1459940Y1053567D03*
X1454389Y1056756D03*
X1461791D03*
X1454389Y1050378D03*
X1461791D03*
X1467342Y1047189D03*
Y1059945D03*
Y1053567D03*
X1465491Y1063134D03*
X1454389D03*
X1456239Y1072701D03*
X1459940Y1066323D03*
X1463641D03*
X1465491Y1069512D03*
X1454389D03*
X1456239Y1066323D03*
X1467342Y1072701D03*
Y1066323D03*
X1459940Y1079079D03*
X1463641D03*
X1456239D03*
X1465491Y1075890D03*
X1454389D03*
X1465491Y1088646D03*
X1454389D03*
X1456239Y1085457D03*
X1465491Y1082268D03*
X1454389D03*
X1467342Y1079079D03*
Y1085457D03*
X1456239Y1098213D03*
X1467342Y1091835D03*
Y1104591D03*
Y1098213D03*
X1463641Y1091835D03*
X1459940D03*
X1456239D03*
X1465491Y1095024D03*
X1454389D03*
X1459940Y1104591D03*
X1463641D03*
X1456239D03*
X1465491Y1107780D03*
X1454389D03*
X1463641Y1110969D03*
X1459940D03*
X1456239D03*
Y1117347D03*
X1454389Y1114158D03*
X1465491D03*
X1467342Y1110969D03*
Y1117347D03*
X1454389Y1120536D03*
X1465491Y1126914D03*
X1454389D03*
X1459940Y1123725D03*
X1463641D03*
X1465491Y1120536D03*
X1456239Y1123725D03*
X1454389Y1133292D03*
X1456239Y1130102D03*
X1465491Y1133292D03*
X1467342Y1123725D03*
Y1130102D03*
X1456239Y1142858D03*
X1465491Y1139669D03*
X1459940Y1136480D03*
X1463641D03*
X1454389Y1139669D03*
X1456239Y1136480D03*
X1465491Y1146047D03*
X1459940Y1149236D03*
X1463641D03*
X1454389Y1146047D03*
X1467342Y1136480D03*
Y1142858D03*
X1463641Y1155614D03*
X1461791Y1152425D03*
X1458090Y1158803D03*
X1454994Y1540512D03*
X1458907Y1547243D03*
X1460301Y1540295D03*
X1463631Y1547243D03*
X1465026Y1540295D03*
X1468356Y1547243D03*
X1457735Y1552195D03*
X1468026Y1554453D03*
X1463301D03*
X1458577D03*
X1468577Y1561853D03*
X1463852D03*
X1459128D03*
X1455098Y1575425D03*
X1468076Y1569063D03*
X1463351D03*
X1460301Y1575641D03*
X1458626Y1569063D03*
X1465026Y1575641D03*
X1458013Y1625380D03*
X1465813D03*
X1464053Y1635380D03*
Y1647292D03*
X1465813Y1657292D03*
X1458013D03*
X1478444Y1028055D03*
X1471043D03*
X1472893Y1031244D03*
X1469192Y1037622D03*
Y1044000D03*
X1478444Y1034433D03*
X1476594Y1037622D03*
X1474743Y1040811D03*
X1476594Y1044000D03*
X1471043Y1034433D03*
X1474743Y1047189D03*
X1480295Y1056756D03*
X1482145Y1059945D03*
X1469192Y1050378D03*
X1476594D03*
Y1056756D03*
X1474743Y1053567D03*
X1478444Y1059945D03*
X1469192Y1056756D03*
X1476594Y1063134D03*
X1478444Y1072701D03*
X1476594Y1069512D03*
X1474743Y1066323D03*
X1471043D03*
X1476594Y1075890D03*
X1474743Y1079079D03*
X1471043D03*
X1478444Y1085457D03*
X1476594Y1088646D03*
Y1082268D03*
X1474743Y1091835D03*
X1471043D03*
X1476594Y1095024D03*
X1478444Y1098213D03*
Y1104591D03*
X1474743D03*
X1471043D03*
X1472893Y1101402D03*
X1476594Y1107780D03*
X1474743Y1110969D03*
X1471043D03*
X1476594Y1114158D03*
X1478444Y1117347D03*
X1476594Y1126914D03*
Y1120536D03*
X1474743Y1123725D03*
X1471043D03*
X1478444Y1130102D03*
X1476594Y1133292D03*
Y1139669D03*
X1474743Y1136480D03*
X1471043D03*
X1478444Y1142858D03*
X1476594Y1146047D03*
X1474743Y1149236D03*
X1471043D03*
X1474743Y1155614D03*
X1478444D03*
X1472893Y1152425D03*
X1480295Y1158803D03*
X1469192D03*
X1469750Y1540295D03*
X1473080Y1547243D03*
X1474474Y1540295D03*
X1477805Y1547243D03*
X1479199Y1540295D03*
X1482529Y1547243D03*
X1483923Y1540295D03*
X1482199Y1554453D03*
X1477474D03*
X1472750D03*
X1482750Y1561853D03*
X1478025D03*
X1473301D03*
X1469750Y1575641D03*
X1483923D03*
X1474474D03*
X1472800Y1569063D03*
X1479199Y1575641D03*
X1470073Y1625380D03*
X1482133D03*
X1477873D03*
X1471833Y1635380D03*
X1483893D03*
X1476113D03*
X1471833Y1647292D03*
X1483893D03*
X1476113D03*
X1470073Y1657292D03*
X1477873D03*
X1482133D03*
X1489547Y1028055D03*
X1496948D03*
X1483995Y1031244D03*
Y1037622D03*
Y1044000D03*
X1491397Y1031244D03*
X1489547Y1040811D03*
Y1034433D03*
X1491397Y1044000D03*
X1496948Y1034433D03*
Y1040811D03*
Y1047189D03*
X1483995Y1050378D03*
Y1056756D03*
X1489547Y1053567D03*
X1495098Y1056756D03*
X1491397Y1050378D03*
X1489547Y1059945D03*
X1493247D03*
X1496948Y1053567D03*
Y1059945D03*
X1483995Y1063134D03*
X1491397D03*
X1483995Y1069512D03*
X1489547Y1072701D03*
X1491397Y1069512D03*
X1496948Y1072701D03*
Y1066323D03*
X1483995Y1075890D03*
X1489547Y1079079D03*
X1496948D03*
X1483995Y1088646D03*
X1491397D03*
X1496948Y1085457D03*
X1483995Y1082268D03*
X1491397D03*
X1489547Y1091835D03*
X1496948D03*
X1483995Y1095024D03*
Y1101402D03*
X1489547Y1098213D03*
X1491397Y1101402D03*
X1496948Y1098213D03*
Y1104591D03*
X1489547Y1110969D03*
X1496948D03*
X1483995Y1107780D03*
X1491397D03*
X1483995Y1114158D03*
X1489547Y1117347D03*
X1496948D03*
X1483995Y1120536D03*
X1491397D03*
X1496948Y1123725D03*
X1483995Y1126914D03*
X1491397D03*
X1483995Y1133292D03*
X1496948Y1130102D03*
X1489547Y1130103D03*
X1483995Y1139669D03*
X1489547Y1136480D03*
X1491397Y1139669D03*
X1496948Y1136480D03*
Y1142858D03*
X1483995Y1146047D03*
X1489547Y1149236D03*
X1491397Y1146047D03*
X1496948Y1149236D03*
X1487696Y1165181D03*
X1498799Y1158803D03*
X1483995Y1152425D03*
X1485846Y1155614D03*
X1489547D03*
X1493247D03*
X1496948D03*
X1483995Y1158803D03*
X1491397D03*
X1493247Y1161992D03*
X1495111Y1165289D03*
X1491410D03*
X1498812D03*
X1488648Y1540295D03*
X1487253Y1547243D03*
X1491978D03*
X1493372Y1540295D03*
X1496702Y1547243D03*
X1498096Y1540295D03*
X1496372Y1554453D03*
X1491648D03*
X1486923D03*
X1496923Y1561853D03*
X1492199D03*
X1487474D03*
X1488648Y1575641D03*
X1493372D03*
X1498096D03*
X1496422Y1569063D03*
X1486973D03*
X1489933Y1625380D03*
X1494193D03*
X1495953Y1635380D03*
X1488173D03*
X1495953Y1647292D03*
X1488173D03*
X1494193Y1657292D03*
X1489933D03*
X1504350Y1028055D03*
X1502499Y1031244D03*
X1509901D03*
X1504350Y1040811D03*
X1502499Y1037622D03*
X1504350Y1034433D03*
X1502499Y1044000D03*
X1509901Y1037622D03*
Y1044000D03*
X1504350Y1047189D03*
Y1053567D03*
X1502499Y1050378D03*
X1509901Y1056756D03*
Y1050378D03*
X1504350Y1059945D03*
X1508050D03*
X1506200Y1056756D03*
X1502499D03*
Y1063134D03*
X1509901D03*
X1502499Y1069512D03*
X1504350Y1072701D03*
Y1066323D03*
X1509901Y1069512D03*
X1502499Y1075890D03*
X1509901D03*
X1504350Y1079079D03*
Y1085457D03*
X1502499Y1088646D03*
X1509901D03*
X1502499Y1082268D03*
X1509901D03*
X1504350Y1091835D03*
X1502499Y1095024D03*
X1509901D03*
X1504350Y1098213D03*
X1502499Y1101402D03*
X1509901D03*
X1504350Y1104591D03*
X1502499Y1107780D03*
X1509901D03*
X1504350Y1110969D03*
X1509901Y1114158D03*
X1504350Y1117347D03*
X1502499Y1114158D03*
Y1120536D03*
X1504350Y1123725D03*
X1509901Y1120536D03*
X1502499Y1126914D03*
X1509901D03*
Y1133292D03*
X1502499D03*
X1504350Y1130103D03*
X1502499Y1139669D03*
X1504350Y1136480D03*
X1509901Y1139669D03*
X1504350Y1142858D03*
Y1149236D03*
X1502499Y1146047D03*
X1509901D03*
X1504350Y1155614D03*
X1502499Y1152425D03*
X1509901D03*
X1511751Y1155614D03*
X1502499Y1158803D03*
X1506200D03*
X1509901D03*
X1509914Y1165289D03*
X1506213D03*
X1502821Y1540295D03*
X1501427Y1547243D03*
X1506151D03*
X1507545Y1540295D03*
X1510875Y1547243D03*
X1512270Y1540295D03*
X1510545Y1554453D03*
X1505821D03*
X1501096D03*
X1511096Y1561853D03*
X1506372D03*
X1501647D03*
X1507545Y1575641D03*
X1512270D03*
X1510595Y1569063D03*
X1502821Y1575641D03*
X1501993Y1625380D03*
X1506253D03*
X1508013Y1635380D03*
X1500233D03*
X1512293D03*
X1508013Y1647292D03*
X1500233D03*
X1512293D03*
X1501993Y1657292D03*
X1506253D03*
X1513187Y1679320D03*
Y1683857D03*
X1505313Y1684454D03*
Y1679920D03*
Y1675383D03*
X1513187Y1688391D03*
Y1693493D03*
Y1698030D03*
X1505313Y1698627D03*
Y1694093D03*
Y1689556D03*
X1513187Y1716737D03*
Y1702564D03*
Y1707666D03*
Y1712203D03*
X1505313Y1712800D03*
Y1708266D03*
Y1703729D03*
X1513187Y1721840D03*
Y1726377D03*
Y1730911D03*
X1505313Y1726974D03*
Y1722440D03*
Y1717903D03*
X1522854Y1028055D03*
X1515452D03*
X1522854Y1034433D03*
Y1040811D03*
X1517302Y1044000D03*
X1528405Y1037622D03*
Y1044000D03*
X1515452Y1040811D03*
Y1034433D03*
X1517302Y1031244D03*
X1528405D03*
X1515452Y1053567D03*
Y1059945D03*
X1522854Y1047189D03*
Y1053567D03*
X1521003Y1056756D03*
X1517302Y1050378D03*
X1522854Y1059945D03*
X1519153D03*
X1528405Y1050378D03*
Y1056756D03*
X1517302Y1063134D03*
X1528405D03*
X1515452Y1072701D03*
X1522854Y1066323D03*
Y1072701D03*
X1517302Y1069512D03*
X1528405D03*
Y1075890D03*
X1515452Y1079079D03*
X1522854D03*
X1517302Y1082268D03*
X1528405D03*
X1522854Y1085457D03*
X1517302Y1088646D03*
X1528405D03*
X1515452Y1091835D03*
X1522854D03*
X1528405Y1095024D03*
X1522854Y1104591D03*
X1528405Y1101402D03*
X1515452Y1098213D03*
X1522854D03*
X1517302Y1101402D03*
Y1107780D03*
X1528405D03*
X1522854Y1110969D03*
X1515452D03*
X1522854Y1117347D03*
X1528405Y1114158D03*
X1515452Y1117347D03*
X1522854Y1123725D03*
X1517302Y1120536D03*
X1528405D03*
X1517302Y1126914D03*
X1528405D03*
Y1133292D03*
X1515452Y1130102D03*
X1522854Y1130103D03*
Y1142858D03*
Y1136480D03*
X1517302Y1139669D03*
X1528405D03*
X1515452Y1136480D03*
X1528405Y1146047D03*
X1515452Y1149236D03*
X1522854D03*
X1517302Y1146047D03*
X1528405Y1152425D03*
X1524704Y1158803D03*
X1528405D03*
X1515452Y1155614D03*
X1519153D03*
X1522854D03*
X1519153Y1161992D03*
X1521718Y1540295D03*
X1515600Y1547243D03*
X1516994Y1540295D03*
X1520324Y1547243D03*
X1526443Y1540295D03*
X1524719Y1554453D03*
X1519994D03*
X1515270D03*
X1525270Y1561853D03*
X1520545D03*
X1515821D03*
X1516994Y1575641D03*
X1526443D03*
X1521718D03*
X1520044Y1569063D03*
X1514053Y1625380D03*
X1518313D03*
X1526113D03*
X1520073Y1635380D03*
X1524353D03*
X1520073Y1647292D03*
X1524353D03*
X1518313Y1657292D03*
X1514053D03*
X1526113D03*
X1521061Y1684454D03*
Y1679920D03*
Y1675383D03*
Y1698627D03*
Y1694093D03*
Y1689556D03*
Y1712800D03*
Y1708266D03*
Y1703729D03*
Y1726974D03*
Y1722440D03*
Y1717903D03*
X1530255Y1028055D03*
X1541358D03*
X1530255Y1034433D03*
Y1040811D03*
X1541357D03*
Y1034433D03*
X1543208Y1031244D03*
Y1044000D03*
X1535806Y1031244D03*
Y1037622D03*
Y1044000D03*
X1530255Y1047189D03*
Y1053567D03*
Y1059945D03*
X1541357Y1053567D03*
Y1059945D03*
X1543208Y1050378D03*
X1532106Y1056756D03*
X1535806D03*
Y1050378D03*
X1533956Y1059945D03*
X1530255Y1066323D03*
Y1072701D03*
X1543208Y1063134D03*
X1535806D03*
X1543208Y1069512D03*
X1541357Y1072701D03*
X1535806Y1069512D03*
X1530255Y1079079D03*
Y1085457D03*
X1535806Y1075890D03*
X1541357Y1079079D03*
X1543208Y1082268D03*
Y1088646D03*
X1535806D03*
Y1082268D03*
X1530255Y1098213D03*
Y1104591D03*
X1541357Y1091835D03*
X1535806Y1095024D03*
X1543208Y1101402D03*
X1541357Y1098213D03*
X1535806Y1101402D03*
X1530255Y1091835D03*
Y1110969D03*
Y1117347D03*
X1543208Y1107780D03*
X1535806D03*
X1541357Y1110969D03*
Y1117347D03*
X1535806Y1114158D03*
X1530255Y1123725D03*
Y1130102D03*
X1543208Y1120536D03*
X1535806D03*
X1543208Y1126914D03*
X1535806D03*
X1541357Y1130102D03*
X1535806Y1133292D03*
X1530255Y1142858D03*
Y1136480D03*
Y1149236D03*
X1541357Y1136480D03*
X1543208Y1139669D03*
X1535806D03*
X1543208Y1146047D03*
X1541357Y1149236D03*
X1535806Y1146047D03*
X1530255Y1155614D03*
X1537657D03*
X1541357D03*
X1535806Y1152425D03*
X1532106Y1158803D03*
X1535806D03*
X1541357Y1161992D03*
X1532106Y1165181D03*
X1531167Y1540295D03*
X1529773Y1547243D03*
X1534188Y1554453D03*
X1529443D03*
X1529994Y1561853D03*
X1534824Y1569063D03*
X1531167Y1575641D03*
X1529493Y1569063D03*
X1530373Y1625380D03*
X1542433D03*
X1538173D03*
X1532133Y1635380D03*
X1536413D03*
X1532133Y1647292D03*
X1536413D03*
X1530373Y1657292D03*
X1542433D03*
X1538173D03*
X1528935Y1679320D03*
Y1683857D03*
X1536809Y1684454D03*
Y1679920D03*
Y1675383D03*
X1528935Y1688391D03*
Y1693493D03*
Y1698030D03*
X1536809Y1698627D03*
Y1694093D03*
Y1689556D03*
X1528935Y1712203D03*
X1536809Y1712800D03*
Y1708266D03*
Y1703729D03*
X1528935Y1716737D03*
Y1702564D03*
Y1707666D03*
Y1721840D03*
Y1726377D03*
Y1730911D03*
X1536809Y1726974D03*
Y1722440D03*
Y1717903D03*
X1553870Y906181D03*
Y912559D03*
Y918937D03*
Y925315D03*
Y931693D03*
Y938071D03*
Y944449D03*
Y950827D03*
Y957205D03*
Y963583D03*
Y969961D03*
Y976339D03*
Y982717D03*
Y989095D03*
Y995473D03*
Y1008229D03*
Y1001851D03*
X1548759Y1028055D03*
X1555051Y1030197D03*
X1548759Y1040811D03*
Y1034433D03*
X1555051Y1042953D03*
Y1036575D03*
X1546909Y1056756D03*
X1545058Y1059945D03*
X1548759Y1047189D03*
X1555051Y1049331D03*
X1548759Y1053567D03*
Y1059945D03*
X1555051Y1055709D03*
Y1062087D03*
X1548759Y1072701D03*
Y1066323D03*
X1555051Y1068465D03*
Y1074843D03*
X1548759Y1079079D03*
X1555051Y1081221D03*
X1548759Y1085457D03*
X1555051Y1087599D03*
X1548759Y1091835D03*
X1555051Y1093977D03*
X1548759Y1098213D03*
Y1104591D03*
X1555051Y1100355D03*
Y1106733D03*
X1548759Y1110969D03*
X1555051Y1113111D03*
X1548759Y1117347D03*
X1555051Y1119489D03*
Y1132245D03*
X1548759Y1123725D03*
X1555051Y1125867D03*
X1548759Y1130102D03*
Y1136480D03*
X1555051Y1138622D03*
X1548759Y1142858D03*
X1555051Y1145000D03*
X1548759Y1149236D03*
X1545058Y1155614D03*
X1548759D03*
X1555051Y1151378D03*
X1550609Y1158803D03*
X1554310D03*
X1550233Y1625380D03*
X1554493D03*
X1544193Y1635380D03*
X1556253D03*
X1548473D03*
X1544193Y1647292D03*
X1556253D03*
X1548473D03*
X1554493Y1657292D03*
X1550233D03*
X1544683Y1679320D03*
Y1683857D03*
X1552557Y1684454D03*
Y1679920D03*
Y1675383D03*
X1544683Y1688391D03*
Y1693493D03*
Y1698030D03*
X1552557Y1698627D03*
Y1694093D03*
Y1689556D03*
X1544683Y1716737D03*
Y1702564D03*
Y1707666D03*
Y1712203D03*
X1552557Y1712800D03*
Y1708266D03*
Y1703729D03*
X1544683Y1721840D03*
Y1726377D03*
Y1730911D03*
X1552557Y1726974D03*
Y1722440D03*
Y1717903D03*
X1562293Y1625380D03*
X1566553D03*
X1568313Y1635380D03*
X1560533D03*
X1572593D03*
X1568313Y1647292D03*
X1560533D03*
X1572593D03*
X1562293Y1657292D03*
X1566553D03*
X1572243Y1684454D03*
Y1679920D03*
Y1675383D03*
X1560431Y1679320D03*
Y1683857D03*
X1572243Y1698627D03*
Y1694093D03*
Y1689556D03*
X1560431Y1688391D03*
Y1693493D03*
Y1698030D03*
X1572243Y1712800D03*
Y1708266D03*
Y1703729D03*
X1560431Y1716737D03*
Y1702564D03*
Y1707666D03*
Y1712203D03*
X1572243Y1726974D03*
Y1722440D03*
Y1717903D03*
X1560431Y1721840D03*
Y1726377D03*
Y1730911D03*
X1583056Y1540514D03*
X1586969Y1547243D03*
X1585797Y1552195D03*
X1586639Y1554453D03*
X1587190Y1561853D03*
X1577688Y1556810D03*
Y1561725D03*
X1586688Y1569063D03*
X1583160Y1575425D03*
X1574353Y1625380D03*
X1578613D03*
X1586413D03*
X1580373Y1635380D03*
X1584653D03*
X1580373Y1647292D03*
X1584653D03*
X1574353Y1657292D03*
X1578613D03*
X1586413D03*
X1580117Y1679320D03*
Y1683857D03*
X1587991Y1684454D03*
Y1679920D03*
Y1675383D03*
X1580117Y1688391D03*
Y1693493D03*
Y1698030D03*
X1587991Y1698627D03*
Y1694093D03*
Y1689556D03*
X1580117Y1716737D03*
Y1702564D03*
Y1707666D03*
Y1712203D03*
X1587991Y1712800D03*
Y1708266D03*
Y1703729D03*
X1580117Y1721840D03*
Y1726377D03*
Y1730911D03*
X1587991Y1726974D03*
Y1722440D03*
Y1717903D03*
X1588363Y1540295D03*
X1591693Y1547243D03*
X1593088Y1540295D03*
X1596418Y1547243D03*
X1597812Y1540295D03*
X1601142Y1547243D03*
X1602536Y1540295D03*
X1600812Y1554453D03*
X1596088D03*
X1591363D03*
X1601363Y1561853D03*
X1596639D03*
X1591914D03*
X1602536Y1575641D03*
X1600862Y1569063D03*
X1597812Y1575641D03*
X1596138Y1569063D03*
X1593088Y1575641D03*
X1591413Y1569063D03*
X1588363Y1575641D03*
X1590673Y1625380D03*
X1602733D03*
X1598473D03*
X1592433Y1635380D03*
X1596713D03*
X1592433Y1647292D03*
X1596713D03*
X1590673Y1657292D03*
X1598473D03*
X1602733D03*
X1595865Y1679320D03*
Y1683857D03*
Y1688391D03*
Y1693493D03*
Y1698030D03*
Y1716737D03*
Y1702564D03*
Y1707666D03*
Y1712203D03*
Y1721840D03*
Y1726377D03*
Y1730911D03*
X1605867Y1547243D03*
X1607261Y1540295D03*
X1610591Y1547243D03*
X1611985Y1540295D03*
X1615315Y1547243D03*
X1616710Y1540295D03*
X1614985Y1554453D03*
X1610261D03*
X1605536D03*
X1615536Y1561853D03*
X1610812D03*
X1606087D03*
X1616710Y1575641D03*
X1615035Y1569063D03*
X1611985Y1575641D03*
X1607261D03*
X1610533Y1625380D03*
X1614793D03*
X1604493Y1635380D03*
X1616553D03*
X1608773D03*
X1604493Y1647292D03*
X1616553D03*
X1608773D03*
X1614793Y1657292D03*
X1610533D03*
X1611613Y1679320D03*
Y1683857D03*
X1603739Y1684454D03*
Y1679920D03*
Y1675383D03*
X1611613Y1688391D03*
Y1693493D03*
Y1698030D03*
X1603739Y1698627D03*
Y1694093D03*
Y1689556D03*
X1611613Y1702564D03*
Y1707666D03*
Y1712203D03*
X1603739Y1712800D03*
Y1708266D03*
Y1703729D03*
X1611613Y1716737D03*
Y1721840D03*
Y1726377D03*
Y1730911D03*
X1603739Y1726974D03*
Y1722440D03*
Y1717903D03*
X1620040Y1547243D03*
X1621434Y1540295D03*
X1624764Y1547243D03*
X1626158Y1540295D03*
X1629489Y1547243D03*
X1630883Y1540295D03*
X1629158Y1554453D03*
X1624434D03*
X1619710D03*
X1629709Y1561853D03*
X1624985D03*
X1620261D03*
X1630883Y1575641D03*
X1626158D03*
X1624484Y1569063D03*
X1621434Y1575641D03*
X1622593Y1625380D03*
X1626853D03*
X1628613Y1635380D03*
X1620833D03*
X1632893D03*
X1628613Y1647292D03*
X1620833D03*
X1632893D03*
X1622593Y1657292D03*
X1626853D03*
X1627361Y1679320D03*
Y1683857D03*
X1619487Y1684454D03*
Y1679920D03*
Y1675383D03*
X1627361Y1688391D03*
Y1693493D03*
Y1698030D03*
X1619487Y1698627D03*
Y1694093D03*
Y1689556D03*
Y1708266D03*
Y1703729D03*
X1627361Y1716737D03*
Y1702564D03*
Y1707666D03*
Y1712203D03*
X1619487Y1712800D03*
X1627361Y1721840D03*
Y1726377D03*
Y1730911D03*
X1619487Y1726974D03*
Y1722440D03*
Y1717903D03*
X1634213Y1547243D03*
X1635607Y1540295D03*
X1638937Y1547243D03*
X1640332Y1540295D03*
X1643662Y1547243D03*
X1645056Y1540295D03*
X1643332Y1554453D03*
X1638607D03*
X1633883D03*
X1643883Y1561853D03*
X1639158D03*
X1634434D03*
X1645056Y1575641D03*
X1640332D03*
X1638657Y1569063D03*
X1635607Y1575641D03*
X1634653Y1625380D03*
X1638923D03*
X1646713D03*
X1640673Y1635286D03*
X1644953Y1635380D03*
X1640673Y1647292D03*
X1644953D03*
X1634653Y1657292D03*
X1638913D03*
X1646713D03*
X1648386Y1547243D03*
X1649780Y1540295D03*
X1654505D03*
X1657835Y1547243D03*
X1659229Y1540295D03*
X1662250Y1554453D03*
X1657505D03*
X1652781D03*
X1648056D03*
X1658056Y1561853D03*
X1653332D03*
X1648607D03*
X1649780Y1575641D03*
X1648106Y1569063D03*
X1654505Y1575641D03*
X1657555Y1569063D03*
X1659229Y1575641D03*
X1652743Y1635380D03*
Y1647292D03*
X1662886Y1569063D03*
G54D38*
X274913Y1019214D03*
X320189Y838505D03*
Y1199923D03*
X561133Y838505D03*
Y1199923D03*
X606409Y1019214D03*
X841240Y1420331D03*
X1016240D03*
X1251055Y1019213D03*
X1296331Y838504D03*
Y1199922D03*
X1537275Y838504D03*
Y1199922D03*
X1582551Y1019213D03*
G54D45*
X393287Y-28508D03*
Y-18508D03*
X731757Y-20090D03*
X735010Y-20104D03*
X728717Y-18895D03*
X734995Y-17589D03*
X731742Y-17575D03*
X735041Y-14717D03*
X735026Y-12202D03*
X734996Y-7172D03*
X728718Y-8478D03*
X735011Y-9687D03*
X731743Y-7158D03*
X731758Y-9673D03*
X844766Y-24648D03*
Y5352D03*
Y15352D03*
X1180124Y-35569D03*
X1183149Y-34249D03*
X1183164Y-36764D03*
X1183139Y-26179D03*
X1180099Y-14984D03*
X1183124Y-13664D03*
X1183139Y-16179D03*
X1183124Y-23664D03*
X1180099Y-24984D03*
X1183139Y-6179D03*
X1183124Y-3664D03*
X1180099Y-4984D03*
Y15016D03*
X1183124Y16336D03*
X1183139Y13821D03*
X1180099Y5016D03*
X1183124Y6336D03*
X1183139Y3821D03*
X1183140Y24187D03*
X1183125Y26702D03*
X1180100Y25382D03*
X1186402Y-34263D03*
X1186417Y-36778D03*
X1186448Y-31442D03*
X1186433Y-28927D03*
X1186392Y-26193D03*
X1186377Y-13678D03*
X1186392Y-16193D03*
X1186377Y-23678D03*
X1186392Y-6193D03*
X1186377Y-3678D03*
Y16322D03*
X1186392Y13807D03*
X1186377Y6322D03*
X1186392Y3807D03*
X1186423Y19143D03*
X1186408Y21658D03*
X1186393Y24173D03*
X1186378Y26688D03*
X1248286Y-34648D03*
Y-4648D03*
Y5352D03*
X1438983Y-35569D03*
X1438959Y25382D03*
X1445292Y-28927D03*
X1445307Y-31442D03*
X1442023Y-36764D03*
X1442008Y-34249D03*
X1445276Y-36778D03*
X1445261Y-34263D03*
X1441909Y-19948D03*
X1445171D03*
X1441909Y-9948D03*
X1445171D03*
X1441909Y52D03*
X1445171D03*
X1441909Y10052D03*
X1445171D03*
X1445237Y26688D03*
X1445252Y24173D03*
X1441984Y26702D03*
X1441999Y24187D03*
X1445267Y21658D03*
X1445282Y19143D03*
X1541580Y-38849D03*
Y-28849D03*
X1735374Y-27916D03*
X1732349Y-29236D03*
X1735389Y-30431D03*
X1735390Y-20014D03*
X1735375Y-17499D03*
X1732350Y-18819D03*
X1738627Y-27930D03*
X1738642Y-30445D03*
X1738643Y-20028D03*
X1738628Y-17513D03*
X1738673Y-25058D03*
X1738658Y-22543D03*
G54D79*
X1900275Y-39973D03*
X1910275D03*
X1931395Y572237D03*
X1921395D03*
X1929766Y1198160D03*
X1919766D03*
X1942395Y-39783D03*
X1952395D03*
X1963362Y572379D03*
X1961856Y1198170D03*
X1973362Y572379D03*
X1971856Y1198170D03*
X1984482Y-39811D03*
X1994482D03*
X2005452Y572389D03*
X2003823Y1198312D03*
X2015452Y572389D03*
X2013823Y1198312D03*
X2036452Y-39631D03*
X2026452D03*
X2047419Y572531D03*
X2057419D03*
G54D21*
X57646Y12480D03*
X137272D03*
X186622D03*
X266858D03*
X315598D03*
X502528Y33267D03*
X582154D03*
X631504D03*
X711740D03*
X760480D03*
X1532055Y12480D03*
X1611681D03*
X1661031D03*
X1741267D03*
X1790007D03*
G54D42*
X326731Y663237D03*
X363731D03*
X754645Y1436735D03*
X1166535Y1422322D03*
X1291146Y1385558D03*
X1320516D03*
X1487677Y649988D03*
X1524437Y650208D03*
X1701285Y208455D03*
X1700840Y1434362D03*
X1731660Y208455D03*
X1770442Y294777D03*
X1800002D03*
G54D63*
X1077638Y133866D03*
G54D26*
X77394Y734588D03*
Y1021399D03*
Y1277698D03*
X107095Y734588D03*
Y1021399D03*
Y1277698D03*
X136795Y734588D03*
Y1021399D03*
Y1277698D03*
X166496Y734588D03*
Y1021399D03*
Y1277698D03*
X196197Y734588D03*
Y1021399D03*
Y1277698D03*
X225898Y734588D03*
Y1021399D03*
Y1277698D03*
X655425Y734588D03*
Y1021399D03*
Y1277698D03*
X685126Y734588D03*
Y1021399D03*
Y1277698D03*
X714827Y734588D03*
Y1021399D03*
Y1277698D03*
X744528Y734588D03*
Y1021399D03*
Y1277698D03*
X774229Y734588D03*
Y1021399D03*
Y1277698D03*
X803929Y734588D03*
Y1021399D03*
Y1277698D03*
X1053536Y734587D03*
Y1021398D03*
Y1277697D03*
X1083237Y734587D03*
Y1021398D03*
Y1277697D03*
X1112937Y734587D03*
Y1021398D03*
Y1277697D03*
X1142638Y734587D03*
Y1021398D03*
Y1277697D03*
X1172339Y734587D03*
Y1021398D03*
Y1277697D03*
X1202040Y734587D03*
Y1021398D03*
Y1277697D03*
X1631567Y734587D03*
Y1021398D03*
Y1277697D03*
X1661268Y734587D03*
Y1021398D03*
Y1277697D03*
X1690969Y734587D03*
Y1021398D03*
Y1277697D03*
X1720670Y734587D03*
Y1021398D03*
Y1277697D03*
X1750371Y734587D03*
Y1021398D03*
Y1277697D03*
X1780071Y734587D03*
Y1021398D03*
Y1277697D03*
G54D57*
X887519Y1528191D03*
G54D69*
X1299439Y112812D03*
G54D70*
X1454797Y87432D03*
G54D71*
X1550377Y581353D03*
G54D49*
X549016Y274272D03*
G54D58*
X900197Y175177D03*
X944685Y155197D03*
G54D78*
X1864706Y1722195D03*
X1887340Y424013D03*
X1887240Y796658D03*
X1887579Y1171532D03*
G54D76*
X1865648Y796913D03*
X1866790Y1171255D03*
X1886177Y1722507D03*
X2076128Y424013D03*
%LPC*%
G75*
G54D83*
G01X-476840Y-884638D02*
Y2768362D01*
X5911000D01*
Y-884638D01*
X-476840D01*
G01X8000Y-625138D02*
Y-630138D01*
G01X6543Y-625138D02*
X9457D01*
G01X14367Y-630138D02*
X11833D01*
Y-625138D01*
X14367D01*
G01X13353Y-627555D02*
X11833D01*
G01X16933Y-625138D02*
Y-630138D01*
X19467D01*
G01X23300Y-630305D02*
X23173Y-630221D01*
Y-630055D01*
X23300Y-629971D01*
X23427Y-630055D01*
Y-630221D01*
X23300Y-630305D01*
G01Y-628055D02*
X23173Y-627971D01*
Y-627805D01*
X23300Y-627721D01*
X23427Y-627805D01*
Y-627971D01*
X23300Y-628055D01*
G01X28083Y-631805D02*
X27450Y-630971D01*
X27133Y-630138D01*
Y-626805D01*
X27450Y-625971D01*
X28083Y-625138D01*
G01X33500D02*
X32993Y-625305D01*
X32613Y-625721D01*
X32360Y-626221D01*
X32170Y-626888D01*
X32107Y-627638D01*
X32170Y-628388D01*
X32360Y-629055D01*
X32613Y-629555D01*
X32993Y-629971D01*
X33500Y-630138D01*
X34007Y-629971D01*
X34387Y-629555D01*
X34640Y-629055D01*
X34830Y-628388D01*
X34893Y-627638D01*
X34830Y-626888D01*
X34640Y-626221D01*
X34387Y-625721D01*
X34007Y-625305D01*
X33500Y-625138D01*
G01X37207Y-629138D02*
X37587Y-629721D01*
X38093Y-630055D01*
X38663Y-630138D01*
X39170Y-630055D01*
X39677Y-629638D01*
X39993Y-629138D01*
X40057Y-628638D01*
X39930Y-628055D01*
X39487Y-627638D01*
X39043Y-627471D01*
X38473D01*
G01X39043D02*
X39423Y-627221D01*
X39740Y-626805D01*
X39867Y-626305D01*
X39740Y-625805D01*
X39423Y-625388D01*
X38853Y-625138D01*
X38283Y-625221D01*
X37713Y-625555D01*
G01X44017Y-631805D02*
X44650Y-630971D01*
X44967Y-630138D01*
Y-626805D01*
X44650Y-625971D01*
X44017Y-625138D01*
G01X47407Y-629138D02*
X47787Y-629721D01*
X48293Y-630055D01*
X48863Y-630138D01*
X49370Y-630055D01*
X49877Y-629638D01*
X50193Y-629138D01*
X50257Y-628638D01*
X50130Y-628055D01*
X49687Y-627638D01*
X49243Y-627471D01*
X48673D01*
G01X49243D02*
X49623Y-627221D01*
X49940Y-626805D01*
X50067Y-626305D01*
X49940Y-625805D01*
X49623Y-625388D01*
X49053Y-625138D01*
X48483Y-625221D01*
X47913Y-625555D01*
G01X52697Y-625971D02*
X53077Y-625471D01*
X53520Y-625221D01*
X54027Y-625138D01*
X54660Y-625305D01*
X55103Y-625721D01*
X55230Y-626221D01*
X55167Y-626721D01*
X54913Y-627138D01*
X53647Y-627971D01*
X53077Y-628555D01*
X52697Y-629388D01*
X52570Y-630138D01*
X55230D01*
G01X58873D02*
X59000Y-629055D01*
X59190Y-628138D01*
X59443Y-627305D01*
X59760Y-626388D01*
X60267Y-625138D01*
X57733D01*
G01X63277Y-628471D02*
X64923D01*
G01X67997Y-625971D02*
X68377Y-625471D01*
X68820Y-625221D01*
X69327Y-625138D01*
X69960Y-625305D01*
X70403Y-625721D01*
X70530Y-626221D01*
X70467Y-626721D01*
X70213Y-627138D01*
X68947Y-627971D01*
X68377Y-628555D01*
X67997Y-629388D01*
X67870Y-630138D01*
X70530D01*
G01X72907Y-629138D02*
X73287Y-629721D01*
X73793Y-630055D01*
X74363Y-630138D01*
X74870Y-630055D01*
X75377Y-629638D01*
X75693Y-629138D01*
X75757Y-628638D01*
X75630Y-628055D01*
X75187Y-627638D01*
X74743Y-627471D01*
X74173D01*
G01X74743D02*
X75123Y-627221D01*
X75440Y-626805D01*
X75567Y-626305D01*
X75440Y-625805D01*
X75123Y-625388D01*
X74553Y-625138D01*
X73983Y-625221D01*
X73413Y-625555D01*
G01X80160Y-630138D02*
Y-625138D01*
X77817Y-628721D01*
X80983D01*
G01X83107Y-629388D02*
X83487Y-629805D01*
X83930Y-630055D01*
X84500Y-630138D01*
X85070Y-629971D01*
X85513Y-629638D01*
X85830Y-629055D01*
X85893Y-628388D01*
X85767Y-627721D01*
X85450Y-627305D01*
X85007Y-626971D01*
X84563Y-626888D01*
X84120Y-626971D01*
X83550Y-627305D01*
X83740Y-625138D01*
X85450D01*
G01X93497Y-630138D02*
Y-625138D01*
X95903D01*
G01X95017Y-627555D02*
X93497D01*
G01X98217Y-630138D02*
X99800Y-625138D01*
X101383Y-630138D01*
G01X100813Y-628388D02*
X98787D01*
G01X103570Y-630138D02*
X106230Y-625138D01*
G01X103570D02*
X106230Y-630138D01*
G01X110000Y-630305D02*
X109873Y-630221D01*
Y-630055D01*
X110000Y-629971D01*
X110127Y-630055D01*
Y-630221D01*
X110000Y-630305D01*
G01Y-628055D02*
X109873Y-627971D01*
Y-627805D01*
X110000Y-627721D01*
X110127Y-627805D01*
Y-627971D01*
X110000Y-628055D01*
G01X114783Y-631805D02*
X114150Y-630971D01*
X113833Y-630138D01*
Y-626805D01*
X114150Y-625971D01*
X114783Y-625138D01*
G01X120200D02*
X119693Y-625305D01*
X119313Y-625721D01*
X119060Y-626221D01*
X118870Y-626888D01*
X118807Y-627638D01*
X118870Y-628388D01*
X119060Y-629055D01*
X119313Y-629555D01*
X119693Y-629971D01*
X120200Y-630138D01*
X120707Y-629971D01*
X121087Y-629555D01*
X121340Y-629055D01*
X121530Y-628388D01*
X121593Y-627638D01*
X121530Y-626888D01*
X121340Y-626221D01*
X121087Y-625721D01*
X120707Y-625305D01*
X120200Y-625138D01*
G01X123907Y-629138D02*
X124287Y-629721D01*
X124793Y-630055D01*
X125363Y-630138D01*
X125870Y-630055D01*
X126377Y-629638D01*
X126693Y-629138D01*
X126757Y-628638D01*
X126630Y-628055D01*
X126187Y-627638D01*
X125743Y-627471D01*
X125173D01*
G01X125743D02*
X126123Y-627221D01*
X126440Y-626805D01*
X126567Y-626305D01*
X126440Y-625805D01*
X126123Y-625388D01*
X125553Y-625138D01*
X124983Y-625221D01*
X124413Y-625555D01*
G01X130717Y-631805D02*
X131350Y-630971D01*
X131667Y-630138D01*
Y-626805D01*
X131350Y-625971D01*
X130717Y-625138D01*
G01X134107Y-629138D02*
X134487Y-629721D01*
X134993Y-630055D01*
X135563Y-630138D01*
X136070Y-630055D01*
X136577Y-629638D01*
X136893Y-629138D01*
X136957Y-628638D01*
X136830Y-628055D01*
X136387Y-627638D01*
X135943Y-627471D01*
X135373D01*
G01X135943D02*
X136323Y-627221D01*
X136640Y-626805D01*
X136767Y-626305D01*
X136640Y-625805D01*
X136323Y-625388D01*
X135753Y-625138D01*
X135183Y-625221D01*
X134613Y-625555D01*
G01X139523Y-629555D02*
X139967Y-629971D01*
X140473Y-630138D01*
X140980Y-629971D01*
X141423Y-629471D01*
X141740Y-628721D01*
X141867Y-627971D01*
Y-627055D01*
X141740Y-626305D01*
X141423Y-625638D01*
X141043Y-625305D01*
X140600Y-625138D01*
X140093Y-625305D01*
X139713Y-625638D01*
X139460Y-626138D01*
X139333Y-626805D01*
X139460Y-627388D01*
X139777Y-627971D01*
X140157Y-628305D01*
X140600Y-628388D01*
X141107Y-628221D01*
X141487Y-627805D01*
X141867Y-627055D01*
G01X145573Y-630138D02*
X145700Y-629055D01*
X145890Y-628138D01*
X146143Y-627305D01*
X146460Y-626388D01*
X146967Y-625138D01*
X144433D01*
G01X149977Y-628471D02*
X151623D01*
G01X154507Y-629138D02*
X154887Y-629721D01*
X155393Y-630055D01*
X155963Y-630138D01*
X156470Y-630055D01*
X156977Y-629638D01*
X157293Y-629138D01*
X157357Y-628638D01*
X157230Y-628055D01*
X156787Y-627638D01*
X156343Y-627471D01*
X155773D01*
G01X156343D02*
X156723Y-627221D01*
X157040Y-626805D01*
X157167Y-626305D01*
X157040Y-625805D01*
X156723Y-625388D01*
X156153Y-625138D01*
X155583Y-625221D01*
X155013Y-625555D01*
G01X159797Y-628055D02*
X160240Y-627471D01*
X160620Y-627138D01*
X161127Y-626971D01*
X161570Y-627138D01*
X161887Y-627471D01*
X162140Y-627971D01*
X162203Y-628555D01*
X162140Y-629055D01*
X161887Y-629555D01*
X161507Y-629971D01*
X161063Y-630138D01*
X160557Y-629971D01*
X160113Y-629471D01*
X159860Y-628721D01*
X159797Y-627888D01*
X159923Y-626805D01*
X160113Y-626221D01*
X160430Y-625638D01*
X160873Y-625221D01*
X161317Y-625138D01*
X161760Y-625305D01*
X162077Y-625721D01*
G01X166100Y-630138D02*
Y-625138D01*
X165340Y-626138D01*
G01Y-630138D02*
X166860D01*
G01X171960D02*
Y-625138D01*
X169617Y-628721D01*
X172783D01*
G01X-4000Y-560138D02*
Y-635138D01*
X496000D01*
Y-560138D01*
X-4000D01*
G01X191000D02*
Y-635138D01*
G01Y-610138D02*
X294000D01*
Y-585138D01*
G01X191000D02*
X294000D01*
G01X296000Y-560138D02*
Y-635138D01*
G01X294000Y-560138D02*
Y-635138D01*
G01X301507Y-620138D02*
Y-615138D01*
X302773D01*
X303280Y-615388D01*
X303660Y-615721D01*
X303977Y-616221D01*
X304230Y-616805D01*
X304293Y-617638D01*
X304230Y-618471D01*
X303977Y-619055D01*
X303660Y-619555D01*
X303280Y-619888D01*
X302773Y-620138D01*
X301507D01*
G01X306417D02*
X308000Y-615138D01*
X309583Y-620138D01*
G01X309013Y-618388D02*
X306987D01*
G01X313100Y-615138D02*
Y-620138D01*
G01X311643Y-615138D02*
X314557D01*
G01X319467Y-620138D02*
X316933D01*
Y-615138D01*
X319467D01*
G01X318453Y-617555D02*
X316933D01*
G01X323300Y-620305D02*
X323173Y-620221D01*
Y-620055D01*
X323300Y-619971D01*
X323427Y-620055D01*
Y-620221D01*
X323300Y-620305D01*
G01Y-618055D02*
X323173Y-617971D01*
Y-617805D01*
X323300Y-617721D01*
X323427Y-617805D01*
Y-617971D01*
X323300Y-618055D01*
G01X296000Y-610138D02*
X496000D01*
G01X301633Y-595138D02*
Y-590138D01*
X303153D01*
X303660Y-590388D01*
X304040Y-590971D01*
X304167Y-591638D01*
X304040Y-592305D01*
X303723Y-592805D01*
X303153Y-593055D01*
X301633D01*
G01X306860Y-595305D02*
X309140Y-590138D01*
G01X311643Y-595138D02*
Y-590138D01*
X314557Y-595138D01*
Y-590138D01*
G01X318200Y-595305D02*
X318073Y-595221D01*
Y-595055D01*
X318200Y-594971D01*
X318327Y-595055D01*
Y-595221D01*
X318200Y-595305D01*
G01Y-593055D02*
X318073Y-592971D01*
Y-592805D01*
X318200Y-592721D01*
X318327Y-592805D01*
Y-592971D01*
X318200Y-593055D01*
G01X296000Y-585138D02*
X496000D01*
G01X301633Y-570138D02*
Y-565138D01*
X303153D01*
X303660Y-565388D01*
X304040Y-565971D01*
X304167Y-566638D01*
X304040Y-567305D01*
X303723Y-567805D01*
X303153Y-568055D01*
X301633D01*
G01X306733Y-570138D02*
Y-565138D01*
X308317D01*
X308823Y-565388D01*
X309140Y-565721D01*
X309267Y-566388D01*
X309140Y-567055D01*
X308760Y-567471D01*
X308317Y-567721D01*
X306733D01*
G01X308317D02*
X309267Y-570138D01*
G01X313100D02*
X312593Y-570055D01*
X312150Y-569721D01*
X311770Y-569221D01*
X311517Y-568638D01*
X311390Y-567971D01*
Y-567305D01*
X311517Y-566638D01*
X311770Y-566055D01*
X312150Y-565555D01*
X312593Y-565221D01*
X313100Y-565138D01*
X313607Y-565221D01*
X314050Y-565555D01*
X314430Y-566055D01*
X314683Y-566638D01*
X314810Y-567305D01*
Y-567971D01*
X314683Y-568638D01*
X314430Y-569221D01*
X314050Y-569721D01*
X313607Y-570055D01*
X313100Y-570138D01*
G01X316933Y-569138D02*
X317250Y-569638D01*
X317630Y-569971D01*
X318073Y-570138D01*
X318580Y-569971D01*
X318960Y-569638D01*
X319340Y-569138D01*
X319467Y-568471D01*
Y-565138D01*
G01X324567Y-570138D02*
X322033D01*
Y-565138D01*
X324567D01*
G01X323553Y-567555D02*
X322033D01*
G01X329793Y-565555D02*
X329413Y-565305D01*
X328970Y-565138D01*
X328463D01*
X327893Y-565388D01*
X327450Y-565805D01*
X327133Y-566305D01*
X326880Y-567138D01*
X326817Y-567888D01*
X326943Y-568638D01*
X327133Y-569138D01*
X327513Y-569638D01*
X327957Y-569971D01*
X328400Y-570138D01*
X328843D01*
X329287Y-569971D01*
X329667Y-569721D01*
X329983Y-569388D01*
G01X333500Y-565138D02*
Y-570138D01*
G01X332043Y-565138D02*
X334957D01*
G01X338600Y-570305D02*
X338473Y-570221D01*
Y-570055D01*
X338600Y-569971D01*
X338727Y-570055D01*
Y-570221D01*
X338600Y-570305D01*
G01Y-568055D02*
X338473Y-567971D01*
Y-567805D01*
X338600Y-567721D01*
X338727Y-567805D01*
Y-567971D01*
X338600Y-568055D01*
G01X411000Y-610138D02*
Y-635138D01*
G01X413633Y-612638D02*
Y-617638D01*
X416167D01*
G01X419240Y-612638D02*
X420760D01*
G01X420000D02*
Y-617638D01*
G01X419240D02*
X420760D01*
G01X425607Y-614971D02*
X425860Y-614721D01*
X426050Y-614305D01*
X426177Y-613721D01*
X426050Y-613221D01*
X425797Y-612888D01*
X425353Y-612638D01*
X423643D01*
Y-617638D01*
X425733D01*
X426177Y-617305D01*
X426430Y-616805D01*
X426557Y-616221D01*
X426430Y-615638D01*
X426050Y-615138D01*
X425607Y-614971D01*
X423643D01*
G01X430200Y-617805D02*
X430073Y-617721D01*
Y-617555D01*
X430200Y-617471D01*
X430327Y-617555D01*
Y-617721D01*
X430200Y-617805D01*
G01Y-615555D02*
X430073Y-615471D01*
Y-615305D01*
X430200Y-615221D01*
X430327Y-615305D01*
Y-615471D01*
X430200Y-615555D01*
G01X454000Y-610138D02*
Y-635138D01*
G01Y-585138D02*
Y-610138D01*
G01X459013Y-637305D02*
X459120Y-637180D01*
X459200Y-636971D01*
X459253Y-636680D01*
X459200Y-636430D01*
X459093Y-636263D01*
X458907Y-636138D01*
X458187D01*
Y-638638D01*
X459067D01*
X459253Y-638471D01*
X459360Y-638221D01*
X459413Y-637930D01*
X459360Y-637638D01*
X459200Y-637388D01*
X459013Y-637305D01*
X458187D01*
G01X461480Y-638638D02*
Y-636971D01*
G01Y-637263D02*
X461373Y-637096D01*
X461213Y-637013D01*
X461027Y-636971D01*
X460840Y-637055D01*
X460680Y-637221D01*
X460573Y-637471D01*
X460520Y-637805D01*
X460573Y-638138D01*
X460680Y-638388D01*
X460840Y-638555D01*
X461027Y-638638D01*
X461213Y-638596D01*
X461373Y-638471D01*
X461480Y-638305D01*
G01X462800Y-638346D02*
X462933Y-638513D01*
X463120Y-638638D01*
X463280D01*
X463440Y-638555D01*
X463547Y-638430D01*
X463600Y-638263D01*
X463573Y-638013D01*
X463467Y-637888D01*
X462987Y-637638D01*
X462880Y-637346D01*
X462933Y-637138D01*
X463040Y-637013D01*
X463200Y-636971D01*
X463360Y-637013D01*
X463520Y-637138D01*
G01X465000Y-637513D02*
X465853D01*
X465773Y-637221D01*
X465640Y-637055D01*
X465453Y-636971D01*
X465267Y-637013D01*
X465107Y-637138D01*
X465000Y-637430D01*
X464947Y-637680D01*
Y-637930D01*
X465000Y-638180D01*
X465133Y-638430D01*
X465293Y-638596D01*
X465480Y-638638D01*
X465667Y-638555D01*
X465853Y-638305D01*
G01X467120Y-638638D02*
Y-636138D01*
G01Y-637388D02*
X467253Y-637138D01*
X467413Y-637013D01*
X467573Y-636971D01*
X467813Y-637055D01*
X467973Y-637221D01*
X468080Y-637513D01*
Y-637846D01*
X468027Y-638180D01*
X467920Y-638430D01*
X467733Y-638596D01*
X467573Y-638638D01*
X467413Y-638596D01*
X467253Y-638471D01*
X467120Y-638263D01*
G01X469800Y-638638D02*
X469640Y-638596D01*
X469480Y-638430D01*
X469373Y-638138D01*
X469320Y-637805D01*
X469373Y-637471D01*
X469480Y-637180D01*
X469640Y-637013D01*
X469800Y-636971D01*
X469960Y-637013D01*
X470120Y-637180D01*
X470227Y-637471D01*
X470253Y-637805D01*
X470227Y-638138D01*
X470120Y-638430D01*
X469960Y-638596D01*
X469800Y-638638D01*
G01X472480D02*
Y-636971D01*
G01Y-637263D02*
X472373Y-637096D01*
X472213Y-637013D01*
X472027Y-636971D01*
X471840Y-637055D01*
X471680Y-637221D01*
X471573Y-637471D01*
X471520Y-637805D01*
X471573Y-638138D01*
X471680Y-638388D01*
X471840Y-638555D01*
X472027Y-638638D01*
X472213Y-638596D01*
X472373Y-638471D01*
X472480Y-638305D01*
G01X473827Y-638638D02*
Y-636971D01*
G01Y-637305D02*
X473960Y-637138D01*
X474093Y-637013D01*
X474280Y-636971D01*
X474413Y-637013D01*
X474573Y-637138D01*
G01X476880Y-636138D02*
Y-638638D01*
G01Y-638263D02*
X476773Y-638471D01*
X476613Y-638596D01*
X476427Y-638638D01*
X476213Y-638555D01*
X476053Y-638346D01*
X475947Y-638096D01*
X475920Y-637805D01*
X475947Y-637513D01*
X476053Y-637263D01*
X476213Y-637055D01*
X476427Y-636971D01*
X476613Y-637013D01*
X476747Y-637096D01*
X476880Y-637263D01*
G01X480267Y-638638D02*
Y-636138D01*
X480933D01*
X481147Y-636263D01*
X481280Y-636430D01*
X481333Y-636763D01*
X481280Y-637096D01*
X481120Y-637305D01*
X480933Y-637430D01*
X480267D01*
G01X480933D02*
X481333Y-638638D01*
G01X482600Y-637513D02*
X483453D01*
X483373Y-637221D01*
X483240Y-637055D01*
X483053Y-636971D01*
X482867Y-637013D01*
X482707Y-637138D01*
X482600Y-637430D01*
X482547Y-637680D01*
Y-637930D01*
X482600Y-638180D01*
X482733Y-638430D01*
X482893Y-638596D01*
X483080Y-638638D01*
X483267Y-638555D01*
X483453Y-638305D01*
G01X484720Y-636971D02*
X485200Y-638638D01*
X485680Y-636971D01*
G01X487400Y-638721D02*
X487347Y-638680D01*
Y-638596D01*
X487400Y-638555D01*
X487453Y-638596D01*
Y-638680D01*
X487400Y-638721D01*
G01X489147Y-638346D02*
X489333Y-638555D01*
X489547Y-638638D01*
X489760Y-638555D01*
X489947Y-638305D01*
X490080Y-637930D01*
X490133Y-637555D01*
Y-637096D01*
X490080Y-636721D01*
X489947Y-636388D01*
X489787Y-636221D01*
X489600Y-636138D01*
X489387Y-636221D01*
X489227Y-636388D01*
X489120Y-636638D01*
X489067Y-636971D01*
X489120Y-637263D01*
X489253Y-637555D01*
X489413Y-637721D01*
X489600Y-637763D01*
X489813Y-637680D01*
X489973Y-637471D01*
X490133Y-637096D01*
G01X492013Y-637305D02*
X492120Y-637180D01*
X492200Y-636971D01*
X492253Y-636680D01*
X492200Y-636430D01*
X492093Y-636263D01*
X491907Y-636138D01*
X491187D01*
Y-638638D01*
X492067D01*
X492253Y-638471D01*
X492360Y-638221D01*
X492413Y-637930D01*
X492360Y-637638D01*
X492200Y-637388D01*
X492013Y-637305D01*
X491187D01*
G01X457900Y-612638D02*
Y-617638D01*
G01X456443Y-612638D02*
X459357D01*
G01X463000Y-617638D02*
X462620Y-617555D01*
X462240Y-617221D01*
X461987Y-616638D01*
X461860Y-615971D01*
X461987Y-615305D01*
X462240Y-614721D01*
X462620Y-614388D01*
X463000Y-614305D01*
X463380Y-614388D01*
X463760Y-614721D01*
X464013Y-615305D01*
X464077Y-615971D01*
X464013Y-616638D01*
X463760Y-617221D01*
X463380Y-617555D01*
X463000Y-617638D01*
G01X468100D02*
X467720Y-617555D01*
X467340Y-617221D01*
X467087Y-616638D01*
X466960Y-615971D01*
X467087Y-615305D01*
X467340Y-614721D01*
X467720Y-614388D01*
X468100Y-614305D01*
X468480Y-614388D01*
X468860Y-614721D01*
X469113Y-615305D01*
X469177Y-615971D01*
X469113Y-616638D01*
X468860Y-617221D01*
X468480Y-617555D01*
X468100Y-617638D01*
G01X473200D02*
Y-612638D01*
G01X478300Y-617805D02*
X478173Y-617721D01*
Y-617555D01*
X478300Y-617471D01*
X478427Y-617555D01*
Y-617721D01*
X478300Y-617805D01*
G01Y-615555D02*
X478173Y-615471D01*
Y-615305D01*
X478300Y-615221D01*
X478427Y-615305D01*
Y-615471D01*
X478300Y-615555D01*
G01X456633Y-592638D02*
Y-587638D01*
X458217D01*
X458723Y-587888D01*
X459040Y-588221D01*
X459167Y-588888D01*
X459040Y-589555D01*
X458660Y-589971D01*
X458217Y-590221D01*
X456633D01*
G01X458217D02*
X459167Y-592638D01*
G01X464267D02*
X461733D01*
Y-587638D01*
X464267D01*
G01X463253Y-590055D02*
X461733D01*
G01X466517Y-587638D02*
X468100Y-592638D01*
X469683Y-587638D01*
G01X473200Y-592805D02*
X473073Y-592721D01*
Y-592555D01*
X473200Y-592471D01*
X473327Y-592555D01*
Y-592721D01*
X473200Y-592805D01*
G01Y-590555D02*
X473073Y-590471D01*
Y-590305D01*
X473200Y-590221D01*
X473327Y-590305D01*
Y-590471D01*
X473200Y-590555D01*
G01X-476840Y-884638D02*
Y2768362D01*
X5911000D01*
Y-884638D01*
X-476840D01*
G01X8820Y-607488D02*
X10387D01*
Y-609378D01*
X9917Y-610008D01*
X9368Y-610428D01*
X8585Y-610638D01*
X7802Y-610428D01*
X7253Y-610008D01*
X6783Y-609378D01*
X6470Y-608643D01*
X6313Y-607803D01*
Y-607068D01*
X6470Y-606438D01*
X6783Y-605703D01*
X7253Y-605073D01*
X7723Y-604653D01*
X8350Y-604338D01*
X8898D01*
X9525Y-604548D01*
X9995Y-604968D01*
G01X12927Y-604338D02*
Y-608853D01*
X13240Y-609798D01*
X13867Y-610428D01*
X14650Y-610638D01*
X15433Y-610428D01*
X16060Y-609798D01*
X16373Y-608853D01*
Y-604338D01*
G01X20010D02*
X21890D01*
G01X20950D02*
Y-610638D01*
G01X20010D02*
X21890D01*
G01X25605Y-609798D02*
X26232Y-610323D01*
X26937Y-610638D01*
X27563D01*
X28190Y-610323D01*
X28660Y-609798D01*
X28895Y-609063D01*
X28738Y-608328D01*
X28347Y-607698D01*
X27642Y-607278D01*
X26702Y-607068D01*
X26153Y-606648D01*
X25918Y-605913D01*
X26075Y-605178D01*
X26467Y-604653D01*
X27015Y-604338D01*
X27563D01*
X28112Y-604548D01*
X28582Y-605073D01*
G01X31905Y-610638D02*
Y-604338D01*
G01X35195D02*
Y-610638D01*
G01Y-607488D02*
X31905D01*
G01X37892Y-610638D02*
X39850Y-604338D01*
X41808Y-610638D01*
G01X41103Y-608433D02*
X38597D01*
G01X44348Y-610638D02*
Y-604338D01*
X47952Y-610638D01*
Y-604338D01*
G01X57027Y-610638D02*
Y-604338D01*
X58593D01*
X59220Y-604653D01*
X59690Y-605073D01*
X60082Y-605703D01*
X60395Y-606438D01*
X60473Y-607488D01*
X60395Y-608538D01*
X60082Y-609273D01*
X59690Y-609903D01*
X59220Y-610323D01*
X58593Y-610638D01*
X57027D01*
G01X64110Y-604338D02*
X65990D01*
G01X65050D02*
Y-610638D01*
G01X64110D02*
X65990D01*
G01X69705Y-609798D02*
X70332Y-610323D01*
X71037Y-610638D01*
X71663D01*
X72290Y-610323D01*
X72760Y-609798D01*
X72995Y-609063D01*
X72838Y-608328D01*
X72447Y-607698D01*
X71742Y-607278D01*
X70802Y-607068D01*
X70253Y-606648D01*
X70018Y-605913D01*
X70175Y-605178D01*
X70567Y-604653D01*
X71115Y-604338D01*
X71663D01*
X72212Y-604548D01*
X72682Y-605073D01*
G01X77650Y-604338D02*
Y-610638D01*
G01X75848Y-604338D02*
X79452D01*
G01X83950Y-610848D02*
X83793Y-610743D01*
Y-610533D01*
X83950Y-610428D01*
X84107Y-610533D01*
Y-610743D01*
X83950Y-610848D01*
G01X90093Y-611793D02*
X90407Y-610428D01*
G01X96550Y-604338D02*
Y-610638D01*
G01X94748Y-604338D02*
X98352D01*
G01X100892Y-610638D02*
X102850Y-604338D01*
X104808Y-610638D01*
G01X104103Y-608433D02*
X101597D01*
G01X109150Y-610638D02*
X108523Y-610533D01*
X107975Y-610113D01*
X107505Y-609483D01*
X107192Y-608748D01*
X107035Y-607908D01*
Y-607068D01*
X107192Y-606228D01*
X107505Y-605493D01*
X107975Y-604863D01*
X108523Y-604443D01*
X109150Y-604338D01*
X109777Y-604443D01*
X110325Y-604863D01*
X110795Y-605493D01*
X111108Y-606228D01*
X111265Y-607068D01*
Y-607908D01*
X111108Y-608748D01*
X110795Y-609483D01*
X110325Y-610113D01*
X109777Y-610533D01*
X109150Y-610638D01*
G01X115450D02*
Y-607803D01*
X113883Y-604338D01*
G01X117017D02*
X115450Y-607803D01*
G01X120027Y-604338D02*
Y-608853D01*
X120340Y-609798D01*
X120967Y-610428D01*
X121750Y-610638D01*
X122533Y-610428D01*
X123160Y-609798D01*
X123473Y-608853D01*
Y-604338D01*
G01X126092Y-610638D02*
X128050Y-604338D01*
X130008Y-610638D01*
G01X129303Y-608433D02*
X126797D01*
G01X132548Y-610638D02*
Y-604338D01*
X136152Y-610638D01*
Y-604338D01*
G01X10073Y-614863D02*
X9603Y-614548D01*
X9055Y-614338D01*
X8428D01*
X7723Y-614653D01*
X7175Y-615178D01*
X6783Y-615808D01*
X6470Y-616858D01*
X6392Y-617803D01*
X6548Y-618748D01*
X6783Y-619378D01*
X7253Y-620008D01*
X7802Y-620428D01*
X8350Y-620638D01*
X8898D01*
X9447Y-620428D01*
X9917Y-620113D01*
X10308Y-619693D01*
G01X13710Y-614338D02*
X15590D01*
G01X14650D02*
Y-620638D01*
G01X13710D02*
X15590D01*
G01X20950Y-614338D02*
Y-620638D01*
G01X19148Y-614338D02*
X22752D01*
G01X27250Y-620638D02*
Y-617803D01*
X25683Y-614338D01*
G01X28817D02*
X27250Y-617803D01*
G01X38127Y-619378D02*
X38597Y-620113D01*
X39223Y-620533D01*
X39928Y-620638D01*
X40555Y-620533D01*
X41182Y-620008D01*
X41573Y-619378D01*
X41652Y-618748D01*
X41495Y-618013D01*
X40947Y-617488D01*
X40398Y-617278D01*
X39693D01*
G01X40398D02*
X40868Y-616963D01*
X41260Y-616438D01*
X41417Y-615808D01*
X41260Y-615178D01*
X40868Y-614653D01*
X40163Y-614338D01*
X39458Y-614443D01*
X38753Y-614863D01*
G01X44427Y-619378D02*
X44897Y-620113D01*
X45523Y-620533D01*
X46228Y-620638D01*
X46855Y-620533D01*
X47482Y-620008D01*
X47873Y-619378D01*
X47952Y-618748D01*
X47795Y-618013D01*
X47247Y-617488D01*
X46698Y-617278D01*
X45993D01*
G01X46698D02*
X47168Y-616963D01*
X47560Y-616438D01*
X47717Y-615808D01*
X47560Y-615178D01*
X47168Y-614653D01*
X46463Y-614338D01*
X45758Y-614443D01*
X45053Y-614863D01*
G01X50727Y-619378D02*
X51197Y-620113D01*
X51823Y-620533D01*
X52528Y-620638D01*
X53155Y-620533D01*
X53782Y-620008D01*
X54173Y-619378D01*
X54252Y-618748D01*
X54095Y-618013D01*
X53547Y-617488D01*
X52998Y-617278D01*
X52293D01*
G01X52998D02*
X53468Y-616963D01*
X53860Y-616438D01*
X54017Y-615808D01*
X53860Y-615178D01*
X53468Y-614653D01*
X52763Y-614338D01*
X52058Y-614443D01*
X51353Y-614863D01*
G01X58593Y-620638D02*
X58750Y-619273D01*
X58985Y-618118D01*
X59298Y-617068D01*
X59690Y-615913D01*
X60317Y-614338D01*
X57183D01*
G01X64893Y-620638D02*
X65050Y-619273D01*
X65285Y-618118D01*
X65598Y-617068D01*
X65990Y-615913D01*
X66617Y-614338D01*
X63483D01*
G01X71193Y-621793D02*
X71507Y-620428D01*
G01X77650Y-614338D02*
Y-620638D01*
G01X75848Y-614338D02*
X79452D01*
G01X81992Y-620638D02*
X83950Y-614338D01*
X85908Y-620638D01*
G01X85203Y-618433D02*
X82697D01*
G01X89310Y-614338D02*
X91190D01*
G01X90250D02*
Y-620638D01*
G01X89310D02*
X91190D01*
G01X94200Y-614338D02*
X95297Y-620638D01*
X96550Y-614338D01*
X97803Y-620638D01*
X98900Y-614338D01*
G01X100892Y-620638D02*
X102850Y-614338D01*
X104808Y-620638D01*
G01X104103Y-618433D02*
X101597D01*
G01X107348Y-620638D02*
Y-614338D01*
X110952Y-620638D01*
Y-614338D01*
G01X121358Y-622738D02*
X120575Y-621688D01*
X120183Y-620638D01*
Y-616438D01*
X120575Y-615388D01*
X121358Y-614338D01*
G01X132783Y-620638D02*
Y-614338D01*
X134742D01*
X135368Y-614653D01*
X135760Y-615073D01*
X135917Y-615913D01*
X135760Y-616753D01*
X135290Y-617278D01*
X134742Y-617593D01*
X132783D01*
G01X134742D02*
X135917Y-620638D01*
G01X140650Y-620848D02*
X140493Y-620743D01*
Y-620533D01*
X140650Y-620428D01*
X140807Y-620533D01*
Y-620743D01*
X140650Y-620848D01*
G01X146950Y-620638D02*
X146323Y-620533D01*
X145775Y-620113D01*
X145305Y-619483D01*
X144992Y-618748D01*
X144835Y-617908D01*
Y-617068D01*
X144992Y-616228D01*
X145305Y-615493D01*
X145775Y-614863D01*
X146323Y-614443D01*
X146950Y-614338D01*
X147577Y-614443D01*
X148125Y-614863D01*
X148595Y-615493D01*
X148908Y-616228D01*
X149065Y-617068D01*
Y-617908D01*
X148908Y-618748D01*
X148595Y-619483D01*
X148125Y-620113D01*
X147577Y-620533D01*
X146950Y-620638D01*
G01X153250Y-620848D02*
X153093Y-620743D01*
Y-620533D01*
X153250Y-620428D01*
X153407Y-620533D01*
Y-620743D01*
X153250Y-620848D01*
G01X161273Y-614863D02*
X160803Y-614548D01*
X160255Y-614338D01*
X159628D01*
X158923Y-614653D01*
X158375Y-615178D01*
X157983Y-615808D01*
X157670Y-616858D01*
X157592Y-617803D01*
X157748Y-618748D01*
X157983Y-619378D01*
X158453Y-620008D01*
X159002Y-620428D01*
X159550Y-620638D01*
X160098D01*
X160647Y-620428D01*
X161117Y-620113D01*
X161508Y-619693D01*
G01X165850Y-620848D02*
X165693Y-620743D01*
Y-620533D01*
X165850Y-620428D01*
X166007Y-620533D01*
Y-620743D01*
X165850Y-620848D01*
G01X172542Y-622738D02*
X173325Y-621688D01*
X173717Y-620638D01*
Y-616438D01*
X173325Y-615388D01*
X172542Y-614338D01*
G01X6548Y-600638D02*
Y-594338D01*
X10152Y-600638D01*
Y-594338D01*
G01X14650Y-600638D02*
X14023Y-600533D01*
X13475Y-600113D01*
X13005Y-599483D01*
X12692Y-598748D01*
X12535Y-597908D01*
Y-597068D01*
X12692Y-596228D01*
X13005Y-595493D01*
X13475Y-594863D01*
X14023Y-594443D01*
X14650Y-594338D01*
X15277Y-594443D01*
X15825Y-594863D01*
X16295Y-595493D01*
X16608Y-596228D01*
X16765Y-597068D01*
Y-597908D01*
X16608Y-598748D01*
X16295Y-599483D01*
X15825Y-600113D01*
X15277Y-600533D01*
X14650Y-600638D01*
G01X20950Y-600848D02*
X20793Y-600743D01*
Y-600533D01*
X20950Y-600428D01*
X21107Y-600533D01*
Y-600743D01*
X20950Y-600848D01*
G01X25762Y-595388D02*
X26232Y-594758D01*
X26780Y-594443D01*
X27407Y-594338D01*
X28190Y-594548D01*
X28738Y-595073D01*
X28895Y-595703D01*
X28817Y-596333D01*
X28503Y-596858D01*
X26937Y-597908D01*
X26232Y-598643D01*
X25762Y-599693D01*
X25605Y-600638D01*
X28895D01*
G01X33550D02*
Y-594338D01*
X32610Y-595598D01*
G01Y-600638D02*
X34490D01*
G01X39850D02*
Y-594338D01*
X38910Y-595598D01*
G01Y-600638D02*
X40790D01*
G01X45993Y-601793D02*
X46307Y-600428D01*
G01X50100Y-594338D02*
X51197Y-600638D01*
X52450Y-594338D01*
X53703Y-600638D01*
X54800Y-594338D01*
G01X60317Y-600638D02*
X57183D01*
Y-594338D01*
X60317D01*
G01X59063Y-597383D02*
X57183D01*
G01X63248Y-600638D02*
Y-594338D01*
X66852Y-600638D01*
Y-594338D01*
G01X69705Y-600638D02*
Y-594338D01*
G01X72995D02*
Y-600638D01*
G01Y-597488D02*
X69705D01*
G01X75927Y-594338D02*
Y-598853D01*
X76240Y-599798D01*
X76867Y-600428D01*
X77650Y-600638D01*
X78433Y-600428D01*
X79060Y-599798D01*
X79373Y-598853D01*
Y-594338D01*
G01X81992Y-600638D02*
X83950Y-594338D01*
X85908Y-600638D01*
G01X85203Y-598433D02*
X82697D01*
G01X95062Y-595388D02*
X95532Y-594758D01*
X96080Y-594443D01*
X96707Y-594338D01*
X97490Y-594548D01*
X98038Y-595073D01*
X98195Y-595703D01*
X98117Y-596333D01*
X97803Y-596858D01*
X96237Y-597908D01*
X95532Y-598643D01*
X95062Y-599693D01*
X94905Y-600638D01*
X98195D01*
G01X101048D02*
Y-594338D01*
X104652Y-600638D01*
Y-594338D01*
G01X107427Y-600638D02*
Y-594338D01*
X108993D01*
X109620Y-594653D01*
X110090Y-595073D01*
X110482Y-595703D01*
X110795Y-596438D01*
X110873Y-597488D01*
X110795Y-598538D01*
X110482Y-599273D01*
X110090Y-599903D01*
X109620Y-600323D01*
X108993Y-600638D01*
X107427D01*
G01X120183D02*
Y-594338D01*
X122142D01*
X122768Y-594653D01*
X123160Y-595073D01*
X123317Y-595913D01*
X123160Y-596753D01*
X122690Y-597278D01*
X122142Y-597593D01*
X120183D01*
G01X122142D02*
X123317Y-600638D01*
G01X126327D02*
Y-594338D01*
X127893D01*
X128520Y-594653D01*
X128990Y-595073D01*
X129382Y-595703D01*
X129695Y-596438D01*
X129773Y-597488D01*
X129695Y-598538D01*
X129382Y-599273D01*
X128990Y-599903D01*
X128520Y-600323D01*
X127893Y-600638D01*
X126327D01*
G01X134350Y-600848D02*
X134193Y-600743D01*
Y-600533D01*
X134350Y-600428D01*
X134507Y-600533D01*
Y-600743D01*
X134350Y-600848D01*
G01X30650Y-589938D02*
X28130Y-589521D01*
X25925Y-587855D01*
X24035Y-585355D01*
X22775Y-582438D01*
X22145Y-579105D01*
Y-575771D01*
X22775Y-572438D01*
X24035Y-569521D01*
X25925Y-567022D01*
X28130Y-565355D01*
X30650Y-564938D01*
X33170Y-565355D01*
X35375Y-567022D01*
X37265Y-569521D01*
X38525Y-572438D01*
X39155Y-575771D01*
Y-579105D01*
X38525Y-582438D01*
X37265Y-585355D01*
X35375Y-587855D01*
X33170Y-589521D01*
X30650Y-589938D01*
G01X33170Y-583271D02*
X36950Y-589938D01*
G01X50495Y-573272D02*
Y-584938D01*
X51755Y-587855D01*
X53645Y-589521D01*
X55850Y-589938D01*
X58055Y-589521D01*
X59945Y-587855D01*
X61205Y-584938D01*
G01Y-589938D02*
Y-573272D01*
G01X86720Y-589938D02*
Y-573272D01*
G01Y-576188D02*
X85460Y-574522D01*
X83570Y-573688D01*
X81365Y-573272D01*
X79160Y-574105D01*
X77270Y-575771D01*
X76010Y-578272D01*
X75380Y-581605D01*
X76010Y-584938D01*
X77270Y-587439D01*
X79160Y-589105D01*
X81365Y-589938D01*
X83570Y-589521D01*
X85460Y-588272D01*
X86720Y-586605D01*
G01X100895Y-589938D02*
Y-573272D01*
G01Y-577438D02*
X102155Y-575355D01*
X104045Y-573688D01*
X106565Y-573272D01*
X108770Y-573688D01*
X110660Y-575355D01*
X111605Y-578272D01*
Y-589938D01*
G01X131450Y-564938D02*
Y-589938D01*
G01X127040Y-573272D02*
X135860D01*
G01X162320Y-589938D02*
Y-573272D01*
G01Y-576188D02*
X161060Y-574522D01*
X159170Y-573688D01*
X156965Y-573272D01*
X154760Y-574105D01*
X152870Y-575771D01*
X151610Y-578272D01*
X150980Y-581605D01*
X151610Y-584938D01*
X152870Y-587439D01*
X154760Y-589105D01*
X156965Y-589938D01*
X159170Y-589521D01*
X161060Y-588272D01*
X162320Y-586605D01*
G01X202000Y-569638D02*
Y-577638D01*
X206000D01*
G01X213800D02*
Y-572305D01*
G01Y-573238D02*
X213400Y-572705D01*
X212800Y-572438D01*
X212100Y-572305D01*
X211400Y-572571D01*
X210800Y-573105D01*
X210400Y-573905D01*
X210200Y-574971D01*
X210400Y-576038D01*
X210800Y-576838D01*
X211400Y-577371D01*
X212100Y-577638D01*
X212800Y-577505D01*
X213400Y-577105D01*
X213800Y-576572D01*
G01X217900Y-580038D02*
X218500Y-580305D01*
X219300Y-580038D01*
X219800Y-579505D01*
X220200Y-578838D01*
X220800Y-576705D01*
X222100Y-572305D01*
G01X218900D02*
X220800Y-576705D01*
G01X226500Y-574038D02*
X229700D01*
X229400Y-573105D01*
X228900Y-572571D01*
X228200Y-572305D01*
X227500Y-572438D01*
X226900Y-572838D01*
X226500Y-573771D01*
X226300Y-574572D01*
Y-575371D01*
X226500Y-576171D01*
X227000Y-576971D01*
X227600Y-577505D01*
X228300Y-577638D01*
X229000Y-577371D01*
X229700Y-576572D01*
G01X234600Y-577638D02*
Y-572305D01*
G01Y-573371D02*
X235100Y-572838D01*
X235600Y-572438D01*
X236300Y-572305D01*
X236800Y-572438D01*
X237400Y-572838D01*
G01X226000Y-626038D02*
X226500Y-626838D01*
X227100Y-627371D01*
X227800Y-627638D01*
X228600Y-627371D01*
X229200Y-626838D01*
X229800Y-626038D01*
X230000Y-624971D01*
Y-619638D01*
G01X237800Y-627638D02*
Y-622305D01*
G01Y-623238D02*
X237400Y-622705D01*
X236800Y-622438D01*
X236100Y-622305D01*
X235400Y-622571D01*
X234800Y-623105D01*
X234400Y-623905D01*
X234200Y-624971D01*
X234400Y-626038D01*
X234800Y-626838D01*
X235400Y-627371D01*
X236100Y-627638D01*
X236800Y-627505D01*
X237400Y-627105D01*
X237800Y-626572D01*
G01X245600Y-622971D02*
X244900Y-622438D01*
X244300Y-622305D01*
X243500Y-622571D01*
X242900Y-623105D01*
X242500Y-624038D01*
X242400Y-624971D01*
X242500Y-625905D01*
X242900Y-626705D01*
X243500Y-627371D01*
X244300Y-627638D01*
X245000Y-627371D01*
X245600Y-626838D01*
G01X250300Y-627638D02*
Y-619638D01*
G01X253500Y-622305D02*
X250300Y-625371D01*
G01X251600Y-624171D02*
X253700Y-627638D01*
G01X229300Y-597538D02*
X231300D01*
Y-599938D01*
X230700Y-600738D01*
X230000Y-601271D01*
X229000Y-601538D01*
X228000Y-601271D01*
X227300Y-600738D01*
X226700Y-599938D01*
X226300Y-599005D01*
X226100Y-597938D01*
Y-597005D01*
X226300Y-596205D01*
X226700Y-595271D01*
X227300Y-594471D01*
X227900Y-593938D01*
X228700Y-593538D01*
X229400D01*
X230200Y-593805D01*
X230800Y-594338D01*
G01X234400Y-601538D02*
Y-593538D01*
X239000Y-601538D01*
Y-593538D01*
G01X242500Y-601538D02*
Y-593538D01*
X244500D01*
X245300Y-593938D01*
X245900Y-594471D01*
X246400Y-595271D01*
X246800Y-596205D01*
X246900Y-597538D01*
X246800Y-598871D01*
X246400Y-599805D01*
X245900Y-600605D01*
X245300Y-601138D01*
X244500Y-601538D01*
X242500D01*
G01X250800Y-598205D02*
X251500Y-597271D01*
X252100Y-596738D01*
X252900Y-596471D01*
X253600Y-596738D01*
X254100Y-597271D01*
X254500Y-598071D01*
X254600Y-599005D01*
X254500Y-599805D01*
X254100Y-600605D01*
X253500Y-601271D01*
X252800Y-601538D01*
X252000Y-601271D01*
X251300Y-600472D01*
X250900Y-599271D01*
X250800Y-597938D01*
X251000Y-596205D01*
X251300Y-595271D01*
X251800Y-594338D01*
X252500Y-593671D01*
X253200Y-593538D01*
X253900Y-593805D01*
X254400Y-594471D01*
G01X260900Y-578138D02*
Y-570138D01*
X259700Y-571738D01*
G01Y-578138D02*
X262100D01*
G01X266700Y-576938D02*
X267300Y-577605D01*
X268000Y-578005D01*
X268900Y-578138D01*
X269800Y-577871D01*
X270500Y-577338D01*
X271000Y-576405D01*
X271100Y-575338D01*
X270900Y-574271D01*
X270400Y-573605D01*
X269700Y-573071D01*
X269000Y-572938D01*
X268300Y-573071D01*
X267400Y-573605D01*
X267700Y-570138D01*
X270400D01*
G01X328600Y-620971D02*
X329200Y-620171D01*
X329900Y-619771D01*
X330700Y-619638D01*
X331700Y-619905D01*
X332400Y-620571D01*
X332600Y-621371D01*
X332500Y-622172D01*
X332100Y-622838D01*
X330100Y-624171D01*
X329200Y-625105D01*
X328600Y-626438D01*
X328400Y-627638D01*
X332600D01*
G01X338500Y-619638D02*
X337700Y-619905D01*
X337100Y-620571D01*
X336700Y-621371D01*
X336400Y-622438D01*
X336300Y-623638D01*
X336400Y-624838D01*
X336700Y-625905D01*
X337100Y-626705D01*
X337700Y-627371D01*
X338500Y-627638D01*
X339300Y-627371D01*
X339900Y-626705D01*
X340300Y-625905D01*
X340600Y-624838D01*
X340700Y-623638D01*
X340600Y-622438D01*
X340300Y-621371D01*
X339900Y-620571D01*
X339300Y-619905D01*
X338500Y-619638D01*
G01X344600Y-620971D02*
X345200Y-620171D01*
X345900Y-619771D01*
X346700Y-619638D01*
X347700Y-619905D01*
X348400Y-620571D01*
X348600Y-621371D01*
X348500Y-622172D01*
X348100Y-622838D01*
X346100Y-624171D01*
X345200Y-625105D01*
X344600Y-626438D01*
X344400Y-627638D01*
X348600D01*
G01X352300Y-626038D02*
X352900Y-626971D01*
X353700Y-627505D01*
X354600Y-627638D01*
X355400Y-627505D01*
X356200Y-626838D01*
X356700Y-626038D01*
X356800Y-625238D01*
X356600Y-624305D01*
X355900Y-623638D01*
X355200Y-623371D01*
X354300D01*
G01X355200D02*
X355800Y-622971D01*
X356300Y-622305D01*
X356500Y-621505D01*
X356300Y-620705D01*
X355800Y-620038D01*
X354900Y-619638D01*
X354000Y-619771D01*
X353100Y-620305D01*
G01X360700Y-627905D02*
X364300Y-619638D01*
G01X370500D02*
X369700Y-619905D01*
X369100Y-620571D01*
X368700Y-621371D01*
X368400Y-622438D01*
X368300Y-623638D01*
X368400Y-624838D01*
X368700Y-625905D01*
X369100Y-626705D01*
X369700Y-627371D01*
X370500Y-627638D01*
X371300Y-627371D01*
X371900Y-626705D01*
X372300Y-625905D01*
X372600Y-624838D01*
X372700Y-623638D01*
X372600Y-622438D01*
X372300Y-621371D01*
X371900Y-620571D01*
X371300Y-619905D01*
X370500Y-619638D01*
G01X379700Y-627638D02*
Y-619638D01*
X376000Y-625371D01*
X381000D01*
G01X384700Y-627905D02*
X388300Y-619638D01*
G01X394500Y-627638D02*
Y-619638D01*
X393300Y-621238D01*
G01Y-627638D02*
X395700D01*
G01X402300D02*
X402500Y-625905D01*
X402800Y-624438D01*
X403200Y-623105D01*
X403700Y-621638D01*
X404500Y-619638D01*
X400500D01*
G01X328300Y-602638D02*
Y-594638D01*
X330300D01*
X331100Y-595038D01*
X331700Y-595571D01*
X332200Y-596371D01*
X332600Y-597305D01*
X332700Y-598638D01*
X332600Y-599971D01*
X332200Y-600905D01*
X331700Y-601705D01*
X331100Y-602238D01*
X330300Y-602638D01*
X328300D01*
G01X336000D02*
X338500Y-594638D01*
X341000Y-602638D01*
G01X340100Y-599838D02*
X336900D01*
G01X344600Y-602638D02*
Y-594638D01*
X348400D01*
G01X347000Y-598505D02*
X344600D01*
G01X354500Y-594638D02*
X353700Y-594905D01*
X353100Y-595571D01*
X352700Y-596371D01*
X352400Y-597438D01*
X352300Y-598638D01*
X352400Y-599838D01*
X352700Y-600905D01*
X353100Y-601705D01*
X353700Y-602371D01*
X354500Y-602638D01*
X355300Y-602371D01*
X355900Y-601705D01*
X356300Y-600905D01*
X356600Y-599838D01*
X356700Y-598638D01*
X356600Y-597438D01*
X356300Y-596371D01*
X355900Y-595571D01*
X355300Y-594905D01*
X354500Y-594638D01*
G01X362500D02*
Y-602638D01*
G01X360200Y-594638D02*
X364800D01*
G01X367900Y-602638D02*
Y-594638D01*
X370500Y-601305D01*
X373100Y-594638D01*
Y-602638D01*
G01X379300Y-598371D02*
X379700Y-597971D01*
X380000Y-597305D01*
X380200Y-596371D01*
X380000Y-595571D01*
X379600Y-595038D01*
X378900Y-594638D01*
X376200D01*
Y-602638D01*
X379500D01*
X380200Y-602105D01*
X380600Y-601305D01*
X380800Y-600371D01*
X380600Y-599438D01*
X380000Y-598638D01*
X379300Y-598371D01*
X376200D01*
G01X384300Y-601038D02*
X384900Y-601971D01*
X385700Y-602505D01*
X386600Y-602638D01*
X387400Y-602505D01*
X388200Y-601838D01*
X388700Y-601038D01*
X388800Y-600238D01*
X388600Y-599305D01*
X387900Y-598638D01*
X387200Y-598371D01*
X386300D01*
G01X387200D02*
X387800Y-597971D01*
X388300Y-597305D01*
X388500Y-596505D01*
X388300Y-595705D01*
X387800Y-595038D01*
X386900Y-594638D01*
X386000Y-594771D01*
X385100Y-595305D01*
G01X393300Y-594638D02*
X395700D01*
G01X394500D02*
Y-602638D01*
G01X393300D02*
X395700D01*
G01X404700Y-595305D02*
X404100Y-594905D01*
X403400Y-594638D01*
X402600D01*
X401700Y-595038D01*
X401000Y-595705D01*
X400500Y-596505D01*
X400100Y-597838D01*
X400000Y-599038D01*
X400200Y-600238D01*
X400500Y-601038D01*
X401100Y-601838D01*
X401800Y-602371D01*
X402500Y-602638D01*
X403200D01*
X403900Y-602371D01*
X404500Y-601971D01*
X405000Y-601438D01*
G01X410500Y-594638D02*
X409700Y-594905D01*
X409100Y-595571D01*
X408700Y-596371D01*
X408400Y-597438D01*
X408300Y-598638D01*
X408400Y-599838D01*
X408700Y-600905D01*
X409100Y-601705D01*
X409700Y-602371D01*
X410500Y-602638D01*
X411300Y-602371D01*
X411900Y-601705D01*
X412300Y-600905D01*
X412600Y-599838D01*
X412700Y-598638D01*
X412600Y-597438D01*
X412300Y-596371D01*
X411900Y-595571D01*
X411300Y-594905D01*
X410500Y-594638D01*
G01X346100Y-577638D02*
Y-569638D01*
X349900D01*
G01X348500Y-573505D02*
X346100D01*
G01X356000Y-569638D02*
X355200Y-569905D01*
X354600Y-570571D01*
X354200Y-571371D01*
X353900Y-572438D01*
X353800Y-573638D01*
X353900Y-574838D01*
X354200Y-575905D01*
X354600Y-576705D01*
X355200Y-577371D01*
X356000Y-577638D01*
X356800Y-577371D01*
X357400Y-576705D01*
X357800Y-575905D01*
X358100Y-574838D01*
X358200Y-573638D01*
X358100Y-572438D01*
X357800Y-571371D01*
X357400Y-570571D01*
X356800Y-569905D01*
X356000Y-569638D01*
G01X364000D02*
Y-577638D01*
G01X361700Y-569638D02*
X366300D01*
G01X372600Y-573638D02*
X374600D01*
Y-576038D01*
X374000Y-576838D01*
X373300Y-577371D01*
X372300Y-577638D01*
X371300Y-577371D01*
X370600Y-576838D01*
X370000Y-576038D01*
X369600Y-575105D01*
X369400Y-574038D01*
Y-573105D01*
X369600Y-572305D01*
X370000Y-571371D01*
X370600Y-570571D01*
X371200Y-570038D01*
X372000Y-569638D01*
X372700D01*
X373500Y-569905D01*
X374100Y-570438D01*
G01X377000Y-580305D02*
X383000D01*
G01X385400Y-577638D02*
Y-569638D01*
X388000Y-576305D01*
X390600Y-569638D01*
Y-577638D01*
G01X396800Y-573371D02*
X397200Y-572971D01*
X397500Y-572305D01*
X397700Y-571371D01*
X397500Y-570571D01*
X397100Y-570038D01*
X396400Y-569638D01*
X393700D01*
Y-577638D01*
X397000D01*
X397700Y-577105D01*
X398100Y-576305D01*
X398300Y-575371D01*
X398100Y-574438D01*
X397500Y-573638D01*
X396800Y-573371D01*
X393700D01*
G01X417000Y-630638D02*
Y-622638D01*
X415800Y-624238D01*
G01Y-630638D02*
X418200D01*
G01X423100Y-627305D02*
X423800Y-626371D01*
X424400Y-625838D01*
X425200Y-625571D01*
X425900Y-625838D01*
X426400Y-626371D01*
X426800Y-627171D01*
X426900Y-628105D01*
X426800Y-628905D01*
X426400Y-629705D01*
X425800Y-630371D01*
X425100Y-630638D01*
X424300Y-630371D01*
X423600Y-629572D01*
X423200Y-628371D01*
X423100Y-627038D01*
X423300Y-625305D01*
X423600Y-624371D01*
X424100Y-623438D01*
X424800Y-622771D01*
X425500Y-622638D01*
X426200Y-622905D01*
X426700Y-623571D01*
G01X433000Y-630905D02*
X432800Y-630771D01*
Y-630505D01*
X433000Y-630371D01*
X433200Y-630505D01*
Y-630771D01*
X433000Y-630905D01*
G01X439100Y-627305D02*
X439800Y-626371D01*
X440400Y-625838D01*
X441200Y-625571D01*
X441900Y-625838D01*
X442400Y-626371D01*
X442800Y-627171D01*
X442900Y-628105D01*
X442800Y-628905D01*
X442400Y-629705D01*
X441800Y-630371D01*
X441100Y-630638D01*
X440300Y-630371D01*
X439600Y-629572D01*
X439200Y-628371D01*
X439100Y-627038D01*
X439300Y-625305D01*
X439600Y-624371D01*
X440100Y-623438D01*
X440800Y-622771D01*
X441500Y-622638D01*
X442200Y-622905D01*
X442700Y-623571D01*
G01X462000Y-630638D02*
Y-622638D01*
X460800Y-624238D01*
G01Y-630638D02*
X463200D01*
G01X469800D02*
X470000Y-628905D01*
X470300Y-627438D01*
X470700Y-626105D01*
X471200Y-624638D01*
X472000Y-622638D01*
X468000D01*
G01X478000Y-630905D02*
X477800Y-630771D01*
Y-630505D01*
X478000Y-630371D01*
X478200Y-630505D01*
Y-630771D01*
X478000Y-630905D01*
G01X484100Y-623971D02*
X484700Y-623171D01*
X485400Y-622771D01*
X486200Y-622638D01*
X487200Y-622905D01*
X487900Y-623571D01*
X488100Y-624371D01*
X488000Y-625172D01*
X487600Y-625838D01*
X485600Y-627171D01*
X484700Y-628105D01*
X484100Y-629438D01*
X483900Y-630638D01*
X488100D01*
G01X486200Y-598305D02*
X485600Y-597905D01*
X484900Y-597638D01*
X484100D01*
X483200Y-598038D01*
X482500Y-598705D01*
X482000Y-599505D01*
X481600Y-600838D01*
X481500Y-602038D01*
X481700Y-603238D01*
X482000Y-604038D01*
X482600Y-604838D01*
X483300Y-605371D01*
X484000Y-605638D01*
X484700D01*
X485400Y-605371D01*
X486000Y-604971D01*
X486500Y-604438D01*
M02*
